(lib_symbols
	(symbol "BAT54-02V-G3-08_1"
			(pin_numbers
				(hide yes)
			)
			(pin_names
				(hide yes)
			)
			(exclude_from_sim no)
			(in_bom yes)
			(on_board yes)
			(property "Reference" "D"
				(at 21.59 -5.08 0)
				(effects
					(font
						(size 1.27 1.27)
						(thickness 0.15)
					)
					(justify left bottom)
				)
			)
			(property "Value" "BAT54-02V-G3-08"
				(at 21.59 -15.24 0)
				(effects
					(font
						(size 1.27 1.27)
						(thickness 0.15)
					)
					(justify left bottom)
					(hide yes)
				)
			)
			(property "Footprint" "antmicro-footprints:SOD-523"
				(at 21.59 -10.16 0)
				(effects
					(font
						(size 1.27 1.27)
						(thickness 0.15)
					)
					(justify left bottom)
					(hide yes)
				)
			)
			(property "Datasheet" "https://www.vishay.com/docs/85633/bat5402v.pdf"
				(at 21.59 -12.7 0)
				(effects
					(font
						(size 1.27 1.27)
						(thickness 0.15)
					)
					(justify left bottom)
					(hide yes)
				)
			)
			(property "Description" "Small Signal Schottky Diode, Single, 30 V, 200 mA, 800 mV, 600 mA, 125 °C"
				(at 21.59 -25.4 0)
				(effects
					(font
						(size 1.27 1.27)
					)
					(justify left bottom)
					(hide yes)
				)
			)
			(property "MPN" "BAT54-02V-G3-08"
				(at 21.59 -7.62 0)
				(effects
					(font
						(size 1.27 1.27)
						(thickness 0.15)
					)
					(justify left bottom)
				)
			)
			(property "Manufacturer" "Vishay"
				(at 21.59 -17.78 0)
				(effects
					(font
						(size 1.27 1.27)
						(thickness 0.15)
					)
					(justify left bottom)
					(hide yes)
				)
			)
			(property "Author" "Antmicro"
				(at 21.59 -20.32 0)
				(effects
					(font
						(size 1.27 1.27)
						(thickness 0.15)
					)
					(justify left bottom)
					(hide yes)
				)
			)
			(property "License" "Apache-2.0"
				(at 21.59 -22.86 0)
				(effects
					(font
						(size 1.27 1.27)
						(thickness 0.15)
					)
					(justify left bottom)
					(hide yes)
				)
			)
			(property "ki_keywords" "SMT, SEMICONDUCTOR, DIODE, SCHOTTKY"
				(at 0 0 0)
				(effects
					(font
						(size 1.27 1.27)
					)
					(hide yes)
				)
			)
			(symbol "BAT54-02V-G3-08_1_0_1"
				(polyline
					(pts
						(xy 1.905 0) (xy 0.635 0)
					)
					(stroke
						(width 0)
						(type default)
					)
					(fill
						(type none)
					)
				)
				(polyline
					(pts
						(xy 4.445 0) (xy 3.175 0)
					)
					(stroke
						(width 0)
						(type default)
					)
					(fill
						(type none)
					)
				)
			)
			(symbol "BAT54-02V-G3-08_1_1_1"
				(polyline
					(pts
						(xy 1.778 1.016) (xy 1.778 -1.016)
					)
					(stroke
						(width 0.254)
						(type default)
					)
					(fill
						(type none)
					)
				)
				(polyline
					(pts
						(xy 1.778 1.016) (xy 1.397 1.016) (xy 1.397 0.762)
					)
					(stroke
						(width 0.254)
						(type default)
					)
					(fill
						(type none)
					)
				)
				(polyline
					(pts
						(xy 1.778 -1.016) (xy 2.159 -1.016) (xy 2.159 -0.762)
					)
					(stroke
						(width 0.254)
						(type default)
					)
					(fill
						(type none)
					)
				)
				(polyline
					(pts
						(xy 3.302 1.016) (xy 3.302 -1.016) (xy 1.778 0) (xy 3.302 1.016)
					)
					(stroke
						(width 0.254)
						(type default)
					)
					(fill
						(type outline)
					)
				)
				(pin passive line
					(at 0 0 0)
					(length 0.635)
					(name "C"
						(effects
							(font
								(size 1.27 1.27)
							)
						)
					)
					(number "1"
						(effects
							(font
								(size 1.27 1.27)
							)
						)
					)
				)
				(pin passive line
					(at 5.08 0 180)
					(length 0.635)
					(name "A"
						(effects
							(font
								(size 1.27 1.27)
							)
						)
					)
					(number "2"
						(effects
							(font
								(size 1.27 1.27)
							)
						)
					)
				)
			)
		)
	(symbol "R_1M8_0402_1"
			(pin_numbers
				(hide yes)
			)
			(pin_names
				(hide yes)
			)
			(exclude_from_sim no)
			(in_bom yes)
			(on_board yes)
			(property "Reference" "R"
				(at 20.32 -5.08 0)
				(effects
					(font
						(size 1.27 1.27)
						(thickness 0.15)
					)
					(justify left bottom)
				)
			)
			(property "Value" "R_1M8_0402"
				(at 20.32 -12.7 0)
				(effects
					(font
						(size 1.27 1.27)
						(thickness 0.15)
					)
					(justify left bottom)
					(hide yes)
				)
			)
			(property "Footprint" "antmicro-footprints:R_0402_1005Metric"
				(at 20.32 -15.24 0)
				(effects
					(font
						(size 1.27 1.27)
						(thickness 0.15)
					)
					(justify left bottom)
					(hide yes)
				)
			)
			(property "Datasheet" "https://www.mouser.com/catalog/specsheets/YAGEO_PYu_RC_Group_51_RoHS_L_12.pdf"
				(at 20.32 -17.78 0)
				(effects
					(font
						(size 1.27 1.27)
						(thickness 0.15)
					)
					(justify left bottom)
					(hide yes)
				)
			)
			(property "Description" "SMD Chip Resistor"
				(at 20.32 -30.48 0)
				(effects
					(font
						(size 1.27 1.27)
					)
					(justify left bottom)
					(hide yes)
				)
			)
			(property "MPN" "RC0402FR-071M8L"
				(at 20.32 -20.32 0)
				(effects
					(font
						(size 1.27 1.27)
						(thickness 0.15)
					)
					(justify left bottom)
					(hide yes)
				)
			)
			(property "Manufacturer" "YAGEO"
				(at 20.32 -22.86 0)
				(effects
					(font
						(size 1.27 1.27)
						(thickness 0.15)
					)
					(justify left bottom)
					(hide yes)
				)
			)
			(property "License" "Apache-2.0"
				(at 20.32 -25.4 0)
				(effects
					(font
						(size 1.27 1.27)
						(thickness 0.15)
					)
					(justify left bottom)
					(hide yes)
				)
			)
			(property "Author" "Antmicro"
				(at 20.32 -27.94 0)
				(effects
					(font
						(size 1.27 1.27)
						(thickness 0.15)
					)
					(justify left bottom)
					(hide yes)
				)
			)
			(property "Val" "1M8"
				(at 20.32 -7.62 0)
				(effects
					(font
						(size 1.27 1.27)
						(thickness 0.15)
					)
					(justify left bottom)
				)
			)
			(property "Tolerance" "1%"
				(at 20.32 -10.16 0)
				(effects
					(font
						(size 1.27 1.27)
					)
					(justify left bottom)
					(hide yes)
				)
			)
			(property "ki_keywords" "0402, SMT, RESISTOR, PASSIVE"
				(at 0 0 0)
				(effects
					(font
						(size 1.27 1.27)
					)
					(hide yes)
				)
			)
			(symbol "R_1M8_0402_1_0_1"
				(rectangle
					(start 0.635 0.889)
					(end 4.445 -0.889)
					(stroke
						(width 0.254)
						(type default)
					)
					(fill
						(type none)
					)
				)
			)
			(symbol "R_1M8_0402_1_1_1"
				(pin passive line
					(at 0 0 0)
					(length 0.635)
					(name "~"
						(effects
							(font
								(size 1.27 1.27)
							)
						)
					)
					(number "1"
						(effects
							(font
								(size 1.27 1.27)
							)
						)
					)
				)
				(pin passive line
					(at 5.08 0 180)
					(length 0.635)
					(name "~"
						(effects
							(font
								(size 1.27 1.27)
							)
						)
					)
					(number "2"
						(effects
							(font
								(size 1.27 1.27)
							)
						)
					)
				)
			)
		)
	(symbol "R_80R6_0402_EIA_1"
			(pin_numbers
				(hide yes)
			)
			(pin_names
				(hide yes)
			)
			(exclude_from_sim no)
			(in_bom yes)
			(on_board yes)
			(property "Reference" "R"
				(at 20.32 -5.08 0)
				(effects
					(font
						(size 1.27 1.27)
						(thickness 0.15)
					)
					(justify left bottom)
				)
			)
			(property "Value" "R_80R6_0402_EIA_1"
				(at 20.32 -12.7 0)
				(effects
					(font
						(size 1.27 1.27)
						(thickness 0.15)
					)
					(justify left bottom)
					(hide yes)
				)
			)
			(property "Footprint" "antmicro-footprints:R_0402_1005Metric_EIA"
				(at 20.32 -15.24 0)
				(effects
					(font
						(size 1.27 1.27)
						(thickness 0.15)
					)
					(justify left bottom)
					(hide yes)
				)
			)
			(property "Datasheet" "https://www.bourns.com/docs/product-datasheets/cr.pdf"
				(at 20.32 -17.78 0)
				(effects
					(font
						(size 1.27 1.27)
						(thickness 0.15)
					)
					(justify left bottom)
					(hide yes)
				)
			)
			(property "Description" "SMD Chip Resistor, 80.6 ohm, ± 1%, 62.5 mW, 0402 [1005 Metric], Thick Film, General Purpose"
				(at 0 0 0)
				(effects
					(font
						(size 1.27 1.27)
					)
					(hide yes)
				)
			)
			(property "MPN" "MC00625W0402180R6"
				(at 20.32 -20.32 0)
				(effects
					(font
						(size 1.27 1.27)
						(thickness 0.15)
					)
					(justify left bottom)
					(hide yes)
				)
			)
			(property "Manufacturer" "Multicomp Pro"
				(at 20.32 -22.86 0)
				(effects
					(font
						(size 1.27 1.27)
						(thickness 0.15)
					)
					(justify left bottom)
					(hide yes)
				)
			)
			(property "License" "Apache-2.0"
				(at 20.32 -25.4 0)
				(effects
					(font
						(size 1.27 1.27)
						(thickness 0.15)
					)
					(justify left bottom)
					(hide yes)
				)
			)
			(property "Author" "Antmicro"
				(at 20.32 -27.94 0)
				(effects
					(font
						(size 1.27 1.27)
						(thickness 0.15)
					)
					(justify left bottom)
					(hide yes)
				)
			)
			(property "Val" "80R6"
				(at 20.32 -7.62 0)
				(effects
					(font
						(size 1.27 1.27)
						(thickness 0.15)
					)
					(justify left bottom)
				)
			)
			(property "Tolerance" "1%"
				(at 20.32 -10.16 0)
				(effects
					(font
						(size 1.27 1.27)
					)
					(justify left bottom)
					(hide yes)
				)
			)
			(property "ki_keywords" "0402, SMT, RESISTOR, PASSIVE"
				(at 0 0 0)
				(effects
					(font
						(size 1.27 1.27)
					)
					(hide yes)
				)
			)
			(symbol "R_80R6_0402_EIA_1_0_1"
				(rectangle
					(start 0.635 0.889)
					(end 4.445 -0.889)
					(stroke
						(width 0.254)
						(type default)
					)
					(fill
						(type none)
					)
				)
			)
			(symbol "R_80R6_0402_EIA_1_1_1"
				(pin passive line
					(at 0 0 0)
					(length 0.635)
					(name "~"
						(effects
							(font
								(size 1.27 1.27)
							)
						)
					)
					(number "1"
						(effects
							(font
								(size 1.27 1.27)
							)
						)
					)
				)
				(pin passive line
					(at 5.08 0 180)
					(length 0.635)
					(name "~"
						(effects
							(font
								(size 1.27 1.27)
							)
						)
					)
					(number "2"
						(effects
							(font
								(size 1.27 1.27)
							)
						)
					)
				)
			)
		)
	(symbol "antmicroBarrelPowerConnectors:BarrelJack_Pin2mm_PJ-002AH"
			(exclude_from_sim no)
			(in_bom yes)
			(on_board yes)
			(property "Reference" "J"
				(at 15.24 -5.08 0)
				(effects
					(font
						(size 1.27 1.27)
						(thickness 0.15)
					)
					(justify left bottom)
				)
			)
			(property "Value" "BarrelJack_Pin2mm_PJ-002AH"
				(at 15.24 -10.16 0)
				(effects
					(font
						(size 1.27 1.27)
						(thickness 0.15)
					)
					(justify left bottom)
					(hide yes)
				)
			)
			(property "Footprint" "antmicro-footprints:BarrelJack_Pin2mm_PJ-002AH"
				(at 15.24 -12.7 0)
				(effects
					(font
						(size 1.27 1.27)
						(thickness 0.15)
					)
					(justify left bottom)
					(hide yes)
				)
			)
			(property "Datasheet" "https://www.cuidevices.com/product/resource/pj-002ah.pdf"
				(at 15.24 -15.24 0)
				(effects
					(font
						(size 1.27 1.27)
						(thickness 0.15)
					)
					(justify left bottom)
					(hide yes)
				)
			)
			(property "Description" "Barrel power connector"
				(at 15.24 -25.4 0)
				(effects
					(font
						(size 1.27 1.27)
					)
					(justify left bottom)
					(hide yes)
				)
			)
			(property "MPN" "PJ-002AH"
				(at 15.24 -7.62 0)
				(effects
					(font
						(size 1.27 1.27)
						(thickness 0.15)
					)
					(justify left bottom)
				)
			)
			(property "Manufacturer" "CUI Inc"
				(at 15.24 -17.78 0)
				(effects
					(font
						(size 1.27 1.27)
						(thickness 0.15)
					)
					(justify left bottom)
					(hide yes)
				)
			)
			(property "Author" "Antmicro"
				(at 15.24 -20.32 0)
				(effects
					(font
						(size 1.27 1.27)
						(thickness 0.15)
					)
					(justify left bottom)
					(hide yes)
				)
			)
			(property "License" "Apache-2.0"
				(at 15.24 -22.86 0)
				(effects
					(font
						(size 1.27 1.27)
						(thickness 0.15)
					)
					(justify left bottom)
					(hide yes)
				)
			)
			(property "ki_keywords" "CONNECTOR"
				(at 0 0 0)
				(effects
					(font
						(size 1.27 1.27)
					)
					(hide yes)
				)
			)
			(symbol "BarrelJack_Pin2mm_PJ-002AH_1_1"
				(rectangle
					(start -12.7 1.905)
					(end -2.54 -6.985)
					(stroke
						(width 0.254)
						(type default)
					)
					(fill
						(type background)
					)
				)
				(rectangle
					(start -8.255 0.635)
					(end -4.445 -0.635)
					(stroke
						(width 0.254)
						(type default)
					)
					(fill
						(type outline)
					)
				)
				(arc
					(start -8.255 -0.635)
					(mid -8.8873 0)
					(end -8.255 0.635)
					(stroke
						(width 0.254)
						(type default)
					)
					(fill
						(type outline)
					)
				)
				(polyline
					(pts
						(xy -6.35 -2.54) (xy -6.985 -2.54) (xy -6.35 -3.81) (xy -5.715 -2.54) (xy -6.35 -2.54)
					)
					(stroke
						(width 0.254)
						(type default)
					)
					(fill
						(type none)
					)
				)
				(rectangle
					(start -4.445 1.27)
					(end -3.81 -1.27)
					(stroke
						(width 0.254)
						(type default)
					)
					(fill
						(type none)
					)
				)
				(polyline
					(pts
						(xy -2.54 0) (xy -3.81 0)
					)
					(stroke
						(width 0.254)
						(type default)
					)
					(fill
						(type background)
					)
				)
				(polyline
					(pts
						(xy -2.54 -2.54) (xy -5.715 -2.54)
					)
					(stroke
						(width 0.254)
						(type default)
					)
					(fill
						(type background)
					)
				)
				(polyline
					(pts
						(xy -2.54 -5.08) (xy -7.62 -5.08) (xy -8.89 -3.81) (xy -10.16 -5.08)
					)
					(stroke
						(width 0.254)
						(type default)
					)
					(fill
						(type none)
					)
				)
				(pin passive line
					(at 0 0 180)
					(length 2.54)
					(name "~"
						(effects
							(font
								(size 1.27 1.27)
							)
						)
					)
					(number "1"
						(effects
							(font
								(size 1.27 1.27)
							)
						)
					)
				)
				(pin passive line
					(at 0 -2.54 180)
					(length 2.54)
					(name "~"
						(effects
							(font
								(size 1.27 1.27)
							)
						)
					)
					(number "3"
						(effects
							(font
								(size 1.27 1.27)
							)
						)
					)
				)
				(pin passive line
					(at 0 -5.08 180)
					(length 2.54)
					(name "~"
						(effects
							(font
								(size 1.27 1.27)
							)
						)
					)
					(number "2"
						(effects
							(font
								(size 1.27 1.27)
							)
						)
					)
				)
			)
		)
	(symbol "antmicroCapacitors0402:C_100n_0402"
			(pin_numbers
				(hide yes)
			)
			(pin_names
				(hide yes)
			)
			(exclude_from_sim no)
			(in_bom yes)
			(on_board yes)
			(property "Reference" "C"
				(at 20.32 -5.08 0)
				(effects
					(font
						(size 1.27 1.27)
						(thickness 0.15)
					)
					(justify left bottom)
				)
			)
			(property "Value" "C_100n_0402"
				(at 20.32 -10.16 0)
				(effects
					(font
						(size 1.27 1.27)
						(thickness 0.15)
					)
					(justify left bottom)
					(hide yes)
				)
			)
			(property "Footprint" "antmicro-footprints:C_0402_1005Metric"
				(at 20.32 -12.7 0)
				(effects
					(font
						(size 1.27 1.27)
						(thickness 0.15)
					)
					(justify left bottom)
					(hide yes)
				)
			)
			(property "Datasheet" "https://www.murata.com/products/productdetail?partno=GRM155R61H104KE14%23"
				(at 20.32 -15.24 0)
				(effects
					(font
						(size 1.27 1.27)
						(thickness 0.15)
					)
					(justify left bottom)
					(hide yes)
				)
			)
			(property "Description" "SMD Multilayer Ceramic Capacitor, 0.1 µF, 50 V, 0402 [1005 Metric], ± 10%, X5R, GRM Series"
				(at 0 0 0)
				(effects
					(font
						(size 1.27 1.27)
					)
					(hide yes)
				)
			)
			(property "MPN" "GRM155R61H104KE14D"
				(at 20.32 -17.78 0)
				(effects
					(font
						(size 1.27 1.27)
						(thickness 0.15)
					)
					(justify left bottom)
					(hide yes)
				)
			)
			(property "Manufacturer" "Murata"
				(at 20.32 -20.32 0)
				(effects
					(font
						(size 1.27 1.27)
						(thickness 0.15)
					)
					(justify left bottom)
					(hide yes)
				)
			)
			(property "License" "Apache-2.0"
				(at 20.32 -22.86 0)
				(effects
					(font
						(size 1.27 1.27)
						(thickness 0.15)
					)
					(justify left bottom)
					(hide yes)
				)
			)
			(property "Author" "Antmicro"
				(at 20.32 -25.4 0)
				(effects
					(font
						(size 1.27 1.27)
						(thickness 0.15)
					)
					(justify left bottom)
					(hide yes)
				)
			)
			(property "Val" "100n"
				(at 20.32 -7.62 0)
				(effects
					(font
						(size 1.27 1.27)
						(thickness 0.15)
					)
					(justify left bottom)
				)
			)
			(property "Voltage" "50V"
				(at 20.32 -27.94 0)
				(effects
					(font
						(size 1.27 1.27)
					)
					(justify left bottom)
					(hide yes)
				)
			)
			(property "Dielectric" "X5R"
				(at 20.32 -30.48 0)
				(effects
					(font
						(size 1.27 1.27)
					)
					(justify left bottom)
					(hide yes)
				)
			)
			(symbol "C_100n_0402_0_1"
				(polyline
					(pts
						(xy 2.032 -1.524) (xy 2.032 1.524)
					)
					(stroke
						(width 0.3048)
						(type default)
					)
					(fill
						(type none)
					)
				)
				(polyline
					(pts
						(xy 3.048 -1.524) (xy 3.048 1.524)
					)
					(stroke
						(width 0.3302)
						(type default)
					)
					(fill
						(type none)
					)
				)
			)
			(symbol "C_100n_0402_1_1"
				(pin passive line
					(at 0 0 0)
					(length 2.032)
					(name "~"
						(effects
							(font
								(size 1.27 1.27)
							)
						)
					)
					(number "1"
						(effects
							(font
								(size 1.27 1.27)
							)
						)
					)
				)
				(pin passive line
					(at 5.08 0 180)
					(length 2.032)
					(name "~"
						(effects
							(font
								(size 1.27 1.27)
							)
						)
					)
					(number "2"
						(effects
							(font
								(size 1.27 1.27)
							)
						)
					)
				)
			)
		)
	(symbol "antmicroCapacitors0402:C_10n_0402"
			(pin_numbers
				(hide yes)
			)
			(pin_names
				(hide yes)
			)
			(exclude_from_sim no)
			(in_bom yes)
			(on_board yes)
			(property "Reference" "C"
				(at 20.32 -5.08 0)
				(effects
					(font
						(size 1.27 1.27)
						(thickness 0.15)
					)
					(justify left bottom)
				)
			)
			(property "Value" "C_10n_0402"
				(at 20.32 -10.16 0)
				(effects
					(font
						(size 1.27 1.27)
						(thickness 0.15)
					)
					(justify left bottom)
					(hide yes)
				)
			)
			(property "Footprint" "antmicro-footprints:C_0402_1005Metric"
				(at 20.32 -12.7 0)
				(effects
					(font
						(size 1.27 1.27)
						(thickness 0.15)
					)
					(justify left bottom)
					(hide yes)
				)
			)
			(property "Datasheet" "https://www.murata.com/products/productdetail?partno=GRM155R71H103KA88%23"
				(at 20.32 -15.24 0)
				(effects
					(font
						(size 1.27 1.27)
						(thickness 0.15)
					)
					(justify left bottom)
					(hide yes)
				)
			)
			(property "Description" "SMD Multilayer Ceramic Capacitor, 10000 pF, 50 V, 0402 [1005 Metric], ± 10%, X7R, GRM Series"
				(at 0 0 0)
				(effects
					(font
						(size 1.27 1.27)
					)
					(hide yes)
				)
			)
			(property "MPN" "GRM155R71H103KA88D"
				(at 20.32 -17.78 0)
				(effects
					(font
						(size 1.27 1.27)
						(thickness 0.15)
					)
					(justify left bottom)
					(hide yes)
				)
			)
			(property "Manufacturer" "Murata"
				(at 20.32 -20.32 0)
				(effects
					(font
						(size 1.27 1.27)
						(thickness 0.15)
					)
					(justify left bottom)
					(hide yes)
				)
			)
			(property "License" "Apache-2.0"
				(at 20.32 -22.86 0)
				(effects
					(font
						(size 1.27 1.27)
						(thickness 0.15)
					)
					(justify left bottom)
					(hide yes)
				)
			)
			(property "Author" "Antmicro"
				(at 20.32 -25.4 0)
				(effects
					(font
						(size 1.27 1.27)
						(thickness 0.15)
					)
					(justify left bottom)
					(hide yes)
				)
			)
			(property "Val" "10n"
				(at 20.32 -7.62 0)
				(effects
					(font
						(size 1.27 1.27)
						(thickness 0.15)
					)
					(justify left bottom)
				)
			)
			(property "Voltage" "50V"
				(at 20.32 -27.94 0)
				(effects
					(font
						(size 1.27 1.27)
					)
					(justify left bottom)
					(hide yes)
				)
			)
			(property "Dielectric" "X7R"
				(at 20.32 -30.48 0)
				(effects
					(font
						(size 1.27 1.27)
					)
					(justify left bottom)
					(hide yes)
				)
			)
			(property "ki_keywords" "0402, SMT, CAPACITOR, PASSIVE"
				(at 0 0 0)
				(effects
					(font
						(size 1.27 1.27)
					)
					(hide yes)
				)
			)
			(symbol "C_10n_0402_0_1"
				(polyline
					(pts
						(xy 2.032 -1.524) (xy 2.032 1.524)
					)
					(stroke
						(width 0.3048)
						(type default)
					)
					(fill
						(type none)
					)
				)
				(polyline
					(pts
						(xy 3.048 -1.524) (xy 3.048 1.524)
					)
					(stroke
						(width 0.3302)
						(type default)
					)
					(fill
						(type none)
					)
				)
			)
			(symbol "C_10n_0402_1_1"
				(pin passive line
					(at 0 0 0)
					(length 2.032)
					(name "~"
						(effects
							(font
								(size 1.27 1.27)
							)
						)
					)
					(number "1"
						(effects
							(font
								(size 1.27 1.27)
							)
						)
					)
				)
				(pin passive line
					(at 5.08 0 180)
					(length 2.032)
					(name "~"
						(effects
							(font
								(size 1.27 1.27)
							)
						)
					)
					(number "2"
						(effects
							(font
								(size 1.27 1.27)
							)
						)
					)
				)
			)
		)
	(symbol "antmicroCapacitors0402:C_10u_6.3V_0402"
			(pin_numbers
				(hide yes)
			)
			(pin_names
				(hide yes)
			)
			(exclude_from_sim no)
			(in_bom yes)
			(on_board yes)
			(property "Reference" "C"
				(at 20.32 -5.08 0)
				(effects
					(font
						(size 1.27 1.27)
						(thickness 0.15)
					)
					(justify left bottom)
				)
			)
			(property "Value" "C_10u_6.3V_0402"
				(at 20.32 -10.16 0)
				(effects
					(font
						(size 1.27 1.27)
						(thickness 0.15)
					)
					(justify left bottom)
					(hide yes)
				)
			)
			(property "Footprint" "antmicro-footprints:C_0402_1005Metric"
				(at 20.32 -12.7 0)
				(effects
					(font
						(size 1.27 1.27)
						(thickness 0.15)
					)
					(justify left bottom)
					(hide yes)
				)
			)
			(property "Datasheet" "https://www.murata.com/products/productdetail?partno=GRM155R60J106ME15%23"
				(at 20.32 -15.24 0)
				(effects
					(font
						(size 1.27 1.27)
						(thickness 0.15)
					)
					(justify left bottom)
					(hide yes)
				)
			)
			(property "Description" "SMD Multilayer Ceramic Capacitor, 10 µF, 6.3 V, 0402 [1005 Metric], ± 20%, X5R, GRM Series"
				(at 0 0 0)
				(effects
					(font
						(size 1.27 1.27)
					)
					(hide yes)
				)
			)
			(property "MPN" "GRM155R60J106ME15D"
				(at 20.32 -17.78 0)
				(effects
					(font
						(size 1.27 1.27)
						(thickness 0.15)
					)
					(justify left bottom)
					(hide yes)
				)
			)
			(property "Manufacturer" "Murata"
				(at 20.32 -20.32 0)
				(effects
					(font
						(size 1.27 1.27)
						(thickness 0.15)
					)
					(justify left bottom)
					(hide yes)
				)
			)
			(property "License" "Apache-2.0"
				(at 20.32 -22.86 0)
				(effects
					(font
						(size 1.27 1.27)
						(thickness 0.15)
					)
					(justify left bottom)
					(hide yes)
				)
			)
			(property "Author" "Antmicro"
				(at 20.32 -25.4 0)
				(effects
					(font
						(size 1.27 1.27)
						(thickness 0.15)
					)
					(justify left bottom)
					(hide yes)
				)
			)
			(property "Val" "10u"
				(at 20.32 -7.62 0)
				(effects
					(font
						(size 1.27 1.27)
						(thickness 0.15)
					)
					(justify left bottom)
				)
			)
			(property "Voltage" "6.3V"
				(at 20.32 -27.94 0)
				(effects
					(font
						(size 1.27 1.27)
					)
					(justify left bottom)
					(hide yes)
				)
			)
			(property "Dielectric" "X5R"
				(at 20.32 -30.48 0)
				(effects
					(font
						(size 1.27 1.27)
					)
					(justify left bottom)
					(hide yes)
				)
			)
			(property "ki_keywords" "0402, SMT, CAPACITOR, PASSIVE, CERAMIC"
				(at 0 0 0)
				(effects
					(font
						(size 1.27 1.27)
					)
					(hide yes)
				)
			)
			(symbol "C_10u_6.3V_0402_0_1"
				(polyline
					(pts
						(xy 2.032 -1.524) (xy 2.032 1.524)
					)
					(stroke
						(width 0.3048)
						(type default)
					)
					(fill
						(type none)
					)
				)
				(polyline
					(pts
						(xy 3.048 -1.524) (xy 3.048 1.524)
					)
					(stroke
						(width 0.3302)
						(type default)
					)
					(fill
						(type none)
					)
				)
			)
			(symbol "C_10u_6.3V_0402_1_1"
				(pin passive line
					(at 0 0 0)
					(length 2.032)
					(name "~"
						(effects
							(font
								(size 1.27 1.27)
							)
						)
					)
					(number "1"
						(effects
							(font
								(size 1.27 1.27)
							)
						)
					)
				)
				(pin passive line
					(at 5.08 0 180)
					(length 2.032)
					(name "~"
						(effects
							(font
								(size 1.27 1.27)
							)
						)
					)
					(number "2"
						(effects
							(font
								(size 1.27 1.27)
							)
						)
					)
				)
			)
		)
	(symbol "antmicroCapacitors0402:C_18p_0402"
			(pin_numbers
				(hide yes)
			)
			(pin_names
				(hide yes)
			)
			(exclude_from_sim no)
			(in_bom yes)
			(on_board yes)
			(property "Reference" "C"
				(at 20.32 -5.08 0)
				(effects
					(font
						(size 1.27 1.27)
						(thickness 0.15)
					)
					(justify left bottom)
				)
			)
			(property "Value" "C_18p_0402"
				(at 20.32 -10.16 0)
				(effects
					(font
						(size 1.27 1.27)
						(thickness 0.15)
					)
					(justify left bottom)
					(hide yes)
				)
			)
			(property "Footprint" "antmicro-footprints:C_0402_1005Metric"
				(at 20.32 -12.7 0)
				(effects
					(font
						(size 1.27 1.27)
						(thickness 0.15)
					)
					(justify left bottom)
					(hide yes)
				)
			)
			(property "Datasheet" "https://product.samsungsem.com/mlcc/CL05C180JB51PN.do"
				(at 20.32 -15.24 0)
				(effects
					(font
						(size 1.27 1.27)
						(thickness 0.15)
					)
					(justify left bottom)
					(hide yes)
				)
			)
			(property "Description" "SMD Multilayer Ceramic Capacitor, 18 pF, 50 V, 0402 [1005 Metric], ± 5%, C0G / NP0, MC"
				(at 0 0 0)
				(effects
					(font
						(size 1.27 1.27)
					)
					(hide yes)
				)
			)
			(property "MPN" "CL05C180JB51PNC"
				(at 20.32 -17.78 0)
				(effects
					(font
						(size 1.27 1.27)
						(thickness 0.15)
					)
					(justify left bottom)
					(hide yes)
				)
			)
			(property "Manufacturer" "Samsung Electro-Mechanics"
				(at 20.32 -20.32 0)
				(effects
					(font
						(size 1.27 1.27)
						(thickness 0.15)
					)
					(justify left bottom)
					(hide yes)
				)
			)
			(property "License" "Apache-2.0"
				(at 20.32 -22.86 0)
				(effects
					(font
						(size 1.27 1.27)
						(thickness 0.15)
					)
					(justify left bottom)
					(hide yes)
				)
			)
			(property "Author" "Antmicro"
				(at 20.32 -25.4 0)
				(effects
					(font
						(size 1.27 1.27)
						(thickness 0.15)
					)
					(justify left bottom)
					(hide yes)
				)
			)
			(property "Val" "18p"
				(at 20.32 -7.62 0)
				(effects
					(font
						(size 1.27 1.27)
						(thickness 0.15)
					)
					(justify left bottom)
				)
			)
			(property "Voltage" ""
				(at 20.32 -27.94 0)
				(effects
					(font
						(size 1.27 1.27)
					)
					(justify left bottom)
					(hide yes)
				)
			)
			(property "Dielectric" ""
				(at 20.32 -30.48 0)
				(effects
					(font
						(size 1.27 1.27)
					)
					(justify left bottom)
					(hide yes)
				)
			)
			(property "ki_keywords" "0402, SMT, CAPACITOR, PASSIVE"
				(at 0 0 0)
				(effects
					(font
						(size 1.27 1.27)
					)
					(hide yes)
				)
			)
			(symbol "C_18p_0402_0_1"
				(polyline
					(pts
						(xy 2.032 -1.524) (xy 2.032 1.524)
					)
					(stroke
						(width 0.3048)
						(type default)
					)
					(fill
						(type none)
					)
				)
				(polyline
					(pts
						(xy 3.048 -1.524) (xy 3.048 1.524)
					)
					(stroke
						(width 0.3302)
						(type default)
					)
					(fill
						(type none)
					)
				)
			)
			(symbol "C_18p_0402_1_1"
				(pin passive line
					(at 0 0 0)
					(length 2.032)
					(name "~"
						(effects
							(font
								(size 1.27 1.27)
							)
						)
					)
					(number "1"
						(effects
							(font
								(size 1.27 1.27)
							)
						)
					)
				)
				(pin passive line
					(at 5.08 0 180)
					(length 2.032)
					(name "~"
						(effects
							(font
								(size 1.27 1.27)
							)
						)
					)
					(number "2"
						(effects
							(font
								(size 1.27 1.27)
							)
						)
					)
				)
			)
		)
	(symbol "antmicroCapacitors0402:C_1u_0402"
			(pin_numbers
				(hide yes)
			)
			(pin_names
				(hide yes)
			)
			(exclude_from_sim no)
			(in_bom yes)
			(on_board yes)
			(property "Reference" "C"
				(at 20.32 -5.08 0)
				(effects
					(font
						(size 1.27 1.27)
						(thickness 0.15)
					)
					(justify left bottom)
				)
			)
			(property "Value" "C_1u_0402"
				(at 20.32 -10.16 0)
				(effects
					(font
						(size 1.27 1.27)
						(thickness 0.15)
					)
					(justify left bottom)
					(hide yes)
				)
			)
			(property "Footprint" "antmicro-footprints:C_0402_1005Metric"
				(at 20.32 -12.7 0)
				(effects
					(font
						(size 1.27 1.27)
						(thickness 0.15)
					)
					(justify left bottom)
					(hide yes)
				)
			)
			(property "Datasheet" "https://product.tdk.com/en/search/capacitor/ceramic/mlcc/info?part_no=C1005X6S1A105K050BC"
				(at 20.32 -15.24 0)
				(effects
					(font
						(size 1.27 1.27)
						(thickness 0.15)
					)
					(justify left bottom)
					(hide yes)
				)
			)
			(property "Description" "SMD Multilayer Ceramic Capacitor, 1 µF, 10 V, 0402 [1005 Metric], ± 10%, X6S, C"
				(at 0 0 0)
				(effects
					(font
						(size 1.27 1.27)
					)
					(hide yes)
				)
			)
			(property "MPN" "C1005X6S1A105K050BC"
				(at 20.32 -17.78 0)
				(effects
					(font
						(size 1.27 1.27)
						(thickness 0.15)
					)
					(justify left bottom)
					(hide yes)
				)
			)
			(property "Manufacturer" "TDK"
				(at 20.32 -20.32 0)
				(effects
					(font
						(size 1.27 1.27)
						(thickness 0.15)
					)
					(justify left bottom)
					(hide yes)
				)
			)
			(property "License" "Apache-2.0"
				(at 20.32 -22.86 0)
				(effects
					(font
						(size 1.27 1.27)
						(thickness 0.15)
					)
					(justify left bottom)
					(hide yes)
				)
			)
			(property "Author" "Antmicro"
				(at 20.32 -25.4 0)
				(effects
					(font
						(size 1.27 1.27)
						(thickness 0.15)
					)
					(justify left bottom)
					(hide yes)
				)
			)
			(property "Val" "1u"
				(at 20.32 -7.62 0)
				(effects
					(font
						(size 1.27 1.27)
						(thickness 0.15)
					)
					(justify left bottom)
				)
			)
			(property "Voltage" ""
				(at 20.32 -27.94 0)
				(effects
					(font
						(size 1.27 1.27)
					)
					(justify left bottom)
					(hide yes)
				)
			)
			(property "Dielectric" ""
				(at 20.32 -30.48 0)
				(effects
					(font
						(size 1.27 1.27)
					)
					(justify left bottom)
					(hide yes)
				)
			)
			(property "ki_keywords" "0402, SMT, CAPACITOR, PASSIVE, CERAMIC, MLCC"
				(at 0 0 0)
				(effects
					(font
						(size 1.27 1.27)
					)
					(hide yes)
				)
			)
			(symbol "C_1u_0402_0_1"
				(polyline
					(pts
						(xy 2.032 -1.524) (xy 2.032 1.524)
					)
					(stroke
						(width 0.3048)
						(type default)
					)
					(fill
						(type none)
					)
				)
				(polyline
					(pts
						(xy 3.048 -1.524) (xy 3.048 1.524)
					)
					(stroke
						(width 0.3302)
						(type default)
					)
					(fill
						(type none)
					)
				)
			)
			(symbol "C_1u_0402_1_1"
				(pin passive line
					(at 0 0 0)
					(length 2.032)
					(name "~"
						(effects
							(font
								(size 1.27 1.27)
							)
						)
					)
					(number "1"
						(effects
							(font
								(size 1.27 1.27)
							)
						)
					)
				)
				(pin passive line
					(at 5.08 0 180)
					(length 2.032)
					(name "~"
						(effects
							(font
								(size 1.27 1.27)
							)
						)
					)
					(number "2"
						(effects
							(font
								(size 1.27 1.27)
							)
						)
					)
				)
			)
		)
	(symbol "antmicroCapacitors0402:C_22n_0402"
			(pin_numbers
				(hide yes)
			)
			(pin_names
				(hide yes)
			)
			(exclude_from_sim no)
			(in_bom yes)
			(on_board yes)
			(property "Reference" "C"
				(at 20.32 -5.08 0)
				(effects
					(font
						(size 1.27 1.27)
						(thickness 0.15)
					)
					(justify left bottom)
				)
			)
			(property "Value" "C_22n_0402"
				(at 20.32 -10.16 0)
				(effects
					(font
						(size 1.27 1.27)
						(thickness 0.15)
					)
					(justify left bottom)
					(hide yes)
				)
			)
			(property "Footprint" "antmicro-footprints:C_0402_1005Metric"
				(at 20.32 -12.7 0)
				(effects
					(font
						(size 1.27 1.27)
						(thickness 0.15)
					)
					(justify left bottom)
					(hide yes)
				)
			)
			(property "Datasheet" "https://www.murata.com/products/productdetail?partno=GCM155R71H223MA55%23"
				(at 20.32 -15.24 0)
				(effects
					(font
						(size 1.27 1.27)
						(thickness 0.15)
					)
					(justify left bottom)
					(hide yes)
				)
			)
			(property "Description" "SMD Multilayer Ceramic Capacitors, 0.022 µF, 50 V, 20%, 0402 [1005 Metric], X7R"
				(at 0 0 0)
				(effects
					(font
						(size 1.27 1.27)
					)
					(hide yes)
				)
			)
			(property "MPN" "GCM155R71H223MA55D"
				(at 20.32 -17.78 0)
				(effects
					(font
						(size 1.27 1.27)
						(thickness 0.15)
					)
					(justify left bottom)
					(hide yes)
				)
			)
			(property "Manufacturer" "Murata"
				(at 20.32 -20.32 0)
				(effects
					(font
						(size 1.27 1.27)
						(thickness 0.15)
					)
					(justify left bottom)
					(hide yes)
				)
			)
			(property "License" "Apache-2.0"
				(at 20.32 -22.86 0)
				(effects
					(font
						(size 1.27 1.27)
						(thickness 0.15)
					)
					(justify left bottom)
					(hide yes)
				)
			)
			(property "Author" "Antmicro"
				(at 20.32 -25.4 0)
				(effects
					(font
						(size 1.27 1.27)
						(thickness 0.15)
					)
					(justify left bottom)
					(hide yes)
				)
			)
			(property "Val" "22n"
				(at 20.32 -7.62 0)
				(effects
					(font
						(size 1.27 1.27)
						(thickness 0.15)
					)
					(justify left bottom)
				)
			)
			(property "Voltage" ""
				(at 20.32 -27.94 0)
				(effects
					(font
						(size 1.27 1.27)
					)
					(justify left bottom)
					(hide yes)
				)
			)
			(property "Dielectric" ""
				(at 20.32 -30.48 0)
				(effects
					(font
						(size 1.27 1.27)
					)
					(justify left bottom)
					(hide yes)
				)
			)
			(property "ki_keywords" "0402, SMT, CAPACITOR, PASSIVE, CERAMIC, MLCC"
				(at 0 0 0)
				(effects
					(font
						(size 1.27 1.27)
					)
					(hide yes)
				)
			)
			(symbol "C_22n_0402_0_1"
				(polyline
					(pts
						(xy 2.032 -1.524) (xy 2.032 1.524)
					)
					(stroke
						(width 0.3048)
						(type default)
					)
					(fill
						(type none)
					)
				)
				(polyline
					(pts
						(xy 3.048 -1.524) (xy 3.048 1.524)
					)
					(stroke
						(width 0.3302)
						(type default)
					)
					(fill
						(type none)
					)
				)
			)
			(symbol "C_22n_0402_1_1"
				(pin passive line
					(at 0 0 0)
					(length 2.032)
					(name "~"
						(effects
							(font
								(size 1.27 1.27)
							)
						)
					)
					(number "1"
						(effects
							(font
								(size 1.27 1.27)
							)
						)
					)
				)
				(pin passive line
					(at 5.08 0 180)
					(length 2.032)
					(name "~"
						(effects
							(font
								(size 1.27 1.27)
							)
						)
					)
					(number "2"
						(effects
							(font
								(size 1.27 1.27)
							)
						)
					)
				)
			)
		)
	(symbol "antmicroCapacitors0402:C_22p_0402"
			(pin_numbers
				(hide yes)
			)
			(pin_names
				(hide yes)
			)
			(exclude_from_sim no)
			(in_bom yes)
			(on_board yes)
			(property "Reference" "C"
				(at 20.32 -5.08 0)
				(effects
					(font
						(size 1.27 1.27)
						(thickness 0.15)
					)
					(justify left bottom)
				)
			)
			(property "Value" "C_22p_0402"
				(at 20.32 -10.16 0)
				(effects
					(font
						(size 1.27 1.27)
						(thickness 0.15)
					)
					(justify left bottom)
					(hide yes)
				)
			)
			(property "Footprint" "antmicro-footprints:C_0402_1005Metric"
				(at 20.32 -12.7 0)
				(effects
					(font
						(size 1.27 1.27)
						(thickness 0.15)
					)
					(justify left bottom)
					(hide yes)
				)
			)
			(property "Datasheet" "https://www.yageo.com/en/Chart/Download/pdf/CC0402JRNPO9BN220"
				(at 20.32 -15.24 0)
				(effects
					(font
						(size 1.27 1.27)
						(thickness 0.15)
					)
					(justify left bottom)
					(hide yes)
				)
			)
			(property "Description" "SMD Multilayer Ceramic Capacitor, 22 pF, 50 V, 0402 [1005 Metric], ± 5%, C0G / NP0, CC Series"
				(at 0 0 0)
				(effects
					(font
						(size 1.27 1.27)
					)
					(hide yes)
				)
			)
			(property "MPN" "CC0402JRNPO9BN220"
				(at 20.32 -17.78 0)
				(effects
					(font
						(size 1.27 1.27)
						(thickness 0.15)
					)
					(justify left bottom)
					(hide yes)
				)
			)
			(property "Manufacturer" "YAGEO"
				(at 20.32 -20.32 0)
				(effects
					(font
						(size 1.27 1.27)
						(thickness 0.15)
					)
					(justify left bottom)
					(hide yes)
				)
			)
			(property "License" "Apache-2.0"
				(at 20.32 -22.86 0)
				(effects
					(font
						(size 1.27 1.27)
						(thickness 0.15)
					)
					(justify left bottom)
					(hide yes)
				)
			)
			(property "Author" "Antmicro"
				(at 20.32 -25.4 0)
				(effects
					(font
						(size 1.27 1.27)
						(thickness 0.15)
					)
					(justify left bottom)
					(hide yes)
				)
			)
			(property "Val" "22p"
				(at 20.32 -7.62 0)
				(effects
					(font
						(size 1.27 1.27)
						(thickness 0.15)
					)
					(justify left bottom)
				)
			)
			(property "Voltage" ""
				(at 20.32 -27.94 0)
				(effects
					(font
						(size 1.27 1.27)
					)
					(justify left bottom)
					(hide yes)
				)
			)
			(property "Dielectric" ""
				(at 20.32 -30.48 0)
				(effects
					(font
						(size 1.27 1.27)
					)
					(justify left bottom)
					(hide yes)
				)
			)
			(property "ki_keywords" "0402, SMT, CAPACITOR, PASSIVE, MLCC, CERAMIC"
				(at 0 0 0)
				(effects
					(font
						(size 1.27 1.27)
					)
					(hide yes)
				)
			)
			(symbol "C_22p_0402_0_1"
				(polyline
					(pts
						(xy 2.032 -1.524) (xy 2.032 1.524)
					)
					(stroke
						(width 0.3048)
						(type default)
					)
					(fill
						(type none)
					)
				)
				(polyline
					(pts
						(xy 3.048 -1.524) (xy 3.048 1.524)
					)
					(stroke
						(width 0.3302)
						(type default)
					)
					(fill
						(type none)
					)
				)
			)
			(symbol "C_22p_0402_1_1"
				(pin passive line
					(at 0 0 0)
					(length 2.032)
					(name "~"
						(effects
							(font
								(size 1.27 1.27)
							)
						)
					)
					(number "1"
						(effects
							(font
								(size 1.27 1.27)
							)
						)
					)
				)
				(pin passive line
					(at 5.08 0 180)
					(length 2.032)
					(name "~"
						(effects
							(font
								(size 1.27 1.27)
							)
						)
					)
					(number "2"
						(effects
							(font
								(size 1.27 1.27)
							)
						)
					)
				)
			)
		)
	(symbol "antmicroCapacitors0402:C_470n_0402"
			(pin_numbers
				(hide yes)
			)
			(pin_names
				(hide yes)
			)
			(exclude_from_sim no)
			(in_bom yes)
			(on_board yes)
			(property "Reference" "C"
				(at 20.32 -5.08 0)
				(effects
					(font
						(size 1.27 1.27)
						(thickness 0.15)
					)
					(justify left bottom)
				)
			)
			(property "Value" "C_470n_0402"
				(at 20.32 -10.16 0)
				(effects
					(font
						(size 1.27 1.27)
						(thickness 0.15)
					)
					(justify left bottom)
					(hide yes)
				)
			)
			(property "Footprint" "antmicro-footprints:C_0402_1005Metric"
				(at 20.32 -12.7 0)
				(effects
					(font
						(size 1.27 1.27)
						(thickness 0.15)
					)
					(justify left bottom)
					(hide yes)
				)
			)
			(property "Datasheet" "https://product.tdk.com/en/search/capacitor/ceramic/mlcc/info?part_no=C1005X5R1E474M050BB"
				(at 20.32 -15.24 0)
				(effects
					(font
						(size 1.27 1.27)
						(thickness 0.15)
					)
					(justify left bottom)
					(hide yes)
				)
			)
			(property "Description" "SMD Multilayer Ceramic Capacitor, 0.47 µF, 25 V, 0402 [1005 Metric], ± 20%, X5R, C"
				(at 0 0 0)
				(effects
					(font
						(size 1.27 1.27)
					)
					(hide yes)
				)
			)
			(property "MPN" "C1005X5R1E474M050BB"
				(at 20.32 -17.78 0)
				(effects
					(font
						(size 1.27 1.27)
						(thickness 0.15)
					)
					(justify left bottom)
					(hide yes)
				)
			)
			(property "Manufacturer" "TDK"
				(at 20.32 -20.32 0)
				(effects
					(font
						(size 1.27 1.27)
						(thickness 0.15)
					)
					(justify left bottom)
					(hide yes)
				)
			)
			(property "License" "Apache-2.0"
				(at 20.32 -22.86 0)
				(effects
					(font
						(size 1.27 1.27)
						(thickness 0.15)
					)
					(justify left bottom)
					(hide yes)
				)
			)
			(property "Author" "Antmicro"
				(at 20.32 -25.4 0)
				(effects
					(font
						(size 1.27 1.27)
						(thickness 0.15)
					)
					(justify left bottom)
					(hide yes)
				)
			)
			(property "Val" "470n"
				(at 20.32 -7.62 0)
				(effects
					(font
						(size 1.27 1.27)
						(thickness 0.15)
					)
					(justify left bottom)
				)
			)
			(property "Voltage" ""
				(at 20.32 -27.94 0)
				(effects
					(font
						(size 1.27 1.27)
					)
					(justify left bottom)
					(hide yes)
				)
			)
			(property "Dielectric" ""
				(at 20.32 -30.48 0)
				(effects
					(font
						(size 1.27 1.27)
					)
					(justify left bottom)
					(hide yes)
				)
			)
			(property "ki_keywords" "0402, SMT, CAPACITOR, PASSIVE, CERAMIC, MLCC"
				(at 0 0 0)
				(effects
					(font
						(size 1.27 1.27)
					)
					(hide yes)
				)
			)
			(symbol "C_470n_0402_0_1"
				(polyline
					(pts
						(xy 2.032 -1.524) (xy 2.032 1.524)
					)
					(stroke
						(width 0.3048)
						(type default)
					)
					(fill
						(type none)
					)
				)
				(polyline
					(pts
						(xy 3.048 -1.524) (xy 3.048 1.524)
					)
					(stroke
						(width 0.3302)
						(type default)
					)
					(fill
						(type none)
					)
				)
			)
			(symbol "C_470n_0402_1_1"
				(pin passive line
					(at 0 0 0)
					(length 2.032)
					(name "~"
						(effects
							(font
								(size 1.27 1.27)
							)
						)
					)
					(number "1"
						(effects
							(font
								(size 1.27 1.27)
							)
						)
					)
				)
				(pin passive line
					(at 5.08 0 180)
					(length 2.032)
					(name "~"
						(effects
							(font
								(size 1.27 1.27)
							)
						)
					)
					(number "2"
						(effects
							(font
								(size 1.27 1.27)
							)
						)
					)
				)
			)
		)
	(symbol "antmicroCapacitors0402:C_4u7_0402"
			(pin_numbers
				(hide yes)
			)
			(pin_names
				(hide yes)
			)
			(exclude_from_sim no)
			(in_bom yes)
			(on_board yes)
			(property "Reference" "C"
				(at 20.32 -5.08 0)
				(effects
					(font
						(size 1.27 1.27)
						(thickness 0.15)
					)
					(justify left bottom)
				)
			)
			(property "Value" "C_4u7_0402"
				(at 20.32 -10.16 0)
				(effects
					(font
						(size 1.27 1.27)
						(thickness 0.15)
					)
					(justify left bottom)
					(hide yes)
				)
			)
			(property "Footprint" "antmicro-footprints:C_0402_1005Metric"
				(at 20.32 -12.7 0)
				(effects
					(font
						(size 1.27 1.27)
						(thickness 0.15)
					)
					(justify left bottom)
					(hide yes)
				)
			)
			(property "Datasheet" "https://www.murata.com/products/productdetail?partno=GRM155R61A475MEAA%23"
				(at 20.32 -15.24 0)
				(effects
					(font
						(size 1.27 1.27)
						(thickness 0.15)
					)
					(justify left bottom)
					(hide yes)
				)
			)
			(property "Description" "SMD Multilayer Ceramic Capacitor, 4.7 µF, 10 V, 0402 [1005 Metric], ± 20%, X5R, GRM Series"
				(at 0 0 0)
				(effects
					(font
						(size 1.27 1.27)
					)
					(hide yes)
				)
			)
			(property "MPN" "GRM155R61A475MEAAD"
				(at 20.32 -17.78 0)
				(effects
					(font
						(size 1.27 1.27)
						(thickness 0.15)
					)
					(justify left bottom)
					(hide yes)
				)
			)
			(property "Manufacturer" "Murata"
				(at 20.32 -20.32 0)
				(effects
					(font
						(size 1.27 1.27)
						(thickness 0.15)
					)
					(justify left bottom)
					(hide yes)
				)
			)
			(property "License" "Apache-2.0"
				(at 20.32 -22.86 0)
				(effects
					(font
						(size 1.27 1.27)
						(thickness 0.15)
					)
					(justify left bottom)
					(hide yes)
				)
			)
			(property "Author" "Antmicro"
				(at 20.32 -25.4 0)
				(effects
					(font
						(size 1.27 1.27)
						(thickness 0.15)
					)
					(justify left bottom)
					(hide yes)
				)
			)
			(property "Val" "4u7"
				(at 20.32 -7.62 0)
				(effects
					(font
						(size 1.27 1.27)
						(thickness 0.15)
					)
					(justify left bottom)
				)
			)
			(property "Voltage" ""
				(at 20.32 -27.94 0)
				(effects
					(font
						(size 1.27 1.27)
					)
					(justify left bottom)
					(hide yes)
				)
			)
			(property "Dielectric" ""
				(at 20.32 -30.48 0)
				(effects
					(font
						(size 1.27 1.27)
					)
					(justify left bottom)
					(hide yes)
				)
			)
			(property "ki_keywords" "0402, SMT, CAPACITOR, PASSIVE"
				(at 0 0 0)
				(effects
					(font
						(size 1.27 1.27)
					)
					(hide yes)
				)
			)
			(symbol "C_4u7_0402_0_1"
				(polyline
					(pts
						(xy 2.032 -1.524) (xy 2.032 1.524)
					)
					(stroke
						(width 0.3048)
						(type default)
					)
					(fill
						(type none)
					)
				)
				(polyline
					(pts
						(xy 3.048 -1.524) (xy 3.048 1.524)
					)
					(stroke
						(width 0.3302)
						(type default)
					)
					(fill
						(type none)
					)
				)
			)
			(symbol "C_4u7_0402_1_1"
				(pin passive line
					(at 0 0 0)
					(length 2.032)
					(name "~"
						(effects
							(font
								(size 1.27 1.27)
							)
						)
					)
					(number "1"
						(effects
							(font
								(size 1.27 1.27)
							)
						)
					)
				)
				(pin passive line
					(at 5.08 0 180)
					(length 2.032)
					(name "~"
						(effects
							(font
								(size 1.27 1.27)
							)
						)
					)
					(number "2"
						(effects
							(font
								(size 1.27 1.27)
							)
						)
					)
				)
			)
		)
	(symbol "antmicroCapacitors0603:C_10u_25V_0603"
			(pin_numbers
				(hide yes)
			)
			(pin_names
				(hide yes)
			)
			(exclude_from_sim no)
			(in_bom yes)
			(on_board yes)
			(property "Reference" "C"
				(at 20.32 -5.08 0)
				(effects
					(font
						(size 1.27 1.27)
						(thickness 0.15)
					)
					(justify left bottom)
				)
			)
			(property "Value" "C_10u_25V_0603"
				(at 20.32 -10.16 0)
				(effects
					(font
						(size 1.27 1.27)
						(thickness 0.15)
					)
					(justify left bottom)
					(hide yes)
				)
			)
			(property "Footprint" "antmicro-footprints:C_0603_1608Metric"
				(at 20.32 -12.7 0)
				(effects
					(font
						(size 1.27 1.27)
						(thickness 0.15)
					)
					(justify left bottom)
					(hide yes)
				)
			)
			(property "Datasheet" "https://product.tdk.com/en/search/capacitor/ceramic/mlcc/info?part_no=C1608X5R1E106M080AC"
				(at 20.32 -15.24 0)
				(effects
					(font
						(size 1.27 1.27)
						(thickness 0.15)
					)
					(justify left bottom)
					(hide yes)
				)
			)
			(property "Description" "SMD Multilayer Ceramic Capacitor, 10 µF, 25 V, 0603 [1608 Metric], ± 20%, X5R, C"
				(at 0 0 0)
				(effects
					(font
						(size 1.27 1.27)
					)
					(hide yes)
				)
			)
			(property "MPN" "C1608X5R1E106M080AC"
				(at 20.32 -17.78 0)
				(effects
					(font
						(size 1.27 1.27)
						(thickness 0.15)
					)
					(justify left bottom)
					(hide yes)
				)
			)
			(property "Manufacturer" "TDK"
				(at 20.32 -20.32 0)
				(effects
					(font
						(size 1.27 1.27)
						(thickness 0.15)
					)
					(justify left bottom)
					(hide yes)
				)
			)
			(property "License" "Apache-2.0"
				(at 20.32 -22.86 0)
				(effects
					(font
						(size 1.27 1.27)
						(thickness 0.15)
					)
					(justify left bottom)
					(hide yes)
				)
			)
			(property "Author" "Antmicro"
				(at 20.32 -25.4 0)
				(effects
					(font
						(size 1.27 1.27)
						(thickness 0.15)
					)
					(justify left bottom)
					(hide yes)
				)
			)
			(property "Val" "10u/25V"
				(at 20.32 -7.62 0)
				(effects
					(font
						(size 1.27 1.27)
						(thickness 0.15)
					)
					(justify left bottom)
				)
			)
			(property "Voltage" ""
				(at 20.32 -27.94 0)
				(effects
					(font
						(size 1.27 1.27)
					)
					(justify left bottom)
					(hide yes)
				)
			)
			(property "Dielectric" ""
				(at 20.32 -30.48 0)
				(effects
					(font
						(size 1.27 1.27)
					)
					(justify left bottom)
					(hide yes)
				)
			)
			(property "ki_keywords" "0603, SMT, CAPACITOR, PASSIVE, CERAMIC, MLCC"
				(at 0 0 0)
				(effects
					(font
						(size 1.27 1.27)
					)
					(hide yes)
				)
			)
			(symbol "C_10u_25V_0603_0_1"
				(polyline
					(pts
						(xy 2.032 -1.524) (xy 2.032 1.524)
					)
					(stroke
						(width 0.3048)
						(type default)
					)
					(fill
						(type none)
					)
				)
				(polyline
					(pts
						(xy 3.048 -1.524) (xy 3.048 1.524)
					)
					(stroke
						(width 0.3302)
						(type default)
					)
					(fill
						(type none)
					)
				)
			)
			(symbol "C_10u_25V_0603_1_1"
				(pin passive line
					(at 0 0 0)
					(length 2.032)
					(name "~"
						(effects
							(font
								(size 1.27 1.27)
							)
						)
					)
					(number "1"
						(effects
							(font
								(size 1.27 1.27)
							)
						)
					)
				)
				(pin passive line
					(at 5.08 0 180)
					(length 2.032)
					(name "~"
						(effects
							(font
								(size 1.27 1.27)
							)
						)
					)
					(number "2"
						(effects
							(font
								(size 1.27 1.27)
							)
						)
					)
				)
			)
		)
	(symbol "antmicroCapacitors0603:C_1u_25V_0603"
			(pin_numbers
				(hide yes)
			)
			(pin_names
				(hide yes)
			)
			(exclude_from_sim no)
			(in_bom yes)
			(on_board yes)
			(property "Reference" "C"
				(at 20.32 -5.08 0)
				(effects
					(font
						(size 1.27 1.27)
						(thickness 0.15)
					)
					(justify left bottom)
				)
			)
			(property "Value" "C_1u_25V_0603"
				(at 20.32 -10.16 0)
				(effects
					(font
						(size 1.27 1.27)
						(thickness 0.15)
					)
					(justify left bottom)
					(hide yes)
				)
			)
			(property "Footprint" "antmicro-footprints:C_0603_1608Metric"
				(at 20.32 -12.7 0)
				(effects
					(font
						(size 1.27 1.27)
						(thickness 0.15)
					)
					(justify left bottom)
					(hide yes)
				)
			)
			(property "Datasheet" "https://product.samsungsem.com/mlcc/CL10A105KA8NNN.do"
				(at 20.32 -15.24 0)
				(effects
					(font
						(size 1.27 1.27)
						(thickness 0.15)
					)
					(justify left bottom)
					(hide yes)
				)
			)
			(property "Description" "SMD Multilayer Ceramic Capacitor, 1 µF, 25 V, 0603 [1608 Metric], ± 10%, X5R, CL"
				(at 0 0 0)
				(effects
					(font
						(size 1.27 1.27)
					)
					(hide yes)
				)
			)
			(property "MPN" "CL10A105KA8NNNC"
				(at 20.32 -17.78 0)
				(effects
					(font
						(size 1.27 1.27)
						(thickness 0.15)
					)
					(justify left bottom)
					(hide yes)
				)
			)
			(property "Manufacturer" "Samsung Electro-Mechanics"
				(at 20.32 -20.32 0)
				(effects
					(font
						(size 1.27 1.27)
						(thickness 0.15)
					)
					(justify left bottom)
					(hide yes)
				)
			)
			(property "License" "Apache-2.0"
				(at 20.32 -22.86 0)
				(effects
					(font
						(size 1.27 1.27)
						(thickness 0.15)
					)
					(justify left bottom)
					(hide yes)
				)
			)
			(property "Author" "Antmicro"
				(at 20.32 -25.4 0)
				(effects
					(font
						(size 1.27 1.27)
						(thickness 0.15)
					)
					(justify left bottom)
					(hide yes)
				)
			)
			(property "Val" "1u/25V"
				(at 20.32 -7.62 0)
				(effects
					(font
						(size 1.27 1.27)
						(thickness 0.15)
					)
					(justify left bottom)
				)
			)
			(property "Voltage" ""
				(at 20.32 -27.94 0)
				(effects
					(font
						(size 1.27 1.27)
					)
					(justify left bottom)
					(hide yes)
				)
			)
			(property "Dielectric" ""
				(at 20.32 -30.48 0)
				(effects
					(font
						(size 1.27 1.27)
					)
					(justify left bottom)
					(hide yes)
				)
			)
			(property "ki_keywords" "0603, SMT, CAPACITOR, PASSIVE, CERAMIC"
				(at 0 0 0)
				(effects
					(font
						(size 1.27 1.27)
					)
					(hide yes)
				)
			)
			(symbol "C_1u_25V_0603_0_1"
				(polyline
					(pts
						(xy 2.032 -1.524) (xy 2.032 1.524)
					)
					(stroke
						(width 0.3048)
						(type default)
					)
					(fill
						(type none)
					)
				)
				(polyline
					(pts
						(xy 3.048 -1.524) (xy 3.048 1.524)
					)
					(stroke
						(width 0.3302)
						(type default)
					)
					(fill
						(type none)
					)
				)
			)
			(symbol "C_1u_25V_0603_1_1"
				(pin passive line
					(at 0 0 0)
					(length 2.032)
					(name "~"
						(effects
							(font
								(size 1.27 1.27)
							)
						)
					)
					(number "1"
						(effects
							(font
								(size 1.27 1.27)
							)
						)
					)
				)
				(pin passive line
					(at 5.08 0 180)
					(length 2.032)
					(name "~"
						(effects
							(font
								(size 1.27 1.27)
							)
						)
					)
					(number "2"
						(effects
							(font
								(size 1.27 1.27)
							)
						)
					)
				)
			)
		)
	(symbol "antmicroCapacitors0603:C_22u_0603"
			(pin_numbers
				(hide yes)
			)
			(pin_names
				(hide yes)
			)
			(exclude_from_sim no)
			(in_bom yes)
			(on_board yes)
			(property "Reference" "C"
				(at 20.32 -5.08 0)
				(effects
					(font
						(size 1.27 1.27)
						(thickness 0.15)
					)
					(justify left bottom)
				)
			)
			(property "Value" "C_22u_0603"
				(at 20.32 -10.16 0)
				(effects
					(font
						(size 1.27 1.27)
						(thickness 0.15)
					)
					(justify left bottom)
					(hide yes)
				)
			)
			(property "Footprint" "antmicro-footprints:C_0603_1608Metric"
				(at 20.32 -12.7 0)
				(effects
					(font
						(size 1.27 1.27)
						(thickness 0.15)
					)
					(justify left bottom)
					(hide yes)
				)
			)
			(property "Datasheet" "https://www.murata.com/products/productdetail?partno=GRM188R60J226MEA0%23"
				(at 20.32 -15.24 0)
				(effects
					(font
						(size 1.27 1.27)
						(thickness 0.15)
					)
					(justify left bottom)
					(hide yes)
				)
			)
			(property "Description" "SMD Multilayer Ceramic Capacitor, 22 µF, 6.3 V, 0603 [1608 Metric], ± 20%, X5R, GRM Series"
				(at 0 0 0)
				(effects
					(font
						(size 1.27 1.27)
					)
					(hide yes)
				)
			)
			(property "MPN" "GRM188R60J226MEA0D"
				(at 20.32 -17.78 0)
				(effects
					(font
						(size 1.27 1.27)
						(thickness 0.15)
					)
					(justify left bottom)
					(hide yes)
				)
			)
			(property "Manufacturer" "Murata"
				(at 20.32 -20.32 0)
				(effects
					(font
						(size 1.27 1.27)
						(thickness 0.15)
					)
					(justify left bottom)
					(hide yes)
				)
			)
			(property "License" "Apache-2.0"
				(at 20.32 -22.86 0)
				(effects
					(font
						(size 1.27 1.27)
						(thickness 0.15)
					)
					(justify left bottom)
					(hide yes)
				)
			)
			(property "Author" "Antmicro"
				(at 20.32 -25.4 0)
				(effects
					(font
						(size 1.27 1.27)
						(thickness 0.15)
					)
					(justify left bottom)
					(hide yes)
				)
			)
			(property "Val" "22u"
				(at 20.32 -7.62 0)
				(effects
					(font
						(size 1.27 1.27)
						(thickness 0.15)
					)
					(justify left bottom)
				)
			)
			(property "Voltage" ""
				(at 20.32 -27.94 0)
				(effects
					(font
						(size 1.27 1.27)
					)
					(justify left bottom)
					(hide yes)
				)
			)
			(property "Dielectric" ""
				(at 20.32 -30.48 0)
				(effects
					(font
						(size 1.27 1.27)
					)
					(justify left bottom)
					(hide yes)
				)
			)
			(property "ki_keywords" "0603, SMT, CAPACITOR, PASSIVE, CERAMIC, MLCC"
				(at 0 0 0)
				(effects
					(font
						(size 1.27 1.27)
					)
					(hide yes)
				)
			)
			(symbol "C_22u_0603_0_1"
				(polyline
					(pts
						(xy 2.032 -1.524) (xy 2.032 1.524)
					)
					(stroke
						(width 0.3048)
						(type default)
					)
					(fill
						(type none)
					)
				)
				(polyline
					(pts
						(xy 3.048 -1.524) (xy 3.048 1.524)
					)
					(stroke
						(width 0.3302)
						(type default)
					)
					(fill
						(type none)
					)
				)
			)
			(symbol "C_22u_0603_1_1"
				(pin passive line
					(at 0 0 0)
					(length 2.032)
					(name "~"
						(effects
							(font
								(size 1.27 1.27)
							)
						)
					)
					(number "1"
						(effects
							(font
								(size 1.27 1.27)
							)
						)
					)
				)
				(pin passive line
					(at 5.08 0 180)
					(length 2.032)
					(name "~"
						(effects
							(font
								(size 1.27 1.27)
							)
						)
					)
					(number "2"
						(effects
							(font
								(size 1.27 1.27)
							)
						)
					)
				)
			)
		)
	(symbol "antmicroCapacitors0603:C_47u_0603"
			(pin_numbers
				(hide yes)
			)
			(pin_names
				(hide yes)
			)
			(exclude_from_sim no)
			(in_bom yes)
			(on_board yes)
			(property "Reference" "C"
				(at 20.32 -5.08 0)
				(effects
					(font
						(size 1.27 1.27)
						(thickness 0.15)
					)
					(justify left bottom)
				)
			)
			(property "Value" "C_47u_0603"
				(at 20.32 -10.16 0)
				(effects
					(font
						(size 1.27 1.27)
						(thickness 0.15)
					)
					(justify left bottom)
					(hide yes)
				)
			)
			(property "Footprint" "antmicro-footprints:C_0603_1608Metric"
				(at 20.32 -12.7 0)
				(effects
					(font
						(size 1.27 1.27)
						(thickness 0.15)
					)
					(justify left bottom)
					(hide yes)
				)
			)
			(property "Datasheet" "https://www.murata.com/products/productdetail?partno=GRM188R60J476ME15%23"
				(at 20.32 -15.24 0)
				(effects
					(font
						(size 1.27 1.27)
						(thickness 0.15)
					)
					(justify left bottom)
					(hide yes)
				)
			)
			(property "Description" "SMD Multilayer Ceramic Capacitor, 47 µF, 6.3 V, 0603 [1608 Metric], ± 20%, X5R, GRM Series"
				(at 0 0 0)
				(effects
					(font
						(size 1.27 1.27)
					)
					(hide yes)
				)
			)
			(property "MPN" "GRM188R60J476ME15D"
				(at 20.32 -17.78 0)
				(effects
					(font
						(size 1.27 1.27)
						(thickness 0.15)
					)
					(justify left bottom)
					(hide yes)
				)
			)
			(property "Manufacturer" "Murata"
				(at 20.32 -20.32 0)
				(effects
					(font
						(size 1.27 1.27)
						(thickness 0.15)
					)
					(justify left bottom)
					(hide yes)
				)
			)
			(property "License" "Apache-2.0"
				(at 20.32 -22.86 0)
				(effects
					(font
						(size 1.27 1.27)
						(thickness 0.15)
					)
					(justify left bottom)
					(hide yes)
				)
			)
			(property "Author" "Antmicro"
				(at 20.32 -25.4 0)
				(effects
					(font
						(size 1.27 1.27)
						(thickness 0.15)
					)
					(justify left bottom)
					(hide yes)
				)
			)
			(property "Val" "47u"
				(at 20.32 -7.62 0)
				(effects
					(font
						(size 1.27 1.27)
						(thickness 0.15)
					)
					(justify left bottom)
				)
			)
			(property "Voltage" ""
				(at 20.32 -27.94 0)
				(effects
					(font
						(size 1.27 1.27)
					)
					(justify left bottom)
					(hide yes)
				)
			)
			(property "Dielectric" ""
				(at 20.32 -30.48 0)
				(effects
					(font
						(size 1.27 1.27)
					)
					(justify left bottom)
					(hide yes)
				)
			)
			(symbol "C_47u_0603_0_1"
				(polyline
					(pts
						(xy 2.032 -1.524) (xy 2.032 1.524)
					)
					(stroke
						(width 0.3048)
						(type default)
					)
					(fill
						(type none)
					)
				)
				(polyline
					(pts
						(xy 3.048 -1.524) (xy 3.048 1.524)
					)
					(stroke
						(width 0.3302)
						(type default)
					)
					(fill
						(type none)
					)
				)
			)
			(symbol "C_47u_0603_1_1"
				(pin passive line
					(at 0 0 0)
					(length 2.032)
					(name "~"
						(effects
							(font
								(size 1.27 1.27)
							)
						)
					)
					(number "1"
						(effects
							(font
								(size 1.27 1.27)
							)
						)
					)
				)
				(pin passive line
					(at 5.08 0 180)
					(length 2.032)
					(name "~"
						(effects
							(font
								(size 1.27 1.27)
							)
						)
					)
					(number "2"
						(effects
							(font
								(size 1.27 1.27)
							)
						)
					)
				)
			)
		)
	(symbol "antmicroCapacitorsmisc:C_100n_0201"
			(pin_numbers
				(hide yes)
			)
			(pin_names
				(hide yes)
			)
			(exclude_from_sim no)
			(in_bom yes)
			(on_board yes)
			(property "Reference" "C"
				(at 20.32 -5.08 0)
				(effects
					(font
						(size 1.27 1.27)
						(thickness 0.15)
					)
					(justify left bottom)
				)
			)
			(property "Value" "C_100n_0201"
				(at 20.32 -10.16 0)
				(effects
					(font
						(size 1.27 1.27)
						(thickness 0.15)
					)
					(justify left bottom)
					(hide yes)
				)
			)
			(property "Footprint" "antmicro-footprints:C_0201"
				(at 20.32 -12.7 0)
				(effects
					(font
						(size 1.27 1.27)
						(thickness 0.15)
					)
					(justify left bottom)
					(hide yes)
				)
			)
			(property "Datasheet" "https://www.yageo.com/en/Chart/Download/pdf/CC0201KRX6S5BB104"
				(at 20.32 -15.24 0)
				(effects
					(font
						(size 1.27 1.27)
						(thickness 0.15)
					)
					(justify left bottom)
					(hide yes)
				)
			)
			(property "Description" "SMD Multilayer Ceramic Capacitor, 0.1 µF, 6.3 V, 0201 [0603 Metric], ± 10%, X6S, CC Series"
				(at 0 0 0)
				(effects
					(font
						(size 1.27 1.27)
					)
					(hide yes)
				)
			)
			(property "MPN" "CC0201KRX6S5BB104"
				(at 20.32 -17.78 0)
				(effects
					(font
						(size 1.27 1.27)
						(thickness 0.15)
					)
					(justify left bottom)
					(hide yes)
				)
			)
			(property "Manufacturer" "YAGEO"
				(at 20.32 -20.32 0)
				(effects
					(font
						(size 1.27 1.27)
						(thickness 0.15)
					)
					(justify left bottom)
					(hide yes)
				)
			)
			(property "License" "Apache-2.0"
				(at 20.32 -22.86 0)
				(effects
					(font
						(size 1.27 1.27)
						(thickness 0.15)
					)
					(justify left bottom)
					(hide yes)
				)
			)
			(property "Author" "Antmicro"
				(at 20.32 -25.4 0)
				(effects
					(font
						(size 1.27 1.27)
						(thickness 0.15)
					)
					(justify left bottom)
					(hide yes)
				)
			)
			(property "Val" "100n"
				(at 20.32 -7.62 0)
				(effects
					(font
						(size 1.27 1.27)
						(thickness 0.15)
					)
					(justify left bottom)
				)
			)
			(property "Voltage" ""
				(at 20.32 -27.94 0)
				(effects
					(font
						(size 1.27 1.27)
					)
					(justify left bottom)
					(hide yes)
				)
			)
			(property "Dielectric" ""
				(at 20.32 -30.48 0)
				(effects
					(font
						(size 1.27 1.27)
					)
					(justify left bottom)
					(hide yes)
				)
			)
			(symbol "C_100n_0201_0_1"
				(polyline
					(pts
						(xy 2.032 -1.524) (xy 2.032 1.524)
					)
					(stroke
						(width 0.3048)
						(type default)
					)
					(fill
						(type none)
					)
				)
				(polyline
					(pts
						(xy 3.048 -1.524) (xy 3.048 1.524)
					)
					(stroke
						(width 0.3302)
						(type default)
					)
					(fill
						(type none)
					)
				)
			)
			(symbol "C_100n_0201_1_1"
				(pin passive line
					(at 0 0 0)
					(length 2.032)
					(name "~"
						(effects
							(font
								(size 1.27 1.27)
							)
						)
					)
					(number "1"
						(effects
							(font
								(size 1.27 1.27)
							)
						)
					)
				)
				(pin passive line
					(at 5.08 0 180)
					(length 2.032)
					(name "~"
						(effects
							(font
								(size 1.27 1.27)
							)
						)
					)
					(number "2"
						(effects
							(font
								(size 1.27 1.27)
							)
						)
					)
				)
			)
		)
	(symbol "antmicroCapacitorsmisc:C_100u_0805"
			(pin_numbers
				(hide yes)
			)
			(pin_names
				(hide yes)
			)
			(exclude_from_sim no)
			(in_bom yes)
			(on_board yes)
			(property "Reference" "C"
				(at 20.32 -5.08 0)
				(effects
					(font
						(size 1.27 1.27)
						(thickness 0.15)
					)
					(justify left bottom)
				)
			)
			(property "Value" "C_100u_0805"
				(at 20.32 -10.16 0)
				(effects
					(font
						(size 1.27 1.27)
						(thickness 0.15)
					)
					(justify left bottom)
					(hide yes)
				)
			)
			(property "Footprint" "antmicro-footprints:C_0805_2012Metric"
				(at 20.32 -12.7 0)
				(effects
					(font
						(size 1.27 1.27)
						(thickness 0.15)
					)
					(justify left bottom)
					(hide yes)
				)
			)
			(property "Datasheet" "https://www.murata.com/products/productdetail?partno=GRM21BR60J107ME15%23"
				(at 20.32 -15.24 0)
				(effects
					(font
						(size 1.27 1.27)
						(thickness 0.15)
					)
					(justify left bottom)
					(hide yes)
				)
			)
			(property "Description" "SMD Multilayer Ceramic Capacitor, 100 µF, 6.3 V, 0805 [2012 Metric], ± 20%, X5R, GRM Series"
				(at 0 0 0)
				(effects
					(font
						(size 1.27 1.27)
					)
					(hide yes)
				)
			)
			(property "MPN" "GRM21BR60J107ME15L"
				(at 20.32 -17.78 0)
				(effects
					(font
						(size 1.27 1.27)
						(thickness 0.15)
					)
					(justify left bottom)
					(hide yes)
				)
			)
			(property "Manufacturer" "Murata"
				(at 20.32 -20.32 0)
				(effects
					(font
						(size 1.27 1.27)
						(thickness 0.15)
					)
					(justify left bottom)
					(hide yes)
				)
			)
			(property "License" "Apache-2.0"
				(at 20.32 -22.86 0)
				(effects
					(font
						(size 1.27 1.27)
						(thickness 0.15)
					)
					(justify left bottom)
					(hide yes)
				)
			)
			(property "Author" "Antmicro"
				(at 20.32 -25.4 0)
				(effects
					(font
						(size 1.27 1.27)
						(thickness 0.15)
					)
					(justify left bottom)
					(hide yes)
				)
			)
			(property "Val" "100u"
				(at 20.32 -7.62 0)
				(effects
					(font
						(size 1.27 1.27)
						(thickness 0.15)
					)
					(justify left bottom)
				)
			)
			(property "Voltage" ""
				(at 20.32 -27.94 0)
				(effects
					(font
						(size 1.27 1.27)
					)
					(justify left bottom)
					(hide yes)
				)
			)
			(property "Dielectric" ""
				(at 20.32 -30.48 0)
				(effects
					(font
						(size 1.27 1.27)
					)
					(justify left bottom)
					(hide yes)
				)
			)
			(property "ki_keywords" "0805, SMT, CAPACITOR, PASSIVE"
				(at 0 0 0)
				(effects
					(font
						(size 1.27 1.27)
					)
					(hide yes)
				)
			)
			(symbol "C_100u_0805_0_1"
				(polyline
					(pts
						(xy 2.032 -1.524) (xy 2.032 1.524)
					)
					(stroke
						(width 0.3048)
						(type default)
					)
					(fill
						(type none)
					)
				)
				(polyline
					(pts
						(xy 3.048 -1.524) (xy 3.048 1.524)
					)
					(stroke
						(width 0.3302)
						(type default)
					)
					(fill
						(type none)
					)
				)
			)
			(symbol "C_100u_0805_1_1"
				(pin passive line
					(at 0 0 0)
					(length 2.032)
					(name "~"
						(effects
							(font
								(size 1.27 1.27)
							)
						)
					)
					(number "1"
						(effects
							(font
								(size 1.27 1.27)
							)
						)
					)
				)
				(pin passive line
					(at 5.08 0 180)
					(length 2.032)
					(name "~"
						(effects
							(font
								(size 1.27 1.27)
							)
						)
					)
					(number "2"
						(effects
							(font
								(size 1.27 1.27)
							)
						)
					)
				)
			)
		)
	(symbol "antmicroCapacitorsmisc:C_22u_25V_0805"
			(pin_numbers
				(hide yes)
			)
			(pin_names
				(hide yes)
			)
			(exclude_from_sim no)
			(in_bom yes)
			(on_board yes)
			(property "Reference" "C"
				(at 20.32 -5.08 0)
				(effects
					(font
						(size 1.27 1.27)
						(thickness 0.15)
					)
					(justify left bottom)
				)
			)
			(property "Value" "C_22u_25V_0805"
				(at 20.32 -10.16 0)
				(effects
					(font
						(size 1.27 1.27)
						(thickness 0.15)
					)
					(justify left bottom)
					(hide yes)
				)
			)
			(property "Footprint" "antmicro-footprints:C_0805_2012Metric"
				(at 20.32 -12.7 0)
				(effects
					(font
						(size 1.27 1.27)
						(thickness 0.15)
					)
					(justify left bottom)
					(hide yes)
				)
			)
			(property "Datasheet" "https://product.samsungsem.com/mlcc/CL21A226MAYNNN.do"
				(at 20.32 -15.24 0)
				(effects
					(font
						(size 1.27 1.27)
						(thickness 0.15)
					)
					(justify left bottom)
					(hide yes)
				)
			)
			(property "Description" "SMT Multilayer Ceramic Capacitor, 22uF, +/-20%, 25V, X5R, 0805 [2012 Metric]"
				(at 0 0 0)
				(effects
					(font
						(size 1.27 1.27)
					)
					(hide yes)
				)
			)
			(property "MPN" "CL21A226MAYNNNE"
				(at 20.32 -17.78 0)
				(effects
					(font
						(size 1.27 1.27)
						(thickness 0.15)
					)
					(justify left bottom)
					(hide yes)
				)
			)
			(property "Manufacturer" "Samsung Electro-Mechanics"
				(at 20.32 -20.32 0)
				(effects
					(font
						(size 1.27 1.27)
						(thickness 0.15)
					)
					(justify left bottom)
					(hide yes)
				)
			)
			(property "License" "Apache-2.0"
				(at 20.32 -22.86 0)
				(effects
					(font
						(size 1.27 1.27)
						(thickness 0.15)
					)
					(justify left bottom)
					(hide yes)
				)
			)
			(property "Author" "Antmicro"
				(at 20.32 -25.4 0)
				(effects
					(font
						(size 1.27 1.27)
						(thickness 0.15)
					)
					(justify left bottom)
					(hide yes)
				)
			)
			(property "Val" "22u_25V"
				(at 20.32 -7.62 0)
				(effects
					(font
						(size 1.27 1.27)
						(thickness 0.15)
					)
					(justify left bottom)
				)
			)
			(property "Voltage" ""
				(at 20.32 -27.94 0)
				(effects
					(font
						(size 1.27 1.27)
					)
					(justify left bottom)
					(hide yes)
				)
			)
			(property "Dielectric" ""
				(at 20.32 -30.48 0)
				(effects
					(font
						(size 1.27 1.27)
					)
					(justify left bottom)
					(hide yes)
				)
			)
			(property "ki_keywords" "0805, SMT, CAPACITOR, PASSIVE"
				(at 0 0 0)
				(effects
					(font
						(size 1.27 1.27)
					)
					(hide yes)
				)
			)
			(symbol "C_22u_25V_0805_0_1"
				(polyline
					(pts
						(xy 2.032 -1.524) (xy 2.032 1.524)
					)
					(stroke
						(width 0.3048)
						(type default)
					)
					(fill
						(type none)
					)
				)
				(polyline
					(pts
						(xy 3.048 -1.524) (xy 3.048 1.524)
					)
					(stroke
						(width 0.3302)
						(type default)
					)
					(fill
						(type none)
					)
				)
			)
			(symbol "C_22u_25V_0805_1_1"
				(pin passive line
					(at 0 0 0)
					(length 2.032)
					(name "~"
						(effects
							(font
								(size 1.27 1.27)
							)
						)
					)
					(number "1"
						(effects
							(font
								(size 1.27 1.27)
							)
						)
					)
				)
				(pin passive line
					(at 5.08 0 180)
					(length 2.032)
					(name "~"
						(effects
							(font
								(size 1.27 1.27)
							)
						)
					)
					(number "2"
						(effects
							(font
								(size 1.27 1.27)
							)
						)
					)
				)
			)
		)
	(symbol "antmicroCapacitorspol:C_Pol_1m_2.5V_KEMET-T520-D"
			(pin_numbers
				(hide yes)
			)
			(pin_names
				(hide yes)
			)
			(exclude_from_sim no)
			(in_bom yes)
			(on_board yes)
			(property "Reference" "C"
				(at 13.97 0 0)
				(effects
					(font
						(size 1.27 1.27)
						(thickness 0.15)
					)
					(justify left bottom)
				)
			)
			(property "Value" "C_Pol_1m_2.5V_KEMET-T520-D"
				(at 13.97 -2.54 0)
				(effects
					(font
						(size 1.27 1.27)
						(thickness 0.15)
					)
					(justify left bottom)
					(hide yes)
				)
			)
			(property "Footprint" "antmicro-footprints:C_Pol_EIA-D"
				(at 13.97 -7.62 0)
				(effects
					(font
						(size 1.27 1.27)
						(thickness 0.15)
					)
					(justify left bottom)
					(hide yes)
				)
			)
			(property "Datasheet" "https://content.kemet.com/datasheets/KEM_T2076_T52X-530.pdf"
				(at 13.97 -10.16 0)
				(effects
					(font
						(size 1.27 1.27)
						(thickness 0.15)
					)
					(justify left bottom)
					(hide yes)
				)
			)
			(property "Description" "Tantalum Polymer Capacitor, 1000 µF, ± 20%, 2.5 V, D, 0.03 ohm, 2917 [7343 Metric]"
				(at 0 0 0)
				(effects
					(font
						(size 1.27 1.27)
					)
					(hide yes)
				)
			)
			(property "MPN" "T520D108M2R5ATE030"
				(at 13.97 -12.7 0)
				(effects
					(font
						(size 1.27 1.27)
						(thickness 0.15)
					)
					(justify left bottom)
					(hide yes)
				)
			)
			(property "Manufacturer" "KEMET"
				(at 13.97 -15.24 0)
				(effects
					(font
						(size 1.27 1.27)
						(thickness 0.15)
					)
					(justify left bottom)
					(hide yes)
				)
			)
			(property "License" "Apache-2.0"
				(at 13.97 -17.78 0)
				(effects
					(font
						(size 1.27 1.27)
						(thickness 0.15)
					)
					(justify left bottom)
					(hide yes)
				)
			)
			(property "Author" "Antmicro"
				(at 13.97 -20.32 0)
				(effects
					(font
						(size 1.27 1.27)
						(thickness 0.15)
					)
					(justify left bottom)
					(hide yes)
				)
			)
			(property "Val" "1000u/2.5V"
				(at 13.97 -5.08 0)
				(effects
					(font
						(size 1.27 1.27)
						(thickness 0.15)
					)
					(justify left bottom)
				)
			)
			(property "Voltage" "2.5V"
				(at 13.97 -22.86 0)
				(effects
					(font
						(size 1.27 1.27)
					)
					(justify left bottom)
					(hide yes)
				)
			)
			(property "Dielectric" "template_dielectric"
				(at 13.97 -25.4 0)
				(effects
					(font
						(size 1.27 1.27)
					)
					(justify left bottom)
					(hide yes)
				)
			)
			(property "ki_keywords" "SMT, CAPACITOR, PASSIVE, POLARIZED"
				(at 0 0 0)
				(effects
					(font
						(size 1.27 1.27)
					)
					(hide yes)
				)
			)
			(symbol "C_Pol_1m_2.5V_KEMET-T520-D_0_1"
				(polyline
					(pts
						(xy 0.9652 1.27) (xy 0.9652 1.778)
					)
					(stroke
						(width 0)
						(type default)
					)
					(fill
						(type none)
					)
				)
				(polyline
					(pts
						(xy 1.2192 1.524) (xy 0.7112 1.524)
					)
					(stroke
						(width 0)
						(type default)
					)
					(fill
						(type none)
					)
				)
				(rectangle
					(start 1.905 -1.524)
					(end 2.286 1.524)
					(stroke
						(width 0)
						(type default)
					)
					(fill
						(type none)
					)
				)
				(rectangle
					(start 2.921 -1.524)
					(end 3.302 1.524)
					(stroke
						(width 0)
						(type default)
					)
					(fill
						(type outline)
					)
				)
			)
			(symbol "C_Pol_1m_2.5V_KEMET-T520-D_1_1"
				(pin passive line
					(at 0 0 0)
					(length 1.8542)
					(name "~"
						(effects
							(font
								(size 1.27 1.27)
							)
						)
					)
					(number "1"
						(effects
							(font
								(size 1.27 1.27)
							)
						)
					)
				)
				(pin passive line
					(at 5.08 0 180)
					(length 1.8542)
					(name "~"
						(effects
							(font
								(size 1.27 1.27)
							)
						)
					)
					(number "2"
						(effects
							(font
								(size 1.27 1.27)
							)
						)
					)
				)
			)
		)
	(symbol "antmicroCapacitorspol:C_Pol_330u_6.3V_KEMET-T520-B"
			(pin_numbers
				(hide yes)
			)
			(pin_names
				(hide yes)
			)
			(exclude_from_sim no)
			(in_bom yes)
			(on_board yes)
			(property "Reference" "C"
				(at 13.97 0 0)
				(effects
					(font
						(size 1.27 1.27)
						(thickness 0.15)
					)
					(justify left bottom)
				)
			)
			(property "Value" "C_Pol_330u_6.3V_KEMET-T520-B"
				(at 13.97 -2.54 0)
				(effects
					(font
						(size 1.27 1.27)
						(thickness 0.15)
					)
					(justify left bottom)
					(hide yes)
				)
			)
			(property "Footprint" "antmicro-footprints:C_Pol_EIA-B"
				(at 13.97 -7.62 0)
				(effects
					(font
						(size 1.27 1.27)
						(thickness 0.15)
					)
					(justify left bottom)
					(hide yes)
				)
			)
			(property "Datasheet" "https://content.kemet.com/datasheets/KEM_T2076_T52X-530.pdf"
				(at 13.97 -10.16 0)
				(effects
					(font
						(size 1.27 1.27)
						(thickness 0.15)
					)
					(justify left bottom)
					(hide yes)
				)
			)
			(property "Description" "Tantalum Polymer Capacitor, KO-CAP®, 330 µF, ± 20%, 6.3 V, B, 0.04 ohm, 1411 [3528 Metric]"
				(at 0 0 0)
				(effects
					(font
						(size 1.27 1.27)
					)
					(hide yes)
				)
			)
			(property "Val" "330u/6.3V"
				(at 13.97 -5.08 0)
				(effects
					(font
						(size 1.27 1.27)
						(thickness 0.15)
					)
					(justify left bottom)
				)
			)
			(property "MPN" "T520B337M006ATE040"
				(at 13.97 -12.7 0)
				(effects
					(font
						(size 1.27 1.27)
						(thickness 0.15)
					)
					(justify left bottom)
					(hide yes)
				)
			)
			(property "Manufacturer" "KEMET"
				(at 13.97 -15.24 0)
				(effects
					(font
						(size 1.27 1.27)
						(thickness 0.15)
					)
					(justify left bottom)
					(hide yes)
				)
			)
			(property "License" "Apache-2.0"
				(at 13.97 -17.78 0)
				(effects
					(font
						(size 1.27 1.27)
						(thickness 0.15)
					)
					(justify left bottom)
					(hide yes)
				)
			)
			(property "Author" "Antmicro"
				(at 13.97 -20.32 0)
				(effects
					(font
						(size 1.27 1.27)
						(thickness 0.15)
					)
					(justify left bottom)
					(hide yes)
				)
			)
			(property "Voltage" "6.3V"
				(at 13.97 -22.86 0)
				(effects
					(font
						(size 1.27 1.27)
					)
					(justify left bottom)
					(hide yes)
				)
			)
			(property "Dielectric" "template_dielectric"
				(at 13.97 -25.4 0)
				(effects
					(font
						(size 1.27 1.27)
					)
					(justify left bottom)
					(hide yes)
				)
			)
			(property "ki_keywords" "SMT, CAPACITOR, PASSIVE, POLARIZED, TANTALUM"
				(at 0 0 0)
				(effects
					(font
						(size 1.27 1.27)
					)
					(hide yes)
				)
			)
			(symbol "C_Pol_330u_6.3V_KEMET-T520-B_0_1"
				(polyline
					(pts
						(xy 0.9652 1.27) (xy 0.9652 1.778)
					)
					(stroke
						(width 0)
						(type default)
					)
					(fill
						(type none)
					)
				)
				(polyline
					(pts
						(xy 1.2192 1.524) (xy 0.7112 1.524)
					)
					(stroke
						(width 0)
						(type default)
					)
					(fill
						(type none)
					)
				)
				(rectangle
					(start 1.905 -1.524)
					(end 2.286 1.524)
					(stroke
						(width 0)
						(type default)
					)
					(fill
						(type none)
					)
				)
				(rectangle
					(start 2.921 -1.524)
					(end 3.302 1.524)
					(stroke
						(width 0)
						(type default)
					)
					(fill
						(type outline)
					)
				)
			)
			(symbol "C_Pol_330u_6.3V_KEMET-T520-B_1_1"
				(pin passive line
					(at 0 0 0)
					(length 1.8542)
					(name "~"
						(effects
							(font
								(size 1.27 1.27)
							)
						)
					)
					(number "1"
						(effects
							(font
								(size 1.27 1.27)
							)
						)
					)
				)
				(pin passive line
					(at 5.08 0 180)
					(length 1.8542)
					(name "~"
						(effects
							(font
								(size 1.27 1.27)
							)
						)
					)
					(number "2"
						(effects
							(font
								(size 1.27 1.27)
							)
						)
					)
				)
			)
		)
	(symbol "antmicroDataAcquisitionDigitaltoAnalogConvertersDAC:MCP4726A0T_DFN"
			(exclude_from_sim no)
			(in_bom yes)
			(on_board yes)
			(property "Reference" "U"
				(at 33.02 -2.54 0)
				(effects
					(font
						(size 1.27 1.27)
						(thickness 0.15)
					)
					(justify left bottom)
				)
			)
			(property "Value" "MCP4726A0T_DFN"
				(at 33.02 -7.62 0)
				(effects
					(font
						(size 1.27 1.27)
						(thickness 0.15)
					)
					(justify left bottom)
					(hide yes)
				)
			)
			(property "Footprint" "antmicro-footprints:DFN-6-1EP_2x2mm_P0.65mm_EP1x1.6mm"
				(at 33.02 -10.16 0)
				(effects
					(font
						(size 1.27 1.27)
						(thickness 0.15)
					)
					(justify left bottom)
					(hide yes)
				)
			)
			(property "Datasheet" "https://ww1.microchip.com/downloads/en/DeviceDoc/22272C.pdf"
				(at 33.02 -12.7 0)
				(effects
					(font
						(size 1.27 1.27)
						(thickness 0.15)
					)
					(justify left bottom)
					(hide yes)
				)
			)
			(property "Description" "12-Bit Voltage Output Digital-to-Analog Converter with EEPROM and I2C Interface"
				(at 0 0 0)
				(effects
					(font
						(size 1.27 1.27)
					)
					(hide yes)
				)
			)
			(property "MPN" "MCP4726A0T-E/MAY"
				(at 33.02 -5.08 0)
				(effects
					(font
						(size 1.27 1.27)
						(thickness 0.15)
					)
					(justify left bottom)
				)
			)
			(property "Manufacturer" "Microchip Technology"
				(at 33.02 -15.24 0)
				(effects
					(font
						(size 1.27 1.27)
						(thickness 0.15)
					)
					(justify left bottom)
					(hide yes)
				)
			)
			(property "Author" "Antmicro"
				(at 33.02 -17.78 0)
				(effects
					(font
						(size 1.27 1.27)
						(thickness 0.15)
					)
					(justify left bottom)
					(hide yes)
				)
			)
			(property "License" "Apache-2.0"
				(at 33.02 -20.32 0)
				(effects
					(font
						(size 1.27 1.27)
						(thickness 0.15)
					)
					(justify left bottom)
					(hide yes)
				)
			)
			(property "ki_keywords" "DAC, SMT, I2C"
				(at 0 0 0)
				(effects
					(font
						(size 1.27 1.27)
					)
					(hide yes)
				)
			)
			(property "ki_fp_filters" "DFN6_2x2MC_MCH DFN6_2x2MC_MCH-M DFN6_2x2MC_MCH-L"
				(at 0 0 0)
				(effects
					(font
						(size 1.27 1.27)
					)
					(hide yes)
				)
			)
			(symbol "MCP4726A0T_DFN_1_1"
				(rectangle
					(start 2.54 2.54)
					(end 16.51 -10.16)
					(stroke
						(width 0.254)
						(type default)
					)
					(fill
						(type background)
					)
				)
				(pin power_in line
					(at 0 0 0)
					(length 2.54)
					(name "VDD"
						(effects
							(font
								(size 1.27 1.27)
							)
						)
					)
					(number "4"
						(effects
							(font
								(size 1.27 1.27)
							)
						)
					)
				)
				(pin input line
					(at 0 -2.54 0)
					(length 2.54)
					(name "SCL"
						(effects
							(font
								(size 1.27 1.27)
							)
						)
					)
					(number "2"
						(effects
							(font
								(size 1.27 1.27)
							)
						)
					)
				)
				(pin bidirectional line
					(at 0 -5.08 0)
					(length 2.54)
					(name "SDA"
						(effects
							(font
								(size 1.27 1.27)
							)
						)
					)
					(number "3"
						(effects
							(font
								(size 1.27 1.27)
							)
						)
					)
				)
				(pin output line
					(at 19.05 0 180)
					(length 2.54)
					(name "VOUT"
						(effects
							(font
								(size 1.27 1.27)
							)
						)
					)
					(number "6"
						(effects
							(font
								(size 1.27 1.27)
							)
						)
					)
				)
				(pin power_in line
					(at 19.05 -2.54 180)
					(length 2.54)
					(name "VREF"
						(effects
							(font
								(size 1.27 1.27)
							)
						)
					)
					(number "1"
						(effects
							(font
								(size 1.27 1.27)
							)
						)
					)
				)
				(pin power_in line
					(at 19.05 -5.08 180)
					(length 2.54)
					(name "GND"
						(effects
							(font
								(size 1.27 1.27)
							)
						)
					)
					(number "5"
						(effects
							(font
								(size 1.27 1.27)
							)
						)
					)
				)
				(pin power_in line
					(at 19.05 -7.62 180)
					(length 2.54)
					(name "SH"
						(effects
							(font
								(size 1.27 1.27)
							)
						)
					)
					(number "7"
						(effects
							(font
								(size 1.27 1.27)
							)
						)
					)
				)
			)
		)
	(symbol "antmicroDiodesRectifiersSingle:BAT54-02V-G3-08"
			(pin_numbers
				(hide yes)
			)
			(pin_names
				(hide yes)
			)
			(exclude_from_sim no)
			(in_bom yes)
			(on_board yes)
			(property "Reference" "D"
				(at 21.59 -5.08 0)
				(effects
					(font
						(size 1.27 1.27)
						(thickness 0.15)
					)
					(justify left bottom)
				)
			)
			(property "Value" "BAT54-02V-G3-08"
				(at 21.59 -15.24 0)
				(effects
					(font
						(size 1.27 1.27)
						(thickness 0.15)
					)
					(justify left bottom)
					(hide yes)
				)
			)
			(property "Footprint" "antmicro-footprints:SOD-523"
				(at 21.59 -10.16 0)
				(effects
					(font
						(size 1.27 1.27)
						(thickness 0.15)
					)
					(justify left bottom)
					(hide yes)
				)
			)
			(property "Datasheet" "https://www.vishay.com/docs/85633/bat5402v.pdf"
				(at 21.59 -12.7 0)
				(effects
					(font
						(size 1.27 1.27)
						(thickness 0.15)
					)
					(justify left bottom)
					(hide yes)
				)
			)
			(property "Description" "Small Signal Schottky Diode, Single, 30 V, 200 mA, 800 mV, 600 mA, 125 °C"
				(at 21.59 -25.4 0)
				(effects
					(font
						(size 1.27 1.27)
					)
					(justify left bottom)
					(hide yes)
				)
			)
			(property "MPN" "BAT54-02V-G3-08"
				(at 21.59 -7.62 0)
				(effects
					(font
						(size 1.27 1.27)
						(thickness 0.15)
					)
					(justify left bottom)
				)
			)
			(property "Manufacturer" "Vishay"
				(at 21.59 -17.78 0)
				(effects
					(font
						(size 1.27 1.27)
						(thickness 0.15)
					)
					(justify left bottom)
					(hide yes)
				)
			)
			(property "Author" "Antmicro"
				(at 21.59 -20.32 0)
				(effects
					(font
						(size 1.27 1.27)
						(thickness 0.15)
					)
					(justify left bottom)
					(hide yes)
				)
			)
			(property "License" "Apache-2.0"
				(at 21.59 -22.86 0)
				(effects
					(font
						(size 1.27 1.27)
						(thickness 0.15)
					)
					(justify left bottom)
					(hide yes)
				)
			)
			(property "ki_keywords" "SMT, SEMICONDUCTOR, DIODE, SCHOTTKY"
				(at 0 0 0)
				(effects
					(font
						(size 1.27 1.27)
					)
					(hide yes)
				)
			)
			(symbol "BAT54-02V-G3-08_0_1"
				(polyline
					(pts
						(xy 1.905 0) (xy 0.635 0)
					)
					(stroke
						(width 0)
						(type default)
					)
					(fill
						(type none)
					)
				)
				(polyline
					(pts
						(xy 4.445 0) (xy 3.175 0)
					)
					(stroke
						(width 0)
						(type default)
					)
					(fill
						(type none)
					)
				)
			)
			(symbol "BAT54-02V-G3-08_1_1"
				(polyline
					(pts
						(xy 1.778 1.016) (xy 1.778 -1.016)
					)
					(stroke
						(width 0.254)
						(type default)
					)
					(fill
						(type none)
					)
				)
				(polyline
					(pts
						(xy 1.778 1.016) (xy 1.397 1.016) (xy 1.397 0.762)
					)
					(stroke
						(width 0.254)
						(type default)
					)
					(fill
						(type none)
					)
				)
				(polyline
					(pts
						(xy 1.778 -1.016) (xy 2.159 -1.016) (xy 2.159 -0.762)
					)
					(stroke
						(width 0.254)
						(type default)
					)
					(fill
						(type none)
					)
				)
				(polyline
					(pts
						(xy 3.302 1.016) (xy 3.302 -1.016) (xy 1.778 0) (xy 3.302 1.016)
					)
					(stroke
						(width 0.254)
						(type default)
					)
					(fill
						(type outline)
					)
				)
				(pin passive line
					(at 0 0 0)
					(length 0.635)
					(name "C"
						(effects
							(font
								(size 1.27 1.27)
							)
						)
					)
					(number "1"
						(effects
							(font
								(size 1.27 1.27)
							)
						)
					)
				)
				(pin passive line
					(at 5.08 0 180)
					(length 0.635)
					(name "A"
						(effects
							(font
								(size 1.27 1.27)
							)
						)
					)
					(number "2"
						(effects
							(font
								(size 1.27 1.27)
							)
						)
					)
				)
			)
		)
	(symbol "antmicroFPGAChips:XC7K160T-FFG676"
			(exclude_from_sim no)
			(in_bom yes)
			(on_board yes)
			(property "Reference" "U"
				(at 68.58 2.54 0)
				(effects
					(font
						(size 1.27 1.27)
						(thickness 0.15)
					)
					(justify left bottom)
				)
			)
			(property "Value" "XC7K160T-FFG676"
				(at 68.58 0 0)
				(effects
					(font
						(size 1.27 1.27)
						(thickness 0.15)
					)
					(justify left bottom)
				)
			)
			(property "Footprint" "antmicro-footprints:BGA-676_27x27mm_Layout26x26_P1x1mm_FFG676"
				(at 68.58 -2.54 0)
				(effects
					(font
						(size 1.27 1.27)
						(thickness 0.15)
					)
					(justify left bottom)
					(hide yes)
				)
			)
			(property "Datasheet" "https://docs.xilinx.com/v/u/en-US/ds180_7Series_Overview"
				(at 68.58 -5.08 0)
				(effects
					(font
						(size 1.27 1.27)
						(thickness 0.15)
					)
					(justify left bottom)
					(hide yes)
				)
			)
			(property "Description" "Kintex®-7 Field Programmable Gate Array (FPGA) IC 300 4976640 65600 676-BBGA, FCBGA"
				(at 0 0 0)
				(effects
					(font
						(size 1.27 1.27)
					)
					(hide yes)
				)
			)
			(property "Author" "Antmicro"
				(at 68.58 -7.62 0)
				(effects
					(font
						(size 1.27 1.27)
						(thickness 0.15)
					)
					(justify left bottom)
					(hide yes)
				)
			)
			(property "License" "Apache-2.0"
				(at 68.58 -10.16 0)
				(effects
					(font
						(size 1.27 1.27)
						(thickness 0.15)
					)
					(justify left bottom)
					(hide yes)
				)
			)
			(property "MPN" "XC7K160T-FFG676"
				(at 0 0 0)
				(effects
					(font
						(size 1.27 1.27)
					)
					(hide yes)
				)
			)
			(property "Manufacturer" "AMD-Xilinx"
				(at 0 0 0)
				(effects
					(font
						(size 1.27 1.27)
					)
					(hide yes)
				)
			)
			(property "ki_locked" ""
				(at 0 0 0)
				(effects
					(font
						(size 1.27 1.27)
					)
				)
			)
			(property "ki_keywords" "SMT, MICROCONTROLLER, IC, FPGA"
				(at 0 0 0)
				(effects
					(font
						(size 1.27 1.27)
					)
					(hide yes)
				)
			)
			(symbol "XC7K160T-FFG676_1_1"
				(rectangle
					(start 5.08 2.54)
					(end 33.02 -132.08)
					(stroke
						(width 0.254)
						(type default)
					)
					(fill
						(type background)
					)
				)
				(polyline
					(pts
						(xy 22.86 -3.81) (xy 30.48 -3.81) (xy 30.48 -130.81) (xy 22.86 -130.81)
					)
					(stroke
						(width 0.254)
						(type default)
					)
					(fill
						(type background)
					)
				)
				(text "BANK 12"
					(at 24.13 -1.27 0)
					(effects
						(font
							(size 1.27 1.27)
							(thickness 0.15)
						)
						(justify left bottom)
					)
				)
				(pin power_in line
					(at 0 0 0)
					(length 5.08)
					(name "VCCO_12"
						(effects
							(font
								(size 1.27 1.27)
							)
						)
					)
					(number "AA21"
						(effects
							(font
								(size 1.27 1.27)
							)
						)
					)
				)
				(pin passive line
					(at 0 0 0)
					(length 5.08)
					(hide yes)
					(name "VCCO_12"
						(effects
							(font
								(size 1.27 1.27)
							)
						)
					)
					(number "AC25"
						(effects
							(font
								(size 1.27 1.27)
							)
						)
					)
				)
				(pin passive line
					(at 0 0 0)
					(length 5.08)
					(hide yes)
					(name "VCCO_12"
						(effects
							(font
								(size 1.27 1.27)
							)
						)
					)
					(number "AD22"
						(effects
							(font
								(size 1.27 1.27)
							)
						)
					)
				)
				(pin passive line
					(at 0 0 0)
					(length 5.08)
					(hide yes)
					(name "VCCO_12"
						(effects
							(font
								(size 1.27 1.27)
							)
						)
					)
					(number "AF26"
						(effects
							(font
								(size 1.27 1.27)
							)
						)
					)
				)
				(pin passive line
					(at 0 0 0)
					(length 5.08)
					(hide yes)
					(name "VCCO_12"
						(effects
							(font
								(size 1.27 1.27)
							)
						)
					)
					(number "U23"
						(effects
							(font
								(size 1.27 1.27)
							)
						)
					)
				)
				(pin passive line
					(at 0 0 0)
					(length 5.08)
					(hide yes)
					(name "VCCO_12"
						(effects
							(font
								(size 1.27 1.27)
							)
						)
					)
					(number "V20"
						(effects
							(font
								(size 1.27 1.27)
							)
						)
					)
				)
				(pin passive line
					(at 0 0 0)
					(length 5.08)
					(hide yes)
					(name "VCCO_12"
						(effects
							(font
								(size 1.27 1.27)
							)
						)
					)
					(number "Y24"
						(effects
							(font
								(size 1.27 1.27)
							)
						)
					)
				)
				(pin bidirectional line
					(at 0 -5.08 0)
					(length 5.08)
					(name "IO_0_12"
						(effects
							(font
								(size 1.27 1.27)
							)
						)
					)
					(number "U21"
						(effects
							(font
								(size 1.27 1.27)
							)
						)
					)
				)
				(pin bidirectional line
					(at 0 -7.62 0)
					(length 5.08)
					(name "IO_L1P_T0_12"
						(effects
							(font
								(size 1.27 1.27)
							)
						)
					)
					(number "U22"
						(effects
							(font
								(size 1.27 1.27)
							)
						)
					)
				)
				(pin bidirectional line
					(at 0 -10.16 0)
					(length 5.08)
					(name "IO_L1N_T0_12"
						(effects
							(font
								(size 1.27 1.27)
							)
						)
					)
					(number "V22"
						(effects
							(font
								(size 1.27 1.27)
							)
						)
					)
				)
				(pin bidirectional line
					(at 0 -12.7 0)
					(length 5.08)
					(name "IO_L2P_T0_12"
						(effects
							(font
								(size 1.27 1.27)
							)
						)
					)
					(number "U24"
						(effects
							(font
								(size 1.27 1.27)
							)
						)
					)
				)
				(pin bidirectional line
					(at 0 -15.24 0)
					(length 5.08)
					(name "IO_L2N_T0_12"
						(effects
							(font
								(size 1.27 1.27)
							)
						)
					)
					(number "U25"
						(effects
							(font
								(size 1.27 1.27)
							)
						)
					)
				)
				(pin bidirectional line
					(at 0 -17.78 0)
					(length 5.08)
					(name "IO_L3P_T0_DQS_12"
						(effects
							(font
								(size 1.27 1.27)
							)
						)
					)
					(number "V23"
						(effects
							(font
								(size 1.27 1.27)
							)
						)
					)
				)
				(pin bidirectional line
					(at 0 -20.32 0)
					(length 5.08)
					(name "IO_L3N_T0_DQS_12"
						(effects
							(font
								(size 1.27 1.27)
							)
						)
					)
					(number "V24"
						(effects
							(font
								(size 1.27 1.27)
							)
						)
					)
				)
				(pin bidirectional line
					(at 0 -22.86 0)
					(length 5.08)
					(name "IO_L4P_T0_12"
						(effects
							(font
								(size 1.27 1.27)
							)
						)
					)
					(number "U26"
						(effects
							(font
								(size 1.27 1.27)
							)
						)
					)
				)
				(pin bidirectional line
					(at 0 -25.4 0)
					(length 5.08)
					(name "IO_L4N_T0_12"
						(effects
							(font
								(size 1.27 1.27)
							)
						)
					)
					(number "V26"
						(effects
							(font
								(size 1.27 1.27)
							)
						)
					)
				)
				(pin bidirectional line
					(at 0 -27.94 0)
					(length 5.08)
					(name "IO_L5P_T0_12"
						(effects
							(font
								(size 1.27 1.27)
							)
						)
					)
					(number "W25"
						(effects
							(font
								(size 1.27 1.27)
							)
						)
					)
				)
				(pin bidirectional line
					(at 0 -30.48 0)
					(length 5.08)
					(name "IO_L5N_T0_12"
						(effects
							(font
								(size 1.27 1.27)
							)
						)
					)
					(number "W26"
						(effects
							(font
								(size 1.27 1.27)
							)
						)
					)
				)
				(pin bidirectional line
					(at 0 -33.02 0)
					(length 5.08)
					(name "IO_L6P_T0_12"
						(effects
							(font
								(size 1.27 1.27)
							)
						)
					)
					(number "V21"
						(effects
							(font
								(size 1.27 1.27)
							)
						)
					)
				)
				(pin bidirectional line
					(at 0 -35.56 0)
					(length 5.08)
					(name "IO_L6N_T0_VREF_12"
						(effects
							(font
								(size 1.27 1.27)
							)
						)
					)
					(number "W21"
						(effects
							(font
								(size 1.27 1.27)
							)
						)
					)
				)
				(pin bidirectional line
					(at 0 -38.1 0)
					(length 5.08)
					(name "IO_L7P_T1_12"
						(effects
							(font
								(size 1.27 1.27)
							)
						)
					)
					(number "AA25"
						(effects
							(font
								(size 1.27 1.27)
							)
						)
					)
				)
				(pin bidirectional line
					(at 0 -40.64 0)
					(length 5.08)
					(name "IO_L7N_T1_12"
						(effects
							(font
								(size 1.27 1.27)
							)
						)
					)
					(number "AB25"
						(effects
							(font
								(size 1.27 1.27)
							)
						)
					)
				)
				(pin bidirectional line
					(at 0 -43.18 0)
					(length 5.08)
					(name "IO_L8P_T1_12"
						(effects
							(font
								(size 1.27 1.27)
							)
						)
					)
					(number "W23"
						(effects
							(font
								(size 1.27 1.27)
							)
						)
					)
				)
				(pin bidirectional line
					(at 0 -45.72 0)
					(length 5.08)
					(name "IO_L8N_T1_12"
						(effects
							(font
								(size 1.27 1.27)
							)
						)
					)
					(number "W24"
						(effects
							(font
								(size 1.27 1.27)
							)
						)
					)
				)
				(pin bidirectional line
					(at 0 -48.26 0)
					(length 5.08)
					(name "IO_L9P_T1_DQS_12"
						(effects
							(font
								(size 1.27 1.27)
							)
						)
					)
					(number "AB26"
						(effects
							(font
								(size 1.27 1.27)
							)
						)
					)
				)
				(pin bidirectional line
					(at 0 -50.8 0)
					(length 5.08)
					(name "IO_L9N_T1_DQS_12"
						(effects
							(font
								(size 1.27 1.27)
							)
						)
					)
					(number "AC26"
						(effects
							(font
								(size 1.27 1.27)
							)
						)
					)
				)
				(pin bidirectional line
					(at 0 -53.34 0)
					(length 5.08)
					(name "IO_L10P_T1_12"
						(effects
							(font
								(size 1.27 1.27)
							)
						)
					)
					(number "Y25"
						(effects
							(font
								(size 1.27 1.27)
							)
						)
					)
				)
				(pin bidirectional line
					(at 0 -55.88 0)
					(length 5.08)
					(name "IO_L10N_T1_12"
						(effects
							(font
								(size 1.27 1.27)
							)
						)
					)
					(number "Y26"
						(effects
							(font
								(size 1.27 1.27)
							)
						)
					)
				)
				(pin bidirectional line
					(at 0 -58.42 0)
					(length 5.08)
					(name "IO_L11P_T1_SRCC_12"
						(effects
							(font
								(size 1.27 1.27)
							)
						)
					)
					(number "AA23"
						(effects
							(font
								(size 1.27 1.27)
							)
						)
					)
				)
				(pin bidirectional line
					(at 0 -60.96 0)
					(length 5.08)
					(name "IO_L11N_T1_SRCC_12"
						(effects
							(font
								(size 1.27 1.27)
							)
						)
					)
					(number "AB24"
						(effects
							(font
								(size 1.27 1.27)
							)
						)
					)
				)
				(pin bidirectional line
					(at 0 -63.5 0)
					(length 5.08)
					(name "IO_L12P_T1_MRCC_12"
						(effects
							(font
								(size 1.27 1.27)
							)
						)
					)
					(number "Y23"
						(effects
							(font
								(size 1.27 1.27)
							)
						)
					)
				)
				(pin bidirectional line
					(at 0 -66.04 0)
					(length 5.08)
					(name "IO_L12N_T1_MRCC_12"
						(effects
							(font
								(size 1.27 1.27)
							)
						)
					)
					(number "AA24"
						(effects
							(font
								(size 1.27 1.27)
							)
						)
					)
				)
				(pin bidirectional line
					(at 0 -68.58 0)
					(length 5.08)
					(name "IO_L13P_T2_MRCC_12"
						(effects
							(font
								(size 1.27 1.27)
							)
						)
					)
					(number "Y22"
						(effects
							(font
								(size 1.27 1.27)
							)
						)
					)
				)
				(pin bidirectional line
					(at 0 -71.12 0)
					(length 5.08)
					(name "IO_L13N_T2_MRCC_12"
						(effects
							(font
								(size 1.27 1.27)
							)
						)
					)
					(number "AA22"
						(effects
							(font
								(size 1.27 1.27)
							)
						)
					)
				)
				(pin bidirectional line
					(at 0 -73.66 0)
					(length 5.08)
					(name "IO_L14P_T2_SRCC_12"
						(effects
							(font
								(size 1.27 1.27)
							)
						)
					)
					(number "AC23"
						(effects
							(font
								(size 1.27 1.27)
							)
						)
					)
				)
				(pin bidirectional line
					(at 0 -76.2 0)
					(length 5.08)
					(name "IO_L14N_T2_SRCC_12"
						(effects
							(font
								(size 1.27 1.27)
							)
						)
					)
					(number "AC24"
						(effects
							(font
								(size 1.27 1.27)
							)
						)
					)
				)
				(pin bidirectional line
					(at 0 -78.74 0)
					(length 5.08)
					(name "IO_L15P_T2_DQS_12"
						(effects
							(font
								(size 1.27 1.27)
							)
						)
					)
					(number "W20"
						(effects
							(font
								(size 1.27 1.27)
							)
						)
					)
				)
				(pin bidirectional line
					(at 0 -81.28 0)
					(length 5.08)
					(name "IO_L15N_T2_DQS_12"
						(effects
							(font
								(size 1.27 1.27)
							)
						)
					)
					(number "Y21"
						(effects
							(font
								(size 1.27 1.27)
							)
						)
					)
				)
				(pin bidirectional line
					(at 0 -83.82 0)
					(length 5.08)
					(name "IO_L16P_T2_12"
						(effects
							(font
								(size 1.27 1.27)
							)
						)
					)
					(number "AD23"
						(effects
							(font
								(size 1.27 1.27)
							)
						)
					)
				)
				(pin bidirectional line
					(at 0 -86.36 0)
					(length 5.08)
					(name "IO_L16N_T2_12"
						(effects
							(font
								(size 1.27 1.27)
							)
						)
					)
					(number "AD24"
						(effects
							(font
								(size 1.27 1.27)
							)
						)
					)
				)
				(pin bidirectional line
					(at 0 -88.9 0)
					(length 5.08)
					(name "IO_L17P_T2_12"
						(effects
							(font
								(size 1.27 1.27)
							)
						)
					)
					(number "AB22"
						(effects
							(font
								(size 1.27 1.27)
							)
						)
					)
				)
				(pin bidirectional line
					(at 0 -91.44 0)
					(length 5.08)
					(name "IO_L17N_T2_12"
						(effects
							(font
								(size 1.27 1.27)
							)
						)
					)
					(number "AC22"
						(effects
							(font
								(size 1.27 1.27)
							)
						)
					)
				)
				(pin bidirectional line
					(at 0 -93.98 0)
					(length 5.08)
					(name "IO_L18P_T2_12"
						(effects
							(font
								(size 1.27 1.27)
							)
						)
					)
					(number "AB21"
						(effects
							(font
								(size 1.27 1.27)
							)
						)
					)
				)
				(pin bidirectional line
					(at 0 -96.52 0)
					(length 5.08)
					(name "IO_L18N_T2_12"
						(effects
							(font
								(size 1.27 1.27)
							)
						)
					)
					(number "AC21"
						(effects
							(font
								(size 1.27 1.27)
							)
						)
					)
				)
				(pin bidirectional line
					(at 0 -99.06 0)
					(length 5.08)
					(name "IO_L19P_T3_12"
						(effects
							(font
								(size 1.27 1.27)
							)
						)
					)
					(number "AD21"
						(effects
							(font
								(size 1.27 1.27)
							)
						)
					)
				)
				(pin bidirectional line
					(at 0 -101.6 0)
					(length 5.08)
					(name "IO_L19N_T3_VREF_12"
						(effects
							(font
								(size 1.27 1.27)
							)
						)
					)
					(number "AE21"
						(effects
							(font
								(size 1.27 1.27)
							)
						)
					)
				)
				(pin bidirectional line
					(at 0 -104.14 0)
					(length 5.08)
					(name "IO_L20P_T3_12"
						(effects
							(font
								(size 1.27 1.27)
							)
						)
					)
					(number "AF24"
						(effects
							(font
								(size 1.27 1.27)
							)
						)
					)
				)
				(pin bidirectional line
					(at 0 -106.68 0)
					(length 5.08)
					(name "IO_L20N_T3_12"
						(effects
							(font
								(size 1.27 1.27)
							)
						)
					)
					(number "AF25"
						(effects
							(font
								(size 1.27 1.27)
							)
						)
					)
				)
				(pin bidirectional line
					(at 0 -109.22 0)
					(length 5.08)
					(name "IO_L21P_T3_DQS_12"
						(effects
							(font
								(size 1.27 1.27)
							)
						)
					)
					(number "AD26"
						(effects
							(font
								(size 1.27 1.27)
							)
						)
					)
				)
				(pin bidirectional line
					(at 0 -111.76 0)
					(length 5.08)
					(name "IO_L21N_T3_DQS_12"
						(effects
							(font
								(size 1.27 1.27)
							)
						)
					)
					(number "AE26"
						(effects
							(font
								(size 1.27 1.27)
							)
						)
					)
				)
				(pin bidirectional line
					(at 0 -114.3 0)
					(length 5.08)
					(name "IO_L22P_T3_12"
						(effects
							(font
								(size 1.27 1.27)
							)
						)
					)
					(number "AE23"
						(effects
							(font
								(size 1.27 1.27)
							)
						)
					)
				)
				(pin bidirectional line
					(at 0 -116.84 0)
					(length 5.08)
					(name "IO_L22N_T3_12"
						(effects
							(font
								(size 1.27 1.27)
							)
						)
					)
					(number "AF23"
						(effects
							(font
								(size 1.27 1.27)
							)
						)
					)
				)
				(pin bidirectional line
					(at 0 -119.38 0)
					(length 5.08)
					(name "IO_L23P_T3_12"
						(effects
							(font
								(size 1.27 1.27)
							)
						)
					)
					(number "AD25"
						(effects
							(font
								(size 1.27 1.27)
							)
						)
					)
				)
				(pin bidirectional line
					(at 0 -121.92 0)
					(length 5.08)
					(name "IO_L23N_T3_12"
						(effects
							(font
								(size 1.27 1.27)
							)
						)
					)
					(number "AE25"
						(effects
							(font
								(size 1.27 1.27)
							)
						)
					)
				)
				(pin bidirectional line
					(at 0 -124.46 0)
					(length 5.08)
					(name "IO_L24P_T3_12"
						(effects
							(font
								(size 1.27 1.27)
							)
						)
					)
					(number "AE22"
						(effects
							(font
								(size 1.27 1.27)
							)
						)
					)
				)
				(pin bidirectional line
					(at 0 -127 0)
					(length 5.08)
					(name "IO_L24N_T3_12"
						(effects
							(font
								(size 1.27 1.27)
							)
						)
					)
					(number "AF22"
						(effects
							(font
								(size 1.27 1.27)
							)
						)
					)
				)
				(pin bidirectional line
					(at 0 -129.54 0)
					(length 5.08)
					(name "IO_25_12"
						(effects
							(font
								(size 1.27 1.27)
							)
						)
					)
					(number "Y20"
						(effects
							(font
								(size 1.27 1.27)
							)
						)
					)
				)
			)
			(symbol "XC7K160T-FFG676_2_1"
				(rectangle
					(start 5.08 -132.08)
					(end 33.02 2.54)
					(stroke
						(width 0.254)
						(type default)
					)
					(fill
						(type background)
					)
				)
				(polyline
					(pts
						(xy 22.86 -3.81) (xy 30.48 -3.81) (xy 30.48 -130.81) (xy 22.86 -130.81)
					)
					(stroke
						(width 0.254)
						(type default)
					)
					(fill
						(type background)
					)
				)
				(text "BANK 13"
					(at 24.13 -1.27 0)
					(effects
						(font
							(size 1.27 1.27)
							(thickness 0.15)
						)
						(justify left bottom)
					)
				)
				(pin power_in line
					(at 0 0 0)
					(length 5.08)
					(name "VCCO_13"
						(effects
							(font
								(size 1.27 1.27)
							)
						)
					)
					(number "K24"
						(effects
							(font
								(size 1.27 1.27)
							)
						)
					)
				)
				(pin passive line
					(at 0 0 0)
					(length 5.08)
					(hide yes)
					(name "VCCO_13"
						(effects
							(font
								(size 1.27 1.27)
							)
						)
					)
					(number "N25"
						(effects
							(font
								(size 1.27 1.27)
							)
						)
					)
				)
				(pin passive line
					(at 0 0 0)
					(length 5.08)
					(hide yes)
					(name "VCCO_13"
						(effects
							(font
								(size 1.27 1.27)
							)
						)
					)
					(number "P22"
						(effects
							(font
								(size 1.27 1.27)
							)
						)
					)
				)
				(pin passive line
					(at 0 0 0)
					(length 5.08)
					(hide yes)
					(name "VCCO_13"
						(effects
							(font
								(size 1.27 1.27)
							)
						)
					)
					(number "R19"
						(effects
							(font
								(size 1.27 1.27)
							)
						)
					)
				)
				(pin passive line
					(at 0 0 0)
					(length 5.08)
					(hide yes)
					(name "VCCO_13"
						(effects
							(font
								(size 1.27 1.27)
							)
						)
					)
					(number "T16"
						(effects
							(font
								(size 1.27 1.27)
							)
						)
					)
				)
				(pin passive line
					(at 0 0 0)
					(length 5.08)
					(hide yes)
					(name "VCCO_13"
						(effects
							(font
								(size 1.27 1.27)
							)
						)
					)
					(number "T26"
						(effects
							(font
								(size 1.27 1.27)
							)
						)
					)
				)
				(pin bidirectional line
					(at 0 -5.08 0)
					(length 5.08)
					(name "IO_0_13"
						(effects
							(font
								(size 1.27 1.27)
							)
						)
					)
					(number "N16"
						(effects
							(font
								(size 1.27 1.27)
							)
						)
					)
				)
				(pin bidirectional line
					(at 0 -7.62 0)
					(length 5.08)
					(name "IO_L1P_T0_13"
						(effects
							(font
								(size 1.27 1.27)
							)
						)
					)
					(number "K25"
						(effects
							(font
								(size 1.27 1.27)
							)
						)
					)
				)
				(pin bidirectional line
					(at 0 -10.16 0)
					(length 5.08)
					(name "IO_L1N_T0_13"
						(effects
							(font
								(size 1.27 1.27)
							)
						)
					)
					(number "K26"
						(effects
							(font
								(size 1.27 1.27)
							)
						)
					)
				)
				(pin bidirectional line
					(at 0 -12.7 0)
					(length 5.08)
					(name "IO_L2P_T0_13"
						(effects
							(font
								(size 1.27 1.27)
							)
						)
					)
					(number "R26"
						(effects
							(font
								(size 1.27 1.27)
							)
						)
					)
				)
				(pin bidirectional line
					(at 0 -15.24 0)
					(length 5.08)
					(name "IO_L2N_T0_13"
						(effects
							(font
								(size 1.27 1.27)
							)
						)
					)
					(number "P26"
						(effects
							(font
								(size 1.27 1.27)
							)
						)
					)
				)
				(pin bidirectional line
					(at 0 -17.78 0)
					(length 5.08)
					(name "IO_L3P_T0_DQS_13"
						(effects
							(font
								(size 1.27 1.27)
							)
						)
					)
					(number "M25"
						(effects
							(font
								(size 1.27 1.27)
							)
						)
					)
				)
				(pin bidirectional line
					(at 0 -20.32 0)
					(length 5.08)
					(name "IO_L3N_T0_DQS_13"
						(effects
							(font
								(size 1.27 1.27)
							)
						)
					)
					(number "L25"
						(effects
							(font
								(size 1.27 1.27)
							)
						)
					)
				)
				(pin bidirectional line
					(at 0 -22.86 0)
					(length 5.08)
					(name "IO_L4P_T0_13"
						(effects
							(font
								(size 1.27 1.27)
							)
						)
					)
					(number "P24"
						(effects
							(font
								(size 1.27 1.27)
							)
						)
					)
				)
				(pin bidirectional line
					(at 0 -25.4 0)
					(length 5.08)
					(name "IO_L4N_T0_13"
						(effects
							(font
								(size 1.27 1.27)
							)
						)
					)
					(number "N24"
						(effects
							(font
								(size 1.27 1.27)
							)
						)
					)
				)
				(pin bidirectional line
					(at 0 -27.94 0)
					(length 5.08)
					(name "IO_L5P_T0_13"
						(effects
							(font
								(size 1.27 1.27)
							)
						)
					)
					(number "N26"
						(effects
							(font
								(size 1.27 1.27)
							)
						)
					)
				)
				(pin bidirectional line
					(at 0 -30.48 0)
					(length 5.08)
					(name "IO_L5N_T0_13"
						(effects
							(font
								(size 1.27 1.27)
							)
						)
					)
					(number "M26"
						(effects
							(font
								(size 1.27 1.27)
							)
						)
					)
				)
				(pin bidirectional line
					(at 0 -33.02 0)
					(length 5.08)
					(name "IO_L6P_T0_13"
						(effects
							(font
								(size 1.27 1.27)
							)
						)
					)
					(number "R25"
						(effects
							(font
								(size 1.27 1.27)
							)
						)
					)
				)
				(pin bidirectional line
					(at 0 -35.56 0)
					(length 5.08)
					(name "IO_L6N_T0_VREF_13"
						(effects
							(font
								(size 1.27 1.27)
							)
						)
					)
					(number "P25"
						(effects
							(font
								(size 1.27 1.27)
							)
						)
					)
				)
				(pin bidirectional line
					(at 0 -38.1 0)
					(length 5.08)
					(name "IO_L7P_T1_13"
						(effects
							(font
								(size 1.27 1.27)
							)
						)
					)
					(number "N19"
						(effects
							(font
								(size 1.27 1.27)
							)
						)
					)
				)
				(pin bidirectional line
					(at 0 -40.64 0)
					(length 5.08)
					(name "IO_L7N_T1_13"
						(effects
							(font
								(size 1.27 1.27)
							)
						)
					)
					(number "M20"
						(effects
							(font
								(size 1.27 1.27)
							)
						)
					)
				)
				(pin bidirectional line
					(at 0 -43.18 0)
					(length 5.08)
					(name "IO_L8P_T1_13"
						(effects
							(font
								(size 1.27 1.27)
							)
						)
					)
					(number "M24"
						(effects
							(font
								(size 1.27 1.27)
							)
						)
					)
				)
				(pin bidirectional line
					(at 0 -45.72 0)
					(length 5.08)
					(name "IO_L8N_T1_13"
						(effects
							(font
								(size 1.27 1.27)
							)
						)
					)
					(number "L24"
						(effects
							(font
								(size 1.27 1.27)
							)
						)
					)
				)
				(pin bidirectional line
					(at 0 -48.26 0)
					(length 5.08)
					(name "IO_L9P_T1_DQS_13"
						(effects
							(font
								(size 1.27 1.27)
							)
						)
					)
					(number "P19"
						(effects
							(font
								(size 1.27 1.27)
							)
						)
					)
				)
				(pin bidirectional line
					(at 0 -50.8 0)
					(length 5.08)
					(name "IO_L9N_T1_DQS_13"
						(effects
							(font
								(size 1.27 1.27)
							)
						)
					)
					(number "P20"
						(effects
							(font
								(size 1.27 1.27)
							)
						)
					)
				)
				(pin bidirectional line
					(at 0 -53.34 0)
					(length 5.08)
					(name "IO_L10P_T1_13"
						(effects
							(font
								(size 1.27 1.27)
							)
						)
					)
					(number "M21"
						(effects
							(font
								(size 1.27 1.27)
							)
						)
					)
				)
				(pin bidirectional line
					(at 0 -55.88 0)
					(length 5.08)
					(name "IO_L10N_T1_13"
						(effects
							(font
								(size 1.27 1.27)
							)
						)
					)
					(number "M22"
						(effects
							(font
								(size 1.27 1.27)
							)
						)
					)
				)
				(pin bidirectional line
					(at 0 -58.42 0)
					(length 5.08)
					(name "IO_L11P_T1_SRCC_13"
						(effects
							(font
								(size 1.27 1.27)
							)
						)
					)
					(number "P23"
						(effects
							(font
								(size 1.27 1.27)
							)
						)
					)
				)
				(pin bidirectional line
					(at 0 -60.96 0)
					(length 5.08)
					(name "IO_L11N_T1_SRCC_13"
						(effects
							(font
								(size 1.27 1.27)
							)
						)
					)
					(number "N23"
						(effects
							(font
								(size 1.27 1.27)
							)
						)
					)
				)
				(pin bidirectional line
					(at 0 -63.5 0)
					(length 5.08)
					(name "IO_L12P_T1_MRCC_13"
						(effects
							(font
								(size 1.27 1.27)
							)
						)
					)
					(number "N21"
						(effects
							(font
								(size 1.27 1.27)
							)
						)
					)
				)
				(pin bidirectional line
					(at 0 -66.04 0)
					(length 5.08)
					(name "IO_L12N_T1_MRCC_13"
						(effects
							(font
								(size 1.27 1.27)
							)
						)
					)
					(number "N22"
						(effects
							(font
								(size 1.27 1.27)
							)
						)
					)
				)
				(pin bidirectional line
					(at 0 -68.58 0)
					(length 5.08)
					(name "IO_L13P_T2_MRCC_13"
						(effects
							(font
								(size 1.27 1.27)
							)
						)
					)
					(number "R21"
						(effects
							(font
								(size 1.27 1.27)
							)
						)
					)
				)
				(pin bidirectional line
					(at 0 -71.12 0)
					(length 5.08)
					(name "IO_L13N_T2_MRCC_13"
						(effects
							(font
								(size 1.27 1.27)
							)
						)
					)
					(number "P21"
						(effects
							(font
								(size 1.27 1.27)
							)
						)
					)
				)
				(pin bidirectional line
					(at 0 -73.66 0)
					(length 5.08)
					(name "IO_L14P_T2_SRCC_13"
						(effects
							(font
								(size 1.27 1.27)
							)
						)
					)
					(number "R22"
						(effects
							(font
								(size 1.27 1.27)
							)
						)
					)
				)
				(pin bidirectional line
					(at 0 -76.2 0)
					(length 5.08)
					(name "IO_L14N_T2_SRCC_13"
						(effects
							(font
								(size 1.27 1.27)
							)
						)
					)
					(number "R23"
						(effects
							(font
								(size 1.27 1.27)
							)
						)
					)
				)
				(pin bidirectional line
					(at 0 -78.74 0)
					(length 5.08)
					(name "IO_L15P_T2_DQS_13"
						(effects
							(font
								(size 1.27 1.27)
							)
						)
					)
					(number "T24"
						(effects
							(font
								(size 1.27 1.27)
							)
						)
					)
				)
				(pin bidirectional line
					(at 0 -81.28 0)
					(length 5.08)
					(name "IO_L15N_T2_DQS_13"
						(effects
							(font
								(size 1.27 1.27)
							)
						)
					)
					(number "T25"
						(effects
							(font
								(size 1.27 1.27)
							)
						)
					)
				)
				(pin bidirectional line
					(at 0 -83.82 0)
					(length 5.08)
					(name "IO_L16P_T2_13"
						(effects
							(font
								(size 1.27 1.27)
							)
						)
					)
					(number "T20"
						(effects
							(font
								(size 1.27 1.27)
							)
						)
					)
				)
				(pin bidirectional line
					(at 0 -86.36 0)
					(length 5.08)
					(name "IO_L16N_T2_13"
						(effects
							(font
								(size 1.27 1.27)
							)
						)
					)
					(number "R20"
						(effects
							(font
								(size 1.27 1.27)
							)
						)
					)
				)
				(pin bidirectional line
					(at 0 -88.9 0)
					(length 5.08)
					(name "IO_L17P_T2_13"
						(effects
							(font
								(size 1.27 1.27)
							)
						)
					)
					(number "T22"
						(effects
							(font
								(size 1.27 1.27)
							)
						)
					)
				)
				(pin bidirectional line
					(at 0 -91.44 0)
					(length 5.08)
					(name "IO_L17N_T2_13"
						(effects
							(font
								(size 1.27 1.27)
							)
						)
					)
					(number "T23"
						(effects
							(font
								(size 1.27 1.27)
							)
						)
					)
				)
				(pin bidirectional line
					(at 0 -93.98 0)
					(length 5.08)
					(name "IO_L18P_T2_13"
						(effects
							(font
								(size 1.27 1.27)
							)
						)
					)
					(number "U19"
						(effects
							(font
								(size 1.27 1.27)
							)
						)
					)
				)
				(pin bidirectional line
					(at 0 -96.52 0)
					(length 5.08)
					(name "IO_L18N_T2_13"
						(effects
							(font
								(size 1.27 1.27)
							)
						)
					)
					(number "U20"
						(effects
							(font
								(size 1.27 1.27)
							)
						)
					)
				)
				(pin bidirectional line
					(at 0 -99.06 0)
					(length 5.08)
					(name "IO_L19P_T3_13"
						(effects
							(font
								(size 1.27 1.27)
							)
						)
					)
					(number "T18"
						(effects
							(font
								(size 1.27 1.27)
							)
						)
					)
				)
				(pin bidirectional line
					(at 0 -101.6 0)
					(length 5.08)
					(name "IO_L19N_T3_VREF_13"
						(effects
							(font
								(size 1.27 1.27)
							)
						)
					)
					(number "T19"
						(effects
							(font
								(size 1.27 1.27)
							)
						)
					)
				)
				(pin bidirectional line
					(at 0 -104.14 0)
					(length 5.08)
					(name "IO_L20P_T3_13"
						(effects
							(font
								(size 1.27 1.27)
							)
						)
					)
					(number "P16"
						(effects
							(font
								(size 1.27 1.27)
							)
						)
					)
				)
				(pin bidirectional line
					(at 0 -106.68 0)
					(length 5.08)
					(name "IO_L20N_T3_13"
						(effects
							(font
								(size 1.27 1.27)
							)
						)
					)
					(number "N17"
						(effects
							(font
								(size 1.27 1.27)
							)
						)
					)
				)
				(pin bidirectional line
					(at 0 -109.22 0)
					(length 5.08)
					(name "IO_L21P_T3_DQS_13"
						(effects
							(font
								(size 1.27 1.27)
							)
						)
					)
					(number "R16"
						(effects
							(font
								(size 1.27 1.27)
							)
						)
					)
				)
				(pin bidirectional line
					(at 0 -111.76 0)
					(length 5.08)
					(name "IO_L21N_T3_DQS_13"
						(effects
							(font
								(size 1.27 1.27)
							)
						)
					)
					(number "R17"
						(effects
							(font
								(size 1.27 1.27)
							)
						)
					)
				)
				(pin bidirectional line
					(at 0 -114.3 0)
					(length 5.08)
					(name "IO_L22P_T3_13"
						(effects
							(font
								(size 1.27 1.27)
							)
						)
					)
					(number "N18"
						(effects
							(font
								(size 1.27 1.27)
							)
						)
					)
				)
				(pin bidirectional line
					(at 0 -116.84 0)
					(length 5.08)
					(name "IO_L22N_T3_13"
						(effects
							(font
								(size 1.27 1.27)
							)
						)
					)
					(number "M19"
						(effects
							(font
								(size 1.27 1.27)
							)
						)
					)
				)
				(pin bidirectional line
					(at 0 -119.38 0)
					(length 5.08)
					(name "IO_L23P_T3_13"
						(effects
							(font
								(size 1.27 1.27)
							)
						)
					)
					(number "U17"
						(effects
							(font
								(size 1.27 1.27)
							)
						)
					)
				)
				(pin bidirectional line
					(at 0 -121.92 0)
					(length 5.08)
					(name "IO_L23N_T3_13"
						(effects
							(font
								(size 1.27 1.27)
							)
						)
					)
					(number "T17"
						(effects
							(font
								(size 1.27 1.27)
							)
						)
					)
				)
				(pin bidirectional line
					(at 0 -124.46 0)
					(length 5.08)
					(name "IO_L24P_T3_13"
						(effects
							(font
								(size 1.27 1.27)
							)
						)
					)
					(number "R18"
						(effects
							(font
								(size 1.27 1.27)
							)
						)
					)
				)
				(pin bidirectional line
					(at 0 -127 0)
					(length 5.08)
					(name "IO_L24N_T3_13"
						(effects
							(font
								(size 1.27 1.27)
							)
						)
					)
					(number "P18"
						(effects
							(font
								(size 1.27 1.27)
							)
						)
					)
				)
				(pin bidirectional line
					(at 0 -129.54 0)
					(length 5.08)
					(name "IO_25_13"
						(effects
							(font
								(size 1.27 1.27)
							)
						)
					)
					(number "U16"
						(effects
							(font
								(size 1.27 1.27)
							)
						)
					)
				)
			)
			(symbol "XC7K160T-FFG676_3_1"
				(rectangle
					(start 5.08 2.54)
					(end 40.64 -132.08)
					(stroke
						(width 0.254)
						(type default)
					)
					(fill
						(type background)
					)
				)
				(polyline
					(pts
						(xy 30.48 -3.81) (xy 38.1 -3.81) (xy 38.1 -130.81) (xy 30.48 -130.81)
					)
					(stroke
						(width 0.254)
						(type default)
					)
					(fill
						(type background)
					)
				)
				(text "BANK 14"
					(at 31.75 -1.27 0)
					(effects
						(font
							(size 1.27 1.27)
							(thickness 0.15)
						)
						(justify left bottom)
					)
				)
				(pin power_in line
					(at 0 0 0)
					(length 5.08)
					(name "VCCO_14"
						(effects
							(font
								(size 1.27 1.27)
							)
						)
					)
					(number "A21"
						(effects
							(font
								(size 1.27 1.27)
							)
						)
					)
				)
				(pin passive line
					(at 0 0 0)
					(length 5.08)
					(hide yes)
					(name "VCCO_14"
						(effects
							(font
								(size 1.27 1.27)
							)
						)
					)
					(number "C25"
						(effects
							(font
								(size 1.27 1.27)
							)
						)
					)
				)
				(pin passive line
					(at 0 0 0)
					(length 5.08)
					(hide yes)
					(name "VCCO_14"
						(effects
							(font
								(size 1.27 1.27)
							)
						)
					)
					(number "D22"
						(effects
							(font
								(size 1.27 1.27)
							)
						)
					)
				)
				(pin passive line
					(at 0 0 0)
					(length 5.08)
					(hide yes)
					(name "VCCO_14"
						(effects
							(font
								(size 1.27 1.27)
							)
						)
					)
					(number "F26"
						(effects
							(font
								(size 1.27 1.27)
							)
						)
					)
				)
				(pin passive line
					(at 0 0 0)
					(length 5.08)
					(hide yes)
					(name "VCCO_14"
						(effects
							(font
								(size 1.27 1.27)
							)
						)
					)
					(number "G23"
						(effects
							(font
								(size 1.27 1.27)
							)
						)
					)
				)
				(pin passive line
					(at 0 0 0)
					(length 5.08)
					(hide yes)
					(name "VCCO_14"
						(effects
							(font
								(size 1.27 1.27)
							)
						)
					)
					(number "L21"
						(effects
							(font
								(size 1.27 1.27)
							)
						)
					)
				)
				(pin bidirectional line
					(at 0 -5.08 0)
					(length 5.08)
					(name "IO_0_14"
						(effects
							(font
								(size 1.27 1.27)
							)
						)
					)
					(number "K21"
						(effects
							(font
								(size 1.27 1.27)
							)
						)
					)
				)
				(pin bidirectional line
					(at 0 -7.62 0)
					(length 5.08)
					(name "IO_L1P_T0_D00_MOSI_14"
						(effects
							(font
								(size 1.27 1.27)
							)
						)
					)
					(number "B24"
						(effects
							(font
								(size 1.27 1.27)
							)
						)
					)
				)
				(pin bidirectional line
					(at 0 -10.16 0)
					(length 5.08)
					(name "IO_L1N_T0_D01_DIN_14"
						(effects
							(font
								(size 1.27 1.27)
							)
						)
					)
					(number "A25"
						(effects
							(font
								(size 1.27 1.27)
							)
						)
					)
				)
				(pin bidirectional line
					(at 0 -12.7 0)
					(length 5.08)
					(name "IO_L2P_T0_D02_14"
						(effects
							(font
								(size 1.27 1.27)
							)
						)
					)
					(number "B22"
						(effects
							(font
								(size 1.27 1.27)
							)
						)
					)
				)
				(pin bidirectional line
					(at 0 -15.24 0)
					(length 5.08)
					(name "IO_L2N_T0_D03_14"
						(effects
							(font
								(size 1.27 1.27)
							)
						)
					)
					(number "A22"
						(effects
							(font
								(size 1.27 1.27)
							)
						)
					)
				)
				(pin bidirectional line
					(at 0 -17.78 0)
					(length 5.08)
					(name "IO_L3P_T0_DQS_PUDC_B_14"
						(effects
							(font
								(size 1.27 1.27)
							)
						)
					)
					(number "B25"
						(effects
							(font
								(size 1.27 1.27)
							)
						)
					)
				)
				(pin bidirectional line
					(at 0 -20.32 0)
					(length 5.08)
					(name "IO_L3N_T0_DQS_EMCCLK_14"
						(effects
							(font
								(size 1.27 1.27)
							)
						)
					)
					(number "B26"
						(effects
							(font
								(size 1.27 1.27)
							)
						)
					)
				)
				(pin bidirectional line
					(at 0 -22.86 0)
					(length 5.08)
					(name "IO_L4P_T0_D04_14"
						(effects
							(font
								(size 1.27 1.27)
							)
						)
					)
					(number "A23"
						(effects
							(font
								(size 1.27 1.27)
							)
						)
					)
				)
				(pin bidirectional line
					(at 0 -25.4 0)
					(length 5.08)
					(name "IO_L4N_T0_D05_14"
						(effects
							(font
								(size 1.27 1.27)
							)
						)
					)
					(number "A24"
						(effects
							(font
								(size 1.27 1.27)
							)
						)
					)
				)
				(pin bidirectional line
					(at 0 -27.94 0)
					(length 5.08)
					(name "IO_L5P_T0_D06_14"
						(effects
							(font
								(size 1.27 1.27)
							)
						)
					)
					(number "D26"
						(effects
							(font
								(size 1.27 1.27)
							)
						)
					)
				)
				(pin bidirectional line
					(at 0 -30.48 0)
					(length 5.08)
					(name "IO_L5N_T0_D07_14"
						(effects
							(font
								(size 1.27 1.27)
							)
						)
					)
					(number "C26"
						(effects
							(font
								(size 1.27 1.27)
							)
						)
					)
				)
				(pin bidirectional line
					(at 0 -33.02 0)
					(length 5.08)
					(name "IO_L6P_T0_FCS_B_14"
						(effects
							(font
								(size 1.27 1.27)
							)
						)
					)
					(number "C23"
						(effects
							(font
								(size 1.27 1.27)
							)
						)
					)
				)
				(pin bidirectional line
					(at 0 -35.56 0)
					(length 5.08)
					(name "IO_L6N_T0_D08_VREF_14"
						(effects
							(font
								(size 1.27 1.27)
							)
						)
					)
					(number "C24"
						(effects
							(font
								(size 1.27 1.27)
							)
						)
					)
				)
				(pin bidirectional line
					(at 0 -38.1 0)
					(length 5.08)
					(name "IO_L7P_T1_D09_14"
						(effects
							(font
								(size 1.27 1.27)
							)
						)
					)
					(number "D21"
						(effects
							(font
								(size 1.27 1.27)
							)
						)
					)
				)
				(pin bidirectional line
					(at 0 -40.64 0)
					(length 5.08)
					(name "IO_L7N_T1_D10_14"
						(effects
							(font
								(size 1.27 1.27)
							)
						)
					)
					(number "C22"
						(effects
							(font
								(size 1.27 1.27)
							)
						)
					)
				)
				(pin bidirectional line
					(at 0 -43.18 0)
					(length 5.08)
					(name "IO_L8P_T1_D11_14"
						(effects
							(font
								(size 1.27 1.27)
							)
						)
					)
					(number "B20"
						(effects
							(font
								(size 1.27 1.27)
							)
						)
					)
				)
				(pin bidirectional line
					(at 0 -45.72 0)
					(length 5.08)
					(name "IO_L8N_T1_D12_14"
						(effects
							(font
								(size 1.27 1.27)
							)
						)
					)
					(number "A20"
						(effects
							(font
								(size 1.27 1.27)
							)
						)
					)
				)
				(pin bidirectional line
					(at 0 -48.26 0)
					(length 5.08)
					(name "IO_L9P_T1_DQS_14"
						(effects
							(font
								(size 1.27 1.27)
							)
						)
					)
					(number "E21"
						(effects
							(font
								(size 1.27 1.27)
							)
						)
					)
				)
				(pin bidirectional line
					(at 0 -50.8 0)
					(length 5.08)
					(name "IO_L9N_T1_DQS_D13_14"
						(effects
							(font
								(size 1.27 1.27)
							)
						)
					)
					(number "E22"
						(effects
							(font
								(size 1.27 1.27)
							)
						)
					)
				)
				(pin bidirectional line
					(at 0 -53.34 0)
					(length 5.08)
					(name "IO_L10P_T1_D14_14"
						(effects
							(font
								(size 1.27 1.27)
							)
						)
					)
					(number "C21"
						(effects
							(font
								(size 1.27 1.27)
							)
						)
					)
				)
				(pin bidirectional line
					(at 0 -55.88 0)
					(length 5.08)
					(name "IO_L10N_T1_D15_14"
						(effects
							(font
								(size 1.27 1.27)
							)
						)
					)
					(number "B21"
						(effects
							(font
								(size 1.27 1.27)
							)
						)
					)
				)
				(pin bidirectional line
					(at 0 -58.42 0)
					(length 5.08)
					(name "IO_L11P_T1_SRCC_14"
						(effects
							(font
								(size 1.27 1.27)
							)
						)
					)
					(number "D23"
						(effects
							(font
								(size 1.27 1.27)
							)
						)
					)
				)
				(pin bidirectional line
					(at 0 -60.96 0)
					(length 5.08)
					(name "IO_L11N_T1_SRCC_14"
						(effects
							(font
								(size 1.27 1.27)
							)
						)
					)
					(number "D24"
						(effects
							(font
								(size 1.27 1.27)
							)
						)
					)
				)
				(pin bidirectional line
					(at 0 -63.5 0)
					(length 5.08)
					(name "IO_L12P_T1_MRCC_14"
						(effects
							(font
								(size 1.27 1.27)
							)
						)
					)
					(number "F22"
						(effects
							(font
								(size 1.27 1.27)
							)
						)
					)
				)
				(pin bidirectional line
					(at 0 -66.04 0)
					(length 5.08)
					(name "IO_L12N_T1_MRCC_14"
						(effects
							(font
								(size 1.27 1.27)
							)
						)
					)
					(number "E23"
						(effects
							(font
								(size 1.27 1.27)
							)
						)
					)
				)
				(pin bidirectional line
					(at 0 -68.58 0)
					(length 5.08)
					(name "IO_L13P_T2_MRCC_14"
						(effects
							(font
								(size 1.27 1.27)
							)
						)
					)
					(number "G22"
						(effects
							(font
								(size 1.27 1.27)
							)
						)
					)
				)
				(pin bidirectional line
					(at 0 -71.12 0)
					(length 5.08)
					(name "IO_L13N_T2_MRCC_14"
						(effects
							(font
								(size 1.27 1.27)
							)
						)
					)
					(number "F23"
						(effects
							(font
								(size 1.27 1.27)
							)
						)
					)
				)
				(pin bidirectional line
					(at 0 -73.66 0)
					(length 5.08)
					(name "IO_L14P_T2_SRCC_14"
						(effects
							(font
								(size 1.27 1.27)
							)
						)
					)
					(number "G24"
						(effects
							(font
								(size 1.27 1.27)
							)
						)
					)
				)
				(pin bidirectional line
					(at 0 -76.2 0)
					(length 5.08)
					(name "IO_L14N_T2_SRCC_14"
						(effects
							(font
								(size 1.27 1.27)
							)
						)
					)
					(number "F24"
						(effects
							(font
								(size 1.27 1.27)
							)
						)
					)
				)
				(pin bidirectional line
					(at 0 -78.74 0)
					(length 5.08)
					(name "IO_L15P_T2_DQS_RDWR_B_14"
						(effects
							(font
								(size 1.27 1.27)
							)
						)
					)
					(number "E25"
						(effects
							(font
								(size 1.27 1.27)
							)
						)
					)
				)
				(pin bidirectional line
					(at 0 -81.28 0)
					(length 5.08)
					(name "IO_L15N_T2_DQS_DOUT_CSO_B_14"
						(effects
							(font
								(size 1.27 1.27)
							)
						)
					)
					(number "D25"
						(effects
							(font
								(size 1.27 1.27)
							)
						)
					)
				)
				(pin bidirectional line
					(at 0 -83.82 0)
					(length 5.08)
					(name "IO_L16P_T2_CSI_B_14"
						(effects
							(font
								(size 1.27 1.27)
							)
						)
					)
					(number "G25"
						(effects
							(font
								(size 1.27 1.27)
							)
						)
					)
				)
				(pin bidirectional line
					(at 0 -86.36 0)
					(length 5.08)
					(name "IO_L16N_T2_A15_D31_14"
						(effects
							(font
								(size 1.27 1.27)
							)
						)
					)
					(number "G26"
						(effects
							(font
								(size 1.27 1.27)
							)
						)
					)
				)
				(pin bidirectional line
					(at 0 -88.9 0)
					(length 5.08)
					(name "IO_L17P_T2_A14_D30_14"
						(effects
							(font
								(size 1.27 1.27)
							)
						)
					)
					(number "F25"
						(effects
							(font
								(size 1.27 1.27)
							)
						)
					)
				)
				(pin bidirectional line
					(at 0 -91.44 0)
					(length 5.08)
					(name "IO_L17N_T2_A13_D29_14"
						(effects
							(font
								(size 1.27 1.27)
							)
						)
					)
					(number "E26"
						(effects
							(font
								(size 1.27 1.27)
							)
						)
					)
				)
				(pin bidirectional line
					(at 0 -93.98 0)
					(length 5.08)
					(name "IO_L18P_T2_A12_D28_14"
						(effects
							(font
								(size 1.27 1.27)
							)
						)
					)
					(number "J26"
						(effects
							(font
								(size 1.27 1.27)
							)
						)
					)
				)
				(pin bidirectional line
					(at 0 -96.52 0)
					(length 5.08)
					(name "IO_L18N_T2_A11_D27_14"
						(effects
							(font
								(size 1.27 1.27)
							)
						)
					)
					(number "H26"
						(effects
							(font
								(size 1.27 1.27)
							)
						)
					)
				)
				(pin bidirectional line
					(at 0 -99.06 0)
					(length 5.08)
					(name "IO_L19P_T3_A10_D26_14"
						(effects
							(font
								(size 1.27 1.27)
							)
						)
					)
					(number "H21"
						(effects
							(font
								(size 1.27 1.27)
							)
						)
					)
				)
				(pin bidirectional line
					(at 0 -101.6 0)
					(length 5.08)
					(name "IO_L19N_T3_A09_D25_VREF_14"
						(effects
							(font
								(size 1.27 1.27)
							)
						)
					)
					(number "G21"
						(effects
							(font
								(size 1.27 1.27)
							)
						)
					)
				)
				(pin bidirectional line
					(at 0 -104.14 0)
					(length 5.08)
					(name "IO_L20P_T3_A08_D24_14"
						(effects
							(font
								(size 1.27 1.27)
							)
						)
					)
					(number "H23"
						(effects
							(font
								(size 1.27 1.27)
							)
						)
					)
				)
				(pin bidirectional line
					(at 0 -106.68 0)
					(length 5.08)
					(name "IO_L20N_T3_A07_D23_14"
						(effects
							(font
								(size 1.27 1.27)
							)
						)
					)
					(number "H24"
						(effects
							(font
								(size 1.27 1.27)
							)
						)
					)
				)
				(pin bidirectional line
					(at 0 -109.22 0)
					(length 5.08)
					(name "IO_L21P_T3_DQS_14"
						(effects
							(font
								(size 1.27 1.27)
							)
						)
					)
					(number "J21"
						(effects
							(font
								(size 1.27 1.27)
							)
						)
					)
				)
				(pin bidirectional line
					(at 0 -111.76 0)
					(length 5.08)
					(name "IO_L21N_T3_DQS_A06_D22_14"
						(effects
							(font
								(size 1.27 1.27)
							)
						)
					)
					(number "H22"
						(effects
							(font
								(size 1.27 1.27)
							)
						)
					)
				)
				(pin bidirectional line
					(at 0 -114.3 0)
					(length 5.08)
					(name "IO_L22P_T3_A05_D21_14"
						(effects
							(font
								(size 1.27 1.27)
							)
						)
					)
					(number "J24"
						(effects
							(font
								(size 1.27 1.27)
							)
						)
					)
				)
				(pin bidirectional line
					(at 0 -116.84 0)
					(length 5.08)
					(name "IO_L22N_T3_A04_D20_14"
						(effects
							(font
								(size 1.27 1.27)
							)
						)
					)
					(number "J25"
						(effects
							(font
								(size 1.27 1.27)
							)
						)
					)
				)
				(pin bidirectional line
					(at 0 -119.38 0)
					(length 5.08)
					(name "IO_L23P_T3_A03_D19_14"
						(effects
							(font
								(size 1.27 1.27)
							)
						)
					)
					(number "L22"
						(effects
							(font
								(size 1.27 1.27)
							)
						)
					)
				)
				(pin bidirectional line
					(at 0 -121.92 0)
					(length 5.08)
					(name "IO_L23N_T3_A02_D18_14"
						(effects
							(font
								(size 1.27 1.27)
							)
						)
					)
					(number "K22"
						(effects
							(font
								(size 1.27 1.27)
							)
						)
					)
				)
				(pin bidirectional line
					(at 0 -124.46 0)
					(length 5.08)
					(name "IO_L24P_T3_A01_D17_14"
						(effects
							(font
								(size 1.27 1.27)
							)
						)
					)
					(number "K23"
						(effects
							(font
								(size 1.27 1.27)
							)
						)
					)
				)
				(pin bidirectional line
					(at 0 -127 0)
					(length 5.08)
					(name "IO_L24N_T3_A00_D16_14"
						(effects
							(font
								(size 1.27 1.27)
							)
						)
					)
					(number "J23"
						(effects
							(font
								(size 1.27 1.27)
							)
						)
					)
				)
				(pin bidirectional line
					(at 0 -129.54 0)
					(length 5.08)
					(name "IO_25_14"
						(effects
							(font
								(size 1.27 1.27)
							)
						)
					)
					(number "L23"
						(effects
							(font
								(size 1.27 1.27)
							)
						)
					)
				)
			)
			(symbol "XC7K160T-FFG676_4_1"
				(rectangle
					(start 5.08 2.54)
					(end 40.64 -132.08)
					(stroke
						(width 0.254)
						(type default)
					)
					(fill
						(type background)
					)
				)
				(polyline
					(pts
						(xy 30.48 -3.81) (xy 38.1 -3.81) (xy 38.1 -130.81) (xy 30.48 -130.81)
					)
					(stroke
						(width 0.254)
						(type default)
					)
					(fill
						(type background)
					)
				)
				(text "BANK 15"
					(at 31.75 -1.27 0)
					(effects
						(font
							(size 1.27 1.27)
							(thickness 0.15)
						)
						(justify left bottom)
					)
				)
				(pin power_in line
					(at 0 0 0)
					(length 5.08)
					(name "VCCO_15"
						(effects
							(font
								(size 1.27 1.27)
							)
						)
					)
					(number "B18"
						(effects
							(font
								(size 1.27 1.27)
							)
						)
					)
				)
				(pin passive line
					(at 0 0 0)
					(length 5.08)
					(hide yes)
					(name "VCCO_15"
						(effects
							(font
								(size 1.27 1.27)
							)
						)
					)
					(number "E19"
						(effects
							(font
								(size 1.27 1.27)
							)
						)
					)
				)
				(pin passive line
					(at 0 0 0)
					(length 5.08)
					(hide yes)
					(name "VCCO_15"
						(effects
							(font
								(size 1.27 1.27)
							)
						)
					)
					(number "F16"
						(effects
							(font
								(size 1.27 1.27)
							)
						)
					)
				)
				(pin passive line
					(at 0 0 0)
					(length 5.08)
					(hide yes)
					(name "VCCO_15"
						(effects
							(font
								(size 1.27 1.27)
							)
						)
					)
					(number "H20"
						(effects
							(font
								(size 1.27 1.27)
							)
						)
					)
				)
				(pin passive line
					(at 0 0 0)
					(length 5.08)
					(hide yes)
					(name "VCCO_15"
						(effects
							(font
								(size 1.27 1.27)
							)
						)
					)
					(number "J17"
						(effects
							(font
								(size 1.27 1.27)
							)
						)
					)
				)
				(pin passive line
					(at 0 0 0)
					(length 5.08)
					(hide yes)
					(name "VCCO_15"
						(effects
							(font
								(size 1.27 1.27)
							)
						)
					)
					(number "M18"
						(effects
							(font
								(size 1.27 1.27)
							)
						)
					)
				)
				(pin bidirectional line
					(at 0 -5.08 0)
					(length 5.08)
					(name "IO_0_15"
						(effects
							(font
								(size 1.27 1.27)
							)
						)
					)
					(number "K15"
						(effects
							(font
								(size 1.27 1.27)
							)
						)
					)
				)
				(pin bidirectional line
					(at 0 -7.62 0)
					(length 5.08)
					(name "IO_L1P_T0_AD0P_15"
						(effects
							(font
								(size 1.27 1.27)
							)
						)
					)
					(number "C16"
						(effects
							(font
								(size 1.27 1.27)
							)
						)
					)
				)
				(pin bidirectional line
					(at 0 -10.16 0)
					(length 5.08)
					(name "IO_L1N_T0_AD0N_15"
						(effects
							(font
								(size 1.27 1.27)
							)
						)
					)
					(number "B16"
						(effects
							(font
								(size 1.27 1.27)
							)
						)
					)
				)
				(pin bidirectional line
					(at 0 -12.7 0)
					(length 5.08)
					(name "IO_L2P_T0_AD8P_15"
						(effects
							(font
								(size 1.27 1.27)
							)
						)
					)
					(number "A18"
						(effects
							(font
								(size 1.27 1.27)
							)
						)
					)
				)
				(pin bidirectional line
					(at 0 -15.24 0)
					(length 5.08)
					(name "IO_L2N_T0_AD8N_15"
						(effects
							(font
								(size 1.27 1.27)
							)
						)
					)
					(number "A19"
						(effects
							(font
								(size 1.27 1.27)
							)
						)
					)
				)
				(pin bidirectional line
					(at 0 -17.78 0)
					(length 5.08)
					(name "IO_L3P_T0_DQS_AD1P_15"
						(effects
							(font
								(size 1.27 1.27)
							)
						)
					)
					(number "B17"
						(effects
							(font
								(size 1.27 1.27)
							)
						)
					)
				)
				(pin bidirectional line
					(at 0 -20.32 0)
					(length 5.08)
					(name "IO_L3N_T0_DQS_AD1N_15"
						(effects
							(font
								(size 1.27 1.27)
							)
						)
					)
					(number "A17"
						(effects
							(font
								(size 1.27 1.27)
							)
						)
					)
				)
				(pin bidirectional line
					(at 0 -22.86 0)
					(length 5.08)
					(name "IO_L4P_T0_AD9P_15"
						(effects
							(font
								(size 1.27 1.27)
							)
						)
					)
					(number "C19"
						(effects
							(font
								(size 1.27 1.27)
							)
						)
					)
				)
				(pin bidirectional line
					(at 0 -25.4 0)
					(length 5.08)
					(name "IO_L4N_T0_AD9N_15"
						(effects
							(font
								(size 1.27 1.27)
							)
						)
					)
					(number "B19"
						(effects
							(font
								(size 1.27 1.27)
							)
						)
					)
				)
				(pin bidirectional line
					(at 0 -27.94 0)
					(length 5.08)
					(name "IO_L5P_T0_AD2P_15"
						(effects
							(font
								(size 1.27 1.27)
							)
						)
					)
					(number "C17"
						(effects
							(font
								(size 1.27 1.27)
							)
						)
					)
				)
				(pin bidirectional line
					(at 0 -30.48 0)
					(length 5.08)
					(name "IO_L5N_T0_AD2N_15"
						(effects
							(font
								(size 1.27 1.27)
							)
						)
					)
					(number "C18"
						(effects
							(font
								(size 1.27 1.27)
							)
						)
					)
				)
				(pin bidirectional line
					(at 0 -33.02 0)
					(length 5.08)
					(name "IO_L6P_T0_15"
						(effects
							(font
								(size 1.27 1.27)
							)
						)
					)
					(number "D15"
						(effects
							(font
								(size 1.27 1.27)
							)
						)
					)
				)
				(pin bidirectional line
					(at 0 -35.56 0)
					(length 5.08)
					(name "IO_L6N_T0_VREF_15"
						(effects
							(font
								(size 1.27 1.27)
							)
						)
					)
					(number "D16"
						(effects
							(font
								(size 1.27 1.27)
							)
						)
					)
				)
				(pin bidirectional line
					(at 0 -38.1 0)
					(length 5.08)
					(name "IO_L7P_T1_AD10P_15"
						(effects
							(font
								(size 1.27 1.27)
							)
						)
					)
					(number "H16"
						(effects
							(font
								(size 1.27 1.27)
							)
						)
					)
				)
				(pin bidirectional line
					(at 0 -40.64 0)
					(length 5.08)
					(name "IO_L7N_T1_AD10N_15"
						(effects
							(font
								(size 1.27 1.27)
							)
						)
					)
					(number "G16"
						(effects
							(font
								(size 1.27 1.27)
							)
						)
					)
				)
				(pin bidirectional line
					(at 0 -43.18 0)
					(length 5.08)
					(name "IO_L8P_T1_AD3P_15"
						(effects
							(font
								(size 1.27 1.27)
							)
						)
					)
					(number "G15"
						(effects
							(font
								(size 1.27 1.27)
							)
						)
					)
				)
				(pin bidirectional line
					(at 0 -45.72 0)
					(length 5.08)
					(name "IO_L8N_T1_AD3N_15"
						(effects
							(font
								(size 1.27 1.27)
							)
						)
					)
					(number "F15"
						(effects
							(font
								(size 1.27 1.27)
							)
						)
					)
				)
				(pin bidirectional line
					(at 0 -48.26 0)
					(length 5.08)
					(name "IO_L9P_T1_DQS_AD11P_15"
						(effects
							(font
								(size 1.27 1.27)
							)
						)
					)
					(number "J15"
						(effects
							(font
								(size 1.27 1.27)
							)
						)
					)
				)
				(pin bidirectional line
					(at 0 -50.8 0)
					(length 5.08)
					(name "IO_L9N_T1_DQS_AD11N_15"
						(effects
							(font
								(size 1.27 1.27)
							)
						)
					)
					(number "J16"
						(effects
							(font
								(size 1.27 1.27)
							)
						)
					)
				)
				(pin bidirectional line
					(at 0 -53.34 0)
					(length 5.08)
					(name "IO_L10P_T1_AD4P_15"
						(effects
							(font
								(size 1.27 1.27)
							)
						)
					)
					(number "E15"
						(effects
							(font
								(size 1.27 1.27)
							)
						)
					)
				)
				(pin bidirectional line
					(at 0 -55.88 0)
					(length 5.08)
					(name "IO_L10N_T1_AD4N_15"
						(effects
							(font
								(size 1.27 1.27)
							)
						)
					)
					(number "E16"
						(effects
							(font
								(size 1.27 1.27)
							)
						)
					)
				)
				(pin bidirectional line
					(at 0 -58.42 0)
					(length 5.08)
					(name "IO_L11P_T1_SRCC_AD12P_15"
						(effects
							(font
								(size 1.27 1.27)
							)
						)
					)
					(number "G17"
						(effects
							(font
								(size 1.27 1.27)
							)
						)
					)
				)
				(pin bidirectional line
					(at 0 -60.96 0)
					(length 5.08)
					(name "IO_L11N_T1_SRCC_AD12N_15"
						(effects
							(font
								(size 1.27 1.27)
							)
						)
					)
					(number "F18"
						(effects
							(font
								(size 1.27 1.27)
							)
						)
					)
				)
				(pin bidirectional line
					(at 0 -63.5 0)
					(length 5.08)
					(name "IO_L12P_T1_MRCC_AD5P_15"
						(effects
							(font
								(size 1.27 1.27)
							)
						)
					)
					(number "F17"
						(effects
							(font
								(size 1.27 1.27)
							)
						)
					)
				)
				(pin bidirectional line
					(at 0 -66.04 0)
					(length 5.08)
					(name "IO_L12N_T1_MRCC_AD5N_15"
						(effects
							(font
								(size 1.27 1.27)
							)
						)
					)
					(number "E17"
						(effects
							(font
								(size 1.27 1.27)
							)
						)
					)
				)
				(pin bidirectional line
					(at 0 -68.58 0)
					(length 5.08)
					(name "IO_L13P_T2_MRCC_15"
						(effects
							(font
								(size 1.27 1.27)
							)
						)
					)
					(number "E18"
						(effects
							(font
								(size 1.27 1.27)
							)
						)
					)
				)
				(pin bidirectional line
					(at 0 -71.12 0)
					(length 5.08)
					(name "IO_L13N_T2_MRCC_15"
						(effects
							(font
								(size 1.27 1.27)
							)
						)
					)
					(number "D18"
						(effects
							(font
								(size 1.27 1.27)
							)
						)
					)
				)
				(pin bidirectional line
					(at 0 -73.66 0)
					(length 5.08)
					(name "IO_L14P_T2_SRCC_15"
						(effects
							(font
								(size 1.27 1.27)
							)
						)
					)
					(number "H17"
						(effects
							(font
								(size 1.27 1.27)
							)
						)
					)
				)
				(pin bidirectional line
					(at 0 -76.2 0)
					(length 5.08)
					(name "IO_L14N_T2_SRCC_15"
						(effects
							(font
								(size 1.27 1.27)
							)
						)
					)
					(number "H18"
						(effects
							(font
								(size 1.27 1.27)
							)
						)
					)
				)
				(pin bidirectional line
					(at 0 -78.74 0)
					(length 5.08)
					(name "IO_L15P_T2_DQS_15"
						(effects
							(font
								(size 1.27 1.27)
							)
						)
					)
					(number "D19"
						(effects
							(font
								(size 1.27 1.27)
							)
						)
					)
				)
				(pin bidirectional line
					(at 0 -81.28 0)
					(length 5.08)
					(name "IO_L15N_T2_DQS_ADV_B_15"
						(effects
							(font
								(size 1.27 1.27)
							)
						)
					)
					(number "D20"
						(effects
							(font
								(size 1.27 1.27)
							)
						)
					)
				)
				(pin bidirectional line
					(at 0 -83.82 0)
					(length 5.08)
					(name "IO_L16P_T2_A28_15"
						(effects
							(font
								(size 1.27 1.27)
							)
						)
					)
					(number "G19"
						(effects
							(font
								(size 1.27 1.27)
							)
						)
					)
				)
				(pin bidirectional line
					(at 0 -86.36 0)
					(length 5.08)
					(name "IO_L16N_T2_A27_15"
						(effects
							(font
								(size 1.27 1.27)
							)
						)
					)
					(number "F20"
						(effects
							(font
								(size 1.27 1.27)
							)
						)
					)
				)
				(pin bidirectional line
					(at 0 -88.9 0)
					(length 5.08)
					(name "IO_L17P_T2_A26_15"
						(effects
							(font
								(size 1.27 1.27)
							)
						)
					)
					(number "F19"
						(effects
							(font
								(size 1.27 1.27)
							)
						)
					)
				)
				(pin bidirectional line
					(at 0 -91.44 0)
					(length 5.08)
					(name "IO_L17N_T2_A25_15"
						(effects
							(font
								(size 1.27 1.27)
							)
						)
					)
					(number "E20"
						(effects
							(font
								(size 1.27 1.27)
							)
						)
					)
				)
				(pin bidirectional line
					(at 0 -93.98 0)
					(length 5.08)
					(name "IO_L18P_T2_A24_15"
						(effects
							(font
								(size 1.27 1.27)
							)
						)
					)
					(number "H19"
						(effects
							(font
								(size 1.27 1.27)
							)
						)
					)
				)
				(pin bidirectional line
					(at 0 -96.52 0)
					(length 5.08)
					(name "IO_L18N_T2_A23_15"
						(effects
							(font
								(size 1.27 1.27)
							)
						)
					)
					(number "G20"
						(effects
							(font
								(size 1.27 1.27)
							)
						)
					)
				)
				(pin bidirectional line
					(at 0 -99.06 0)
					(length 5.08)
					(name "IO_L19P_T3_A22_15"
						(effects
							(font
								(size 1.27 1.27)
							)
						)
					)
					(number "K20"
						(effects
							(font
								(size 1.27 1.27)
							)
						)
					)
				)
				(pin bidirectional line
					(at 0 -101.6 0)
					(length 5.08)
					(name "IO_L19N_T3_A21_VREF_15"
						(effects
							(font
								(size 1.27 1.27)
							)
						)
					)
					(number "J20"
						(effects
							(font
								(size 1.27 1.27)
							)
						)
					)
				)
				(pin bidirectional line
					(at 0 -104.14 0)
					(length 5.08)
					(name "IO_L20P_T3_A20_15"
						(effects
							(font
								(size 1.27 1.27)
							)
						)
					)
					(number "J18"
						(effects
							(font
								(size 1.27 1.27)
							)
						)
					)
				)
				(pin bidirectional line
					(at 0 -106.68 0)
					(length 5.08)
					(name "IO_L20N_T3_A19_15"
						(effects
							(font
								(size 1.27 1.27)
							)
						)
					)
					(number "J19"
						(effects
							(font
								(size 1.27 1.27)
							)
						)
					)
				)
				(pin bidirectional line
					(at 0 -109.22 0)
					(length 5.08)
					(name "IO_L21P_T3_DQS_15"
						(effects
							(font
								(size 1.27 1.27)
							)
						)
					)
					(number "L19"
						(effects
							(font
								(size 1.27 1.27)
							)
						)
					)
				)
				(pin bidirectional line
					(at 0 -111.76 0)
					(length 5.08)
					(name "IO_L21N_T3_DQS_A18_15"
						(effects
							(font
								(size 1.27 1.27)
							)
						)
					)
					(number "L20"
						(effects
							(font
								(size 1.27 1.27)
							)
						)
					)
				)
				(pin bidirectional line
					(at 0 -114.3 0)
					(length 5.08)
					(name "IO_L22P_T3_A17_15"
						(effects
							(font
								(size 1.27 1.27)
							)
						)
					)
					(number "K16"
						(effects
							(font
								(size 1.27 1.27)
							)
						)
					)
				)
				(pin bidirectional line
					(at 0 -116.84 0)
					(length 5.08)
					(name "IO_L22N_T3_A16_15"
						(effects
							(font
								(size 1.27 1.27)
							)
						)
					)
					(number "K17"
						(effects
							(font
								(size 1.27 1.27)
							)
						)
					)
				)
				(pin bidirectional line
					(at 0 -119.38 0)
					(length 5.08)
					(name "IO_L23P_T3_FOE_B_15"
						(effects
							(font
								(size 1.27 1.27)
							)
						)
					)
					(number "M17"
						(effects
							(font
								(size 1.27 1.27)
							)
						)
					)
				)
				(pin bidirectional line
					(at 0 -121.92 0)
					(length 5.08)
					(name "IO_L23N_T3_FWE_B_15"
						(effects
							(font
								(size 1.27 1.27)
							)
						)
					)
					(number "L18"
						(effects
							(font
								(size 1.27 1.27)
							)
						)
					)
				)
				(pin bidirectional line
					(at 0 -124.46 0)
					(length 5.08)
					(name "IO_L24P_T3_RS1_15"
						(effects
							(font
								(size 1.27 1.27)
							)
						)
					)
					(number "L17"
						(effects
							(font
								(size 1.27 1.27)
							)
						)
					)
				)
				(pin bidirectional line
					(at 0 -127 0)
					(length 5.08)
					(name "IO_L24N_T3_RS0_15"
						(effects
							(font
								(size 1.27 1.27)
							)
						)
					)
					(number "K18"
						(effects
							(font
								(size 1.27 1.27)
							)
						)
					)
				)
				(pin bidirectional line
					(at 0 -129.54 0)
					(length 5.08)
					(name "IO_25_15"
						(effects
							(font
								(size 1.27 1.27)
							)
						)
					)
					(number "M16"
						(effects
							(font
								(size 1.27 1.27)
							)
						)
					)
				)
			)
			(symbol "XC7K160T-FFG676_5_1"
				(rectangle
					(start 5.08 -132.08)
					(end 33.02 2.54)
					(stroke
						(width 0.254)
						(type default)
					)
					(fill
						(type background)
					)
				)
				(polyline
					(pts
						(xy 22.86 -3.81) (xy 30.48 -3.81) (xy 30.48 -130.81) (xy 22.86 -130.81)
					)
					(stroke
						(width 0.254)
						(type default)
					)
					(fill
						(type background)
					)
				)
				(text "BANK 16"
					(at 24.13 -1.27 0)
					(effects
						(font
							(size 1.27 1.27)
							(thickness 0.15)
						)
						(justify left bottom)
					)
				)
				(pin power_in line
					(at 0 0 0)
					(length 5.08)
					(name "VCCO_16"
						(effects
							(font
								(size 1.27 1.27)
							)
						)
					)
					(number "A11"
						(effects
							(font
								(size 1.27 1.27)
							)
						)
					)
				)
				(pin passive line
					(at 0 0 0)
					(length 5.08)
					(hide yes)
					(name "VCCO_16"
						(effects
							(font
								(size 1.27 1.27)
							)
						)
					)
					(number "B8"
						(effects
							(font
								(size 1.27 1.27)
							)
						)
					)
				)
				(pin passive line
					(at 0 0 0)
					(length 5.08)
					(hide yes)
					(name "VCCO_16"
						(effects
							(font
								(size 1.27 1.27)
							)
						)
					)
					(number "C15"
						(effects
							(font
								(size 1.27 1.27)
							)
						)
					)
				)
				(pin passive line
					(at 0 0 0)
					(length 5.08)
					(hide yes)
					(name "VCCO_16"
						(effects
							(font
								(size 1.27 1.27)
							)
						)
					)
					(number "D12"
						(effects
							(font
								(size 1.27 1.27)
							)
						)
					)
				)
				(pin passive line
					(at 0 0 0)
					(length 5.08)
					(hide yes)
					(name "VCCO_16"
						(effects
							(font
								(size 1.27 1.27)
							)
						)
					)
					(number "E9"
						(effects
							(font
								(size 1.27 1.27)
							)
						)
					)
				)
				(pin passive line
					(at 0 0 0)
					(length 5.08)
					(hide yes)
					(name "VCCO_16"
						(effects
							(font
								(size 1.27 1.27)
							)
						)
					)
					(number "G13"
						(effects
							(font
								(size 1.27 1.27)
							)
						)
					)
				)
				(pin passive line
					(at 0 0 0)
					(length 5.08)
					(hide yes)
					(name "VCCO_16"
						(effects
							(font
								(size 1.27 1.27)
							)
						)
					)
					(number "H10"
						(effects
							(font
								(size 1.27 1.27)
							)
						)
					)
				)
				(pin bidirectional line
					(at 0 -5.08 0)
					(length 5.08)
					(name "IO_0_16"
						(effects
							(font
								(size 1.27 1.27)
							)
						)
					)
					(number "J8"
						(effects
							(font
								(size 1.27 1.27)
							)
						)
					)
				)
				(pin bidirectional line
					(at 0 -7.62 0)
					(length 5.08)
					(name "IO_L1P_T0_16"
						(effects
							(font
								(size 1.27 1.27)
							)
						)
					)
					(number "H9"
						(effects
							(font
								(size 1.27 1.27)
							)
						)
					)
				)
				(pin bidirectional line
					(at 0 -10.16 0)
					(length 5.08)
					(name "IO_L1N_T0_16"
						(effects
							(font
								(size 1.27 1.27)
							)
						)
					)
					(number "H8"
						(effects
							(font
								(size 1.27 1.27)
							)
						)
					)
				)
				(pin bidirectional line
					(at 0 -12.7 0)
					(length 5.08)
					(name "IO_L2P_T0_16"
						(effects
							(font
								(size 1.27 1.27)
							)
						)
					)
					(number "G10"
						(effects
							(font
								(size 1.27 1.27)
							)
						)
					)
				)
				(pin bidirectional line
					(at 0 -15.24 0)
					(length 5.08)
					(name "IO_L2N_T0_16"
						(effects
							(font
								(size 1.27 1.27)
							)
						)
					)
					(number "G9"
						(effects
							(font
								(size 1.27 1.27)
							)
						)
					)
				)
				(pin bidirectional line
					(at 0 -17.78 0)
					(length 5.08)
					(name "IO_L3P_T0_DQS_16"
						(effects
							(font
								(size 1.27 1.27)
							)
						)
					)
					(number "J13"
						(effects
							(font
								(size 1.27 1.27)
							)
						)
					)
				)
				(pin bidirectional line
					(at 0 -20.32 0)
					(length 5.08)
					(name "IO_L3N_T0_DQS_16"
						(effects
							(font
								(size 1.27 1.27)
							)
						)
					)
					(number "H13"
						(effects
							(font
								(size 1.27 1.27)
							)
						)
					)
				)
				(pin bidirectional line
					(at 0 -22.86 0)
					(length 5.08)
					(name "IO_L4P_T0_16"
						(effects
							(font
								(size 1.27 1.27)
							)
						)
					)
					(number "J11"
						(effects
							(font
								(size 1.27 1.27)
							)
						)
					)
				)
				(pin bidirectional line
					(at 0 -25.4 0)
					(length 5.08)
					(name "IO_L4N_T0_16"
						(effects
							(font
								(size 1.27 1.27)
							)
						)
					)
					(number "J10"
						(effects
							(font
								(size 1.27 1.27)
							)
						)
					)
				)
				(pin bidirectional line
					(at 0 -27.94 0)
					(length 5.08)
					(name "IO_L5P_T0_16"
						(effects
							(font
								(size 1.27 1.27)
							)
						)
					)
					(number "H14"
						(effects
							(font
								(size 1.27 1.27)
							)
						)
					)
				)
				(pin bidirectional line
					(at 0 -30.48 0)
					(length 5.08)
					(name "IO_L5N_T0_16"
						(effects
							(font
								(size 1.27 1.27)
							)
						)
					)
					(number "G14"
						(effects
							(font
								(size 1.27 1.27)
							)
						)
					)
				)
				(pin bidirectional line
					(at 0 -33.02 0)
					(length 5.08)
					(name "IO_L6P_T0_16"
						(effects
							(font
								(size 1.27 1.27)
							)
						)
					)
					(number "H12"
						(effects
							(font
								(size 1.27 1.27)
							)
						)
					)
				)
				(pin bidirectional line
					(at 0 -35.56 0)
					(length 5.08)
					(name "IO_L6N_T0_VREF_16"
						(effects
							(font
								(size 1.27 1.27)
							)
						)
					)
					(number "H11"
						(effects
							(font
								(size 1.27 1.27)
							)
						)
					)
				)
				(pin bidirectional line
					(at 0 -38.1 0)
					(length 5.08)
					(name "IO_L7P_T1_16"
						(effects
							(font
								(size 1.27 1.27)
							)
						)
					)
					(number "F9"
						(effects
							(font
								(size 1.27 1.27)
							)
						)
					)
				)
				(pin bidirectional line
					(at 0 -40.64 0)
					(length 5.08)
					(name "IO_L7N_T1_16"
						(effects
							(font
								(size 1.27 1.27)
							)
						)
					)
					(number "F8"
						(effects
							(font
								(size 1.27 1.27)
							)
						)
					)
				)
				(pin bidirectional line
					(at 0 -43.18 0)
					(length 5.08)
					(name "IO_L8P_T1_16"
						(effects
							(font
								(size 1.27 1.27)
							)
						)
					)
					(number "D9"
						(effects
							(font
								(size 1.27 1.27)
							)
						)
					)
				)
				(pin bidirectional line
					(at 0 -45.72 0)
					(length 5.08)
					(name "IO_L8N_T1_16"
						(effects
							(font
								(size 1.27 1.27)
							)
						)
					)
					(number "D8"
						(effects
							(font
								(size 1.27 1.27)
							)
						)
					)
				)
				(pin bidirectional line
					(at 0 -48.26 0)
					(length 5.08)
					(name "IO_L9P_T1_DQS_16"
						(effects
							(font
								(size 1.27 1.27)
							)
						)
					)
					(number "A9"
						(effects
							(font
								(size 1.27 1.27)
							)
						)
					)
				)
				(pin bidirectional line
					(at 0 -50.8 0)
					(length 5.08)
					(name "IO_L9N_T1_DQS_16"
						(effects
							(font
								(size 1.27 1.27)
							)
						)
					)
					(number "A8"
						(effects
							(font
								(size 1.27 1.27)
							)
						)
					)
				)
				(pin bidirectional line
					(at 0 -53.34 0)
					(length 5.08)
					(name "IO_L10P_T1_16"
						(effects
							(font
								(size 1.27 1.27)
							)
						)
					)
					(number "C9"
						(effects
							(font
								(size 1.27 1.27)
							)
						)
					)
				)
				(pin bidirectional line
					(at 0 -55.88 0)
					(length 5.08)
					(name "IO_L10N_T1_16"
						(effects
							(font
								(size 1.27 1.27)
							)
						)
					)
					(number "B9"
						(effects
							(font
								(size 1.27 1.27)
							)
						)
					)
				)
				(pin bidirectional line
					(at 0 -58.42 0)
					(length 5.08)
					(name "IO_L11P_T1_SRCC_16"
						(effects
							(font
								(size 1.27 1.27)
							)
						)
					)
					(number "G11"
						(effects
							(font
								(size 1.27 1.27)
							)
						)
					)
				)
				(pin bidirectional line
					(at 0 -60.96 0)
					(length 5.08)
					(name "IO_L11N_T1_SRCC_16"
						(effects
							(font
								(size 1.27 1.27)
							)
						)
					)
					(number "F10"
						(effects
							(font
								(size 1.27 1.27)
							)
						)
					)
				)
				(pin bidirectional line
					(at 0 -63.5 0)
					(length 5.08)
					(name "IO_L12P_T1_MRCC_16"
						(effects
							(font
								(size 1.27 1.27)
							)
						)
					)
					(number "E10"
						(effects
							(font
								(size 1.27 1.27)
							)
						)
					)
				)
				(pin bidirectional line
					(at 0 -66.04 0)
					(length 5.08)
					(name "IO_L12N_T1_MRCC_16"
						(effects
							(font
								(size 1.27 1.27)
							)
						)
					)
					(number "D10"
						(effects
							(font
								(size 1.27 1.27)
							)
						)
					)
				)
				(pin bidirectional line
					(at 0 -68.58 0)
					(length 5.08)
					(name "IO_L13P_T2_MRCC_16"
						(effects
							(font
								(size 1.27 1.27)
							)
						)
					)
					(number "C12"
						(effects
							(font
								(size 1.27 1.27)
							)
						)
					)
				)
				(pin bidirectional line
					(at 0 -71.12 0)
					(length 5.08)
					(name "IO_L13N_T2_MRCC_16"
						(effects
							(font
								(size 1.27 1.27)
							)
						)
					)
					(number "C11"
						(effects
							(font
								(size 1.27 1.27)
							)
						)
					)
				)
				(pin bidirectional line
					(at 0 -73.66 0)
					(length 5.08)
					(name "IO_L14P_T2_SRCC_16"
						(effects
							(font
								(size 1.27 1.27)
							)
						)
					)
					(number "E11"
						(effects
							(font
								(size 1.27 1.27)
							)
						)
					)
				)
				(pin bidirectional line
					(at 0 -76.2 0)
					(length 5.08)
					(name "IO_L14N_T2_SRCC_16"
						(effects
							(font
								(size 1.27 1.27)
							)
						)
					)
					(number "D11"
						(effects
							(font
								(size 1.27 1.27)
							)
						)
					)
				)
				(pin bidirectional line
					(at 0 -78.74 0)
					(length 5.08)
					(name "IO_L15P_T2_DQS_16"
						(effects
							(font
								(size 1.27 1.27)
							)
						)
					)
					(number "F14"
						(effects
							(font
								(size 1.27 1.27)
							)
						)
					)
				)
				(pin bidirectional line
					(at 0 -81.28 0)
					(length 5.08)
					(name "IO_L15N_T2_DQS_16"
						(effects
							(font
								(size 1.27 1.27)
							)
						)
					)
					(number "F13"
						(effects
							(font
								(size 1.27 1.27)
							)
						)
					)
				)
				(pin bidirectional line
					(at 0 -83.82 0)
					(length 5.08)
					(name "IO_L16P_T2_16"
						(effects
							(font
								(size 1.27 1.27)
							)
						)
					)
					(number "G12"
						(effects
							(font
								(size 1.27 1.27)
							)
						)
					)
				)
				(pin bidirectional line
					(at 0 -86.36 0)
					(length 5.08)
					(name "IO_L16N_T2_16"
						(effects
							(font
								(size 1.27 1.27)
							)
						)
					)
					(number "F12"
						(effects
							(font
								(size 1.27 1.27)
							)
						)
					)
				)
				(pin bidirectional line
					(at 0 -88.9 0)
					(length 5.08)
					(name "IO_L17P_T2_16"
						(effects
							(font
								(size 1.27 1.27)
							)
						)
					)
					(number "D14"
						(effects
							(font
								(size 1.27 1.27)
							)
						)
					)
				)
				(pin bidirectional line
					(at 0 -91.44 0)
					(length 5.08)
					(name "IO_L17N_T2_16"
						(effects
							(font
								(size 1.27 1.27)
							)
						)
					)
					(number "D13"
						(effects
							(font
								(size 1.27 1.27)
							)
						)
					)
				)
				(pin bidirectional line
					(at 0 -93.98 0)
					(length 5.08)
					(name "IO_L18P_T2_16"
						(effects
							(font
								(size 1.27 1.27)
							)
						)
					)
					(number "E13"
						(effects
							(font
								(size 1.27 1.27)
							)
						)
					)
				)
				(pin bidirectional line
					(at 0 -96.52 0)
					(length 5.08)
					(name "IO_L18N_T2_16"
						(effects
							(font
								(size 1.27 1.27)
							)
						)
					)
					(number "E12"
						(effects
							(font
								(size 1.27 1.27)
							)
						)
					)
				)
				(pin bidirectional line
					(at 0 -99.06 0)
					(length 5.08)
					(name "IO_L19P_T3_16"
						(effects
							(font
								(size 1.27 1.27)
							)
						)
					)
					(number "C14"
						(effects
							(font
								(size 1.27 1.27)
							)
						)
					)
				)
				(pin bidirectional line
					(at 0 -101.6 0)
					(length 5.08)
					(name "IO_L19N_T3_VREF_16"
						(effects
							(font
								(size 1.27 1.27)
							)
						)
					)
					(number "C13"
						(effects
							(font
								(size 1.27 1.27)
							)
						)
					)
				)
				(pin bidirectional line
					(at 0 -104.14 0)
					(length 5.08)
					(name "IO_L20P_T3_16"
						(effects
							(font
								(size 1.27 1.27)
							)
						)
					)
					(number "B12"
						(effects
							(font
								(size 1.27 1.27)
							)
						)
					)
				)
				(pin bidirectional line
					(at 0 -106.68 0)
					(length 5.08)
					(name "IO_L20N_T3_16"
						(effects
							(font
								(size 1.27 1.27)
							)
						)
					)
					(number "B11"
						(effects
							(font
								(size 1.27 1.27)
							)
						)
					)
				)
				(pin bidirectional line
					(at 0 -109.22 0)
					(length 5.08)
					(name "IO_L21P_T3_DQS_16"
						(effects
							(font
								(size 1.27 1.27)
							)
						)
					)
					(number "B14"
						(effects
							(font
								(size 1.27 1.27)
							)
						)
					)
				)
				(pin bidirectional line
					(at 0 -111.76 0)
					(length 5.08)
					(name "IO_L21N_T3_DQS_16"
						(effects
							(font
								(size 1.27 1.27)
							)
						)
					)
					(number "A14"
						(effects
							(font
								(size 1.27 1.27)
							)
						)
					)
				)
				(pin bidirectional line
					(at 0 -114.3 0)
					(length 5.08)
					(name "IO_L22P_T3_16"
						(effects
							(font
								(size 1.27 1.27)
							)
						)
					)
					(number "B10"
						(effects
							(font
								(size 1.27 1.27)
							)
						)
					)
				)
				(pin bidirectional line
					(at 0 -116.84 0)
					(length 5.08)
					(name "IO_L22N_T3_16"
						(effects
							(font
								(size 1.27 1.27)
							)
						)
					)
					(number "A10"
						(effects
							(font
								(size 1.27 1.27)
							)
						)
					)
				)
				(pin bidirectional line
					(at 0 -119.38 0)
					(length 5.08)
					(name "IO_L23P_T3_16"
						(effects
							(font
								(size 1.27 1.27)
							)
						)
					)
					(number "B15"
						(effects
							(font
								(size 1.27 1.27)
							)
						)
					)
				)
				(pin bidirectional line
					(at 0 -121.92 0)
					(length 5.08)
					(name "IO_L23N_T3_16"
						(effects
							(font
								(size 1.27 1.27)
							)
						)
					)
					(number "A15"
						(effects
							(font
								(size 1.27 1.27)
							)
						)
					)
				)
				(pin bidirectional line
					(at 0 -124.46 0)
					(length 5.08)
					(name "IO_L24P_T3_16"
						(effects
							(font
								(size 1.27 1.27)
							)
						)
					)
					(number "A13"
						(effects
							(font
								(size 1.27 1.27)
							)
						)
					)
				)
				(pin bidirectional line
					(at 0 -127 0)
					(length 5.08)
					(name "IO_L24N_T3_16"
						(effects
							(font
								(size 1.27 1.27)
							)
						)
					)
					(number "A12"
						(effects
							(font
								(size 1.27 1.27)
							)
						)
					)
				)
				(pin bidirectional line
					(at 0 -129.54 0)
					(length 5.08)
					(name "IO_25_16"
						(effects
							(font
								(size 1.27 1.27)
							)
						)
					)
					(number "J14"
						(effects
							(font
								(size 1.27 1.27)
							)
						)
					)
				)
			)
			(symbol "XC7K160T-FFG676_6_1"
				(rectangle
					(start 5.08 -132.08)
					(end 33.02 2.54)
					(stroke
						(width 0.254)
						(type default)
					)
					(fill
						(type background)
					)
				)
				(polyline
					(pts
						(xy 22.86 -3.81) (xy 30.48 -3.81) (xy 30.48 -130.81) (xy 22.86 -130.81)
					)
					(stroke
						(width 0.254)
						(type default)
					)
					(fill
						(type background)
					)
				)
				(text "BANK 32"
					(at 24.13 -1.27 0)
					(effects
						(font
							(size 1.27 1.27)
							(thickness 0.15)
						)
						(justify left bottom)
					)
				)
				(pin power_in line
					(at 0 0 0)
					(length 5.08)
					(name "VCCO_32"
						(effects
							(font
								(size 1.27 1.27)
							)
						)
					)
					(number "AB18"
						(effects
							(font
								(size 1.27 1.27)
							)
						)
					)
				)
				(pin passive line
					(at 0 0 0)
					(length 5.08)
					(hide yes)
					(name "VCCO_32"
						(effects
							(font
								(size 1.27 1.27)
							)
						)
					)
					(number "AC15"
						(effects
							(font
								(size 1.27 1.27)
							)
						)
					)
				)
				(pin passive line
					(at 0 0 0)
					(length 5.08)
					(hide yes)
					(name "VCCO_32"
						(effects
							(font
								(size 1.27 1.27)
							)
						)
					)
					(number "AE19"
						(effects
							(font
								(size 1.27 1.27)
							)
						)
					)
				)
				(pin passive line
					(at 0 0 0)
					(length 5.08)
					(hide yes)
					(name "VCCO_32"
						(effects
							(font
								(size 1.27 1.27)
							)
						)
					)
					(number "AF16"
						(effects
							(font
								(size 1.27 1.27)
							)
						)
					)
				)
				(pin passive line
					(at 0 0 0)
					(length 5.08)
					(hide yes)
					(name "VCCO_32"
						(effects
							(font
								(size 1.27 1.27)
							)
						)
					)
					(number "W17"
						(effects
							(font
								(size 1.27 1.27)
							)
						)
					)
				)
				(pin passive line
					(at 0 0 0)
					(length 5.08)
					(hide yes)
					(name "VCCO_32"
						(effects
							(font
								(size 1.27 1.27)
							)
						)
					)
					(number "Y14"
						(effects
							(font
								(size 1.27 1.27)
							)
						)
					)
				)
				(pin bidirectional line
					(at 0 -5.08 0)
					(length 5.08)
					(name "IO_0_VRN_32"
						(effects
							(font
								(size 1.27 1.27)
							)
						)
					)
					(number "V13"
						(effects
							(font
								(size 1.27 1.27)
							)
						)
					)
				)
				(pin bidirectional line
					(at 0 -7.62 0)
					(length 5.08)
					(name "IO_L1P_T0_32"
						(effects
							(font
								(size 1.27 1.27)
							)
						)
					)
					(number "AE17"
						(effects
							(font
								(size 1.27 1.27)
							)
						)
					)
				)
				(pin bidirectional line
					(at 0 -10.16 0)
					(length 5.08)
					(name "IO_L1N_T0_32"
						(effects
							(font
								(size 1.27 1.27)
							)
						)
					)
					(number "AF17"
						(effects
							(font
								(size 1.27 1.27)
							)
						)
					)
				)
				(pin bidirectional line
					(at 0 -12.7 0)
					(length 5.08)
					(name "IO_L2P_T0_32"
						(effects
							(font
								(size 1.27 1.27)
							)
						)
					)
					(number "AF14"
						(effects
							(font
								(size 1.27 1.27)
							)
						)
					)
				)
				(pin bidirectional line
					(at 0 -15.24 0)
					(length 5.08)
					(name "IO_L2N_T0_32"
						(effects
							(font
								(size 1.27 1.27)
							)
						)
					)
					(number "AF15"
						(effects
							(font
								(size 1.27 1.27)
							)
						)
					)
				)
				(pin bidirectional line
					(at 0 -17.78 0)
					(length 5.08)
					(name "IO_L3P_T0_DQS_32"
						(effects
							(font
								(size 1.27 1.27)
							)
						)
					)
					(number "AE18"
						(effects
							(font
								(size 1.27 1.27)
							)
						)
					)
				)
				(pin bidirectional line
					(at 0 -20.32 0)
					(length 5.08)
					(name "IO_L3N_T0_DQS_32"
						(effects
							(font
								(size 1.27 1.27)
							)
						)
					)
					(number "AF18"
						(effects
							(font
								(size 1.27 1.27)
							)
						)
					)
				)
				(pin bidirectional line
					(at 0 -22.86 0)
					(length 5.08)
					(name "IO_L4P_T0_32"
						(effects
							(font
								(size 1.27 1.27)
							)
						)
					)
					(number "AD15"
						(effects
							(font
								(size 1.27 1.27)
							)
						)
					)
				)
				(pin bidirectional line
					(at 0 -25.4 0)
					(length 5.08)
					(name "IO_L4N_T0_32"
						(effects
							(font
								(size 1.27 1.27)
							)
						)
					)
					(number "AE15"
						(effects
							(font
								(size 1.27 1.27)
							)
						)
					)
				)
				(pin bidirectional line
					(at 0 -27.94 0)
					(length 5.08)
					(name "IO_L5P_T0_32"
						(effects
							(font
								(size 1.27 1.27)
							)
						)
					)
					(number "AF19"
						(effects
							(font
								(size 1.27 1.27)
							)
						)
					)
				)
				(pin bidirectional line
					(at 0 -30.48 0)
					(length 5.08)
					(name "IO_L5N_T0_32"
						(effects
							(font
								(size 1.27 1.27)
							)
						)
					)
					(number "AF20"
						(effects
							(font
								(size 1.27 1.27)
							)
						)
					)
				)
				(pin bidirectional line
					(at 0 -33.02 0)
					(length 5.08)
					(name "IO_L6P_T0_32"
						(effects
							(font
								(size 1.27 1.27)
							)
						)
					)
					(number "AD16"
						(effects
							(font
								(size 1.27 1.27)
							)
						)
					)
				)
				(pin bidirectional line
					(at 0 -35.56 0)
					(length 5.08)
					(name "IO_L6N_T0_VREF_32"
						(effects
							(font
								(size 1.27 1.27)
							)
						)
					)
					(number "AE16"
						(effects
							(font
								(size 1.27 1.27)
							)
						)
					)
				)
				(pin bidirectional line
					(at 0 -38.1 0)
					(length 5.08)
					(name "IO_L7P_T1_32"
						(effects
							(font
								(size 1.27 1.27)
							)
						)
					)
					(number "AA14"
						(effects
							(font
								(size 1.27 1.27)
							)
						)
					)
				)
				(pin bidirectional line
					(at 0 -40.64 0)
					(length 5.08)
					(name "IO_L7N_T1_32"
						(effects
							(font
								(size 1.27 1.27)
							)
						)
					)
					(number "AA15"
						(effects
							(font
								(size 1.27 1.27)
							)
						)
					)
				)
				(pin bidirectional line
					(at 0 -43.18 0)
					(length 5.08)
					(name "IO_L8P_T1_32"
						(effects
							(font
								(size 1.27 1.27)
							)
						)
					)
					(number "AC14"
						(effects
							(font
								(size 1.27 1.27)
							)
						)
					)
				)
				(pin bidirectional line
					(at 0 -45.72 0)
					(length 5.08)
					(name "IO_L8N_T1_32"
						(effects
							(font
								(size 1.27 1.27)
							)
						)
					)
					(number "AD14"
						(effects
							(font
								(size 1.27 1.27)
							)
						)
					)
				)
				(pin bidirectional line
					(at 0 -48.26 0)
					(length 5.08)
					(name "IO_L9P_T1_DQS_32"
						(effects
							(font
								(size 1.27 1.27)
							)
						)
					)
					(number "Y15"
						(effects
							(font
								(size 1.27 1.27)
							)
						)
					)
				)
				(pin bidirectional line
					(at 0 -50.8 0)
					(length 5.08)
					(name "IO_L9N_T1_DQS_32"
						(effects
							(font
								(size 1.27 1.27)
							)
						)
					)
					(number "Y16"
						(effects
							(font
								(size 1.27 1.27)
							)
						)
					)
				)
				(pin bidirectional line
					(at 0 -53.34 0)
					(length 5.08)
					(name "IO_L10P_T1_32"
						(effects
							(font
								(size 1.27 1.27)
							)
						)
					)
					(number "AB14"
						(effects
							(font
								(size 1.27 1.27)
							)
						)
					)
				)
				(pin bidirectional line
					(at 0 -55.88 0)
					(length 5.08)
					(name "IO_L10N_T1_32"
						(effects
							(font
								(size 1.27 1.27)
							)
						)
					)
					(number "AB15"
						(effects
							(font
								(size 1.27 1.27)
							)
						)
					)
				)
				(pin bidirectional line
					(at 0 -58.42 0)
					(length 5.08)
					(name "IO_L11P_T1_SRCC_32"
						(effects
							(font
								(size 1.27 1.27)
							)
						)
					)
					(number "AA17"
						(effects
							(font
								(size 1.27 1.27)
							)
						)
					)
				)
				(pin bidirectional line
					(at 0 -60.96 0)
					(length 5.08)
					(name "IO_L11N_T1_SRCC_32"
						(effects
							(font
								(size 1.27 1.27)
							)
						)
					)
					(number "AA18"
						(effects
							(font
								(size 1.27 1.27)
							)
						)
					)
				)
				(pin bidirectional line
					(at 0 -63.5 0)
					(length 5.08)
					(name "IO_L12P_T1_MRCC_32"
						(effects
							(font
								(size 1.27 1.27)
							)
						)
					)
					(number "AB16"
						(effects
							(font
								(size 1.27 1.27)
							)
						)
					)
				)
				(pin bidirectional line
					(at 0 -66.04 0)
					(length 5.08)
					(name "IO_L12N_T1_MRCC_32"
						(effects
							(font
								(size 1.27 1.27)
							)
						)
					)
					(number "AC16"
						(effects
							(font
								(size 1.27 1.27)
							)
						)
					)
				)
				(pin bidirectional line
					(at 0 -68.58 0)
					(length 5.08)
					(name "IO_L13P_T2_MRCC_32"
						(effects
							(font
								(size 1.27 1.27)
							)
						)
					)
					(number "AC18"
						(effects
							(font
								(size 1.27 1.27)
							)
						)
					)
				)
				(pin bidirectional line
					(at 0 -71.12 0)
					(length 5.08)
					(name "IO_L13N_T2_MRCC_32"
						(effects
							(font
								(size 1.27 1.27)
							)
						)
					)
					(number "AD18"
						(effects
							(font
								(size 1.27 1.27)
							)
						)
					)
				)
				(pin bidirectional line
					(at 0 -73.66 0)
					(length 5.08)
					(name "IO_L14P_T2_SRCC_32"
						(effects
							(font
								(size 1.27 1.27)
							)
						)
					)
					(number "AB17"
						(effects
							(font
								(size 1.27 1.27)
							)
						)
					)
				)
				(pin bidirectional line
					(at 0 -76.2 0)
					(length 5.08)
					(name "IO_L14N_T2_SRCC_32"
						(effects
							(font
								(size 1.27 1.27)
							)
						)
					)
					(number "AC17"
						(effects
							(font
								(size 1.27 1.27)
							)
						)
					)
				)
				(pin bidirectional line
					(at 0 -78.74 0)
					(length 5.08)
					(name "IO_L15P_T2_DQS_32"
						(effects
							(font
								(size 1.27 1.27)
							)
						)
					)
					(number "AD20"
						(effects
							(font
								(size 1.27 1.27)
							)
						)
					)
				)
				(pin bidirectional line
					(at 0 -81.28 0)
					(length 5.08)
					(name "IO_L15N_T2_DQS_32"
						(effects
							(font
								(size 1.27 1.27)
							)
						)
					)
					(number "AE20"
						(effects
							(font
								(size 1.27 1.27)
							)
						)
					)
				)
				(pin bidirectional line
					(at 0 -83.82 0)
					(length 5.08)
					(name "IO_L16P_T2_32"
						(effects
							(font
								(size 1.27 1.27)
							)
						)
					)
					(number "AA19"
						(effects
							(font
								(size 1.27 1.27)
							)
						)
					)
				)
				(pin bidirectional line
					(at 0 -86.36 0)
					(length 5.08)
					(name "IO_L16N_T2_32"
						(effects
							(font
								(size 1.27 1.27)
							)
						)
					)
					(number "AA20"
						(effects
							(font
								(size 1.27 1.27)
							)
						)
					)
				)
				(pin bidirectional line
					(at 0 -88.9 0)
					(length 5.08)
					(name "IO_L17P_T2_32"
						(effects
							(font
								(size 1.27 1.27)
							)
						)
					)
					(number "AC19"
						(effects
							(font
								(size 1.27 1.27)
							)
						)
					)
				)
				(pin bidirectional line
					(at 0 -91.44 0)
					(length 5.08)
					(name "IO_L17N_T2_32"
						(effects
							(font
								(size 1.27 1.27)
							)
						)
					)
					(number "AD19"
						(effects
							(font
								(size 1.27 1.27)
							)
						)
					)
				)
				(pin bidirectional line
					(at 0 -93.98 0)
					(length 5.08)
					(name "IO_L18P_T2_32"
						(effects
							(font
								(size 1.27 1.27)
							)
						)
					)
					(number "AB19"
						(effects
							(font
								(size 1.27 1.27)
							)
						)
					)
				)
				(pin bidirectional line
					(at 0 -96.52 0)
					(length 5.08)
					(name "IO_L18N_T2_32"
						(effects
							(font
								(size 1.27 1.27)
							)
						)
					)
					(number "AB20"
						(effects
							(font
								(size 1.27 1.27)
							)
						)
					)
				)
				(pin bidirectional line
					(at 0 -99.06 0)
					(length 5.08)
					(name "IO_L19P_T3_32"
						(effects
							(font
								(size 1.27 1.27)
							)
						)
					)
					(number "Y17"
						(effects
							(font
								(size 1.27 1.27)
							)
						)
					)
				)
				(pin bidirectional line
					(at 0 -101.6 0)
					(length 5.08)
					(name "IO_L19N_T3_VREF_32"
						(effects
							(font
								(size 1.27 1.27)
							)
						)
					)
					(number "Y18"
						(effects
							(font
								(size 1.27 1.27)
							)
						)
					)
				)
				(pin bidirectional line
					(at 0 -104.14 0)
					(length 5.08)
					(name "IO_L20P_T3_32"
						(effects
							(font
								(size 1.27 1.27)
							)
						)
					)
					(number "V16"
						(effects
							(font
								(size 1.27 1.27)
							)
						)
					)
				)
				(pin bidirectional line
					(at 0 -106.68 0)
					(length 5.08)
					(name "IO_L20N_T3_32"
						(effects
							(font
								(size 1.27 1.27)
							)
						)
					)
					(number "V17"
						(effects
							(font
								(size 1.27 1.27)
							)
						)
					)
				)
				(pin bidirectional line
					(at 0 -109.22 0)
					(length 5.08)
					(name "IO_L21P_T3_DQS_32"
						(effects
							(font
								(size 1.27 1.27)
							)
						)
					)
					(number "W18"
						(effects
							(font
								(size 1.27 1.27)
							)
						)
					)
				)
				(pin bidirectional line
					(at 0 -111.76 0)
					(length 5.08)
					(name "IO_L21N_T3_DQS_32"
						(effects
							(font
								(size 1.27 1.27)
							)
						)
					)
					(number "W19"
						(effects
							(font
								(size 1.27 1.27)
							)
						)
					)
				)
				(pin bidirectional line
					(at 0 -114.3 0)
					(length 5.08)
					(name "IO_L22P_T3_32"
						(effects
							(font
								(size 1.27 1.27)
							)
						)
					)
					(number "W15"
						(effects
							(font
								(size 1.27 1.27)
							)
						)
					)
				)
				(pin bidirectional line
					(at 0 -116.84 0)
					(length 5.08)
					(name "IO_L22N_T3_32"
						(effects
							(font
								(size 1.27 1.27)
							)
						)
					)
					(number "W16"
						(effects
							(font
								(size 1.27 1.27)
							)
						)
					)
				)
				(pin bidirectional line
					(at 0 -119.38 0)
					(length 5.08)
					(name "IO_L23P_T3_32"
						(effects
							(font
								(size 1.27 1.27)
							)
						)
					)
					(number "V18"
						(effects
							(font
								(size 1.27 1.27)
							)
						)
					)
				)
				(pin bidirectional line
					(at 0 -121.92 0)
					(length 5.08)
					(name "IO_L23N_T3_32"
						(effects
							(font
								(size 1.27 1.27)
							)
						)
					)
					(number "V19"
						(effects
							(font
								(size 1.27 1.27)
							)
						)
					)
				)
				(pin bidirectional line
					(at 0 -124.46 0)
					(length 5.08)
					(name "IO_L24P_T3_32"
						(effects
							(font
								(size 1.27 1.27)
							)
						)
					)
					(number "V14"
						(effects
							(font
								(size 1.27 1.27)
							)
						)
					)
				)
				(pin bidirectional line
					(at 0 -127 0)
					(length 5.08)
					(name "IO_L24N_T3_32"
						(effects
							(font
								(size 1.27 1.27)
							)
						)
					)
					(number "W14"
						(effects
							(font
								(size 1.27 1.27)
							)
						)
					)
				)
				(pin bidirectional line
					(at 0 -129.54 0)
					(length 5.08)
					(name "IO_25_VRP_32"
						(effects
							(font
								(size 1.27 1.27)
							)
						)
					)
					(number "W13"
						(effects
							(font
								(size 1.27 1.27)
							)
						)
					)
				)
			)
			(symbol "XC7K160T-FFG676_7_1"
				(rectangle
					(start 5.08 -132.08)
					(end 33.02 2.54)
					(stroke
						(width 0.254)
						(type default)
					)
					(fill
						(type background)
					)
				)
				(polyline
					(pts
						(xy 22.86 -3.81) (xy 30.48 -3.81) (xy 30.48 -130.81) (xy 22.86 -130.81)
					)
					(stroke
						(width 0.254)
						(type default)
					)
					(fill
						(type background)
					)
				)
				(text "BANK 33"
					(at 24.13 -1.27 0)
					(effects
						(font
							(size 1.27 1.27)
							(thickness 0.15)
						)
						(justify left bottom)
					)
				)
				(pin power_in line
					(at 0 0 0)
					(length 5.08)
					(name "VCCO_33"
						(effects
							(font
								(size 1.27 1.27)
							)
						)
					)
					(number "AA11"
						(effects
							(font
								(size 1.27 1.27)
							)
						)
					)
				)
				(pin passive line
					(at 0 0 0)
					(length 5.08)
					(hide yes)
					(name "VCCO_33"
						(effects
							(font
								(size 1.27 1.27)
							)
						)
					)
					(number "AB8"
						(effects
							(font
								(size 1.27 1.27)
							)
						)
					)
				)
				(pin passive line
					(at 0 0 0)
					(length 5.08)
					(hide yes)
					(name "VCCO_33"
						(effects
							(font
								(size 1.27 1.27)
							)
						)
					)
					(number "AD12"
						(effects
							(font
								(size 1.27 1.27)
							)
						)
					)
				)
				(pin passive line
					(at 0 0 0)
					(length 5.08)
					(hide yes)
					(name "VCCO_33"
						(effects
							(font
								(size 1.27 1.27)
							)
						)
					)
					(number "AE9"
						(effects
							(font
								(size 1.27 1.27)
							)
						)
					)
				)
				(pin passive line
					(at 0 0 0)
					(length 5.08)
					(hide yes)
					(name "VCCO_33"
						(effects
							(font
								(size 1.27 1.27)
							)
						)
					)
					(number "V10"
						(effects
							(font
								(size 1.27 1.27)
							)
						)
					)
				)
				(pin passive line
					(at 0 0 0)
					(length 5.08)
					(hide yes)
					(name "VCCO_33"
						(effects
							(font
								(size 1.27 1.27)
							)
						)
					)
					(number "W7"
						(effects
							(font
								(size 1.27 1.27)
							)
						)
					)
				)
				(pin bidirectional line
					(at 0 -5.08 0)
					(length 5.08)
					(name "IO_0_VRN_33"
						(effects
							(font
								(size 1.27 1.27)
							)
						)
					)
					(number "U9"
						(effects
							(font
								(size 1.27 1.27)
							)
						)
					)
				)
				(pin bidirectional line
					(at 0 -7.62 0)
					(length 5.08)
					(name "IO_L1P_T0_33"
						(effects
							(font
								(size 1.27 1.27)
							)
						)
					)
					(number "V11"
						(effects
							(font
								(size 1.27 1.27)
							)
						)
					)
				)
				(pin bidirectional line
					(at 0 -10.16 0)
					(length 5.08)
					(name "IO_L1N_T0_33"
						(effects
							(font
								(size 1.27 1.27)
							)
						)
					)
					(number "W11"
						(effects
							(font
								(size 1.27 1.27)
							)
						)
					)
				)
				(pin bidirectional line
					(at 0 -12.7 0)
					(length 5.08)
					(name "IO_L2P_T0_33"
						(effects
							(font
								(size 1.27 1.27)
							)
						)
					)
					(number "V8"
						(effects
							(font
								(size 1.27 1.27)
							)
						)
					)
				)
				(pin bidirectional line
					(at 0 -15.24 0)
					(length 5.08)
					(name "IO_L2N_T0_33"
						(effects
							(font
								(size 1.27 1.27)
							)
						)
					)
					(number "V7"
						(effects
							(font
								(size 1.27 1.27)
							)
						)
					)
				)
				(pin bidirectional line
					(at 0 -17.78 0)
					(length 5.08)
					(name "IO_L3P_T0_DQS_33"
						(effects
							(font
								(size 1.27 1.27)
							)
						)
					)
					(number "W10"
						(effects
							(font
								(size 1.27 1.27)
							)
						)
					)
				)
				(pin bidirectional line
					(at 0 -20.32 0)
					(length 5.08)
					(name "IO_L3N_T0_DQS_33"
						(effects
							(font
								(size 1.27 1.27)
							)
						)
					)
					(number "W9"
						(effects
							(font
								(size 1.27 1.27)
							)
						)
					)
				)
				(pin bidirectional line
					(at 0 -22.86 0)
					(length 5.08)
					(name "IO_L4P_T0_33"
						(effects
							(font
								(size 1.27 1.27)
							)
						)
					)
					(number "Y8"
						(effects
							(font
								(size 1.27 1.27)
							)
						)
					)
				)
				(pin bidirectional line
					(at 0 -25.4 0)
					(length 5.08)
					(name "IO_L4N_T0_33"
						(effects
							(font
								(size 1.27 1.27)
							)
						)
					)
					(number "Y7"
						(effects
							(font
								(size 1.27 1.27)
							)
						)
					)
				)
				(pin bidirectional line
					(at 0 -27.94 0)
					(length 5.08)
					(name "IO_L5P_T0_33"
						(effects
							(font
								(size 1.27 1.27)
							)
						)
					)
					(number "Y11"
						(effects
							(font
								(size 1.27 1.27)
							)
						)
					)
				)
				(pin bidirectional line
					(at 0 -30.48 0)
					(length 5.08)
					(name "IO_L5N_T0_33"
						(effects
							(font
								(size 1.27 1.27)
							)
						)
					)
					(number "Y10"
						(effects
							(font
								(size 1.27 1.27)
							)
						)
					)
				)
				(pin bidirectional line
					(at 0 -33.02 0)
					(length 5.08)
					(name "IO_L6P_T0_33"
						(effects
							(font
								(size 1.27 1.27)
							)
						)
					)
					(number "V9"
						(effects
							(font
								(size 1.27 1.27)
							)
						)
					)
				)
				(pin bidirectional line
					(at 0 -35.56 0)
					(length 5.08)
					(name "IO_L6N_T0_VREF_33"
						(effects
							(font
								(size 1.27 1.27)
							)
						)
					)
					(number "W8"
						(effects
							(font
								(size 1.27 1.27)
							)
						)
					)
				)
				(pin bidirectional line
					(at 0 -38.1 0)
					(length 5.08)
					(name "IO_L7P_T1_33"
						(effects
							(font
								(size 1.27 1.27)
							)
						)
					)
					(number "AE7"
						(effects
							(font
								(size 1.27 1.27)
							)
						)
					)
				)
				(pin bidirectional line
					(at 0 -40.64 0)
					(length 5.08)
					(name "IO_L7N_T1_33"
						(effects
							(font
								(size 1.27 1.27)
							)
						)
					)
					(number "AF7"
						(effects
							(font
								(size 1.27 1.27)
							)
						)
					)
				)
				(pin bidirectional line
					(at 0 -43.18 0)
					(length 5.08)
					(name "IO_L8P_T1_33"
						(effects
							(font
								(size 1.27 1.27)
							)
						)
					)
					(number "AA8"
						(effects
							(font
								(size 1.27 1.27)
							)
						)
					)
				)
				(pin bidirectional line
					(at 0 -45.72 0)
					(length 5.08)
					(name "IO_L8N_T1_33"
						(effects
							(font
								(size 1.27 1.27)
							)
						)
					)
					(number "AA7"
						(effects
							(font
								(size 1.27 1.27)
							)
						)
					)
				)
				(pin bidirectional line
					(at 0 -48.26 0)
					(length 5.08)
					(name "IO_L9P_T1_DQS_33"
						(effects
							(font
								(size 1.27 1.27)
							)
						)
					)
					(number "AC8"
						(effects
							(font
								(size 1.27 1.27)
							)
						)
					)
				)
				(pin bidirectional line
					(at 0 -50.8 0)
					(length 5.08)
					(name "IO_L9N_T1_DQS_33"
						(effects
							(font
								(size 1.27 1.27)
							)
						)
					)
					(number "AD8"
						(effects
							(font
								(size 1.27 1.27)
							)
						)
					)
				)
				(pin bidirectional line
					(at 0 -53.34 0)
					(length 5.08)
					(name "IO_L10P_T1_33"
						(effects
							(font
								(size 1.27 1.27)
							)
						)
					)
					(number "AB7"
						(effects
							(font
								(size 1.27 1.27)
							)
						)
					)
				)
				(pin bidirectional line
					(at 0 -55.88 0)
					(length 5.08)
					(name "IO_L10N_T1_33"
						(effects
							(font
								(size 1.27 1.27)
							)
						)
					)
					(number "AC7"
						(effects
							(font
								(size 1.27 1.27)
							)
						)
					)
				)
				(pin bidirectional line
					(at 0 -58.42 0)
					(length 5.08)
					(name "IO_L11P_T1_SRCC_33"
						(effects
							(font
								(size 1.27 1.27)
							)
						)
					)
					(number "AA9"
						(effects
							(font
								(size 1.27 1.27)
							)
						)
					)
				)
				(pin bidirectional line
					(at 0 -60.96 0)
					(length 5.08)
					(name "IO_L11N_T1_SRCC_33"
						(effects
							(font
								(size 1.27 1.27)
							)
						)
					)
					(number "AB9"
						(effects
							(font
								(size 1.27 1.27)
							)
						)
					)
				)
				(pin bidirectional line
					(at 0 -63.5 0)
					(length 5.08)
					(name "IO_L12P_T1_MRCC_33"
						(effects
							(font
								(size 1.27 1.27)
							)
						)
					)
					(number "AC9"
						(effects
							(font
								(size 1.27 1.27)
							)
						)
					)
				)
				(pin bidirectional line
					(at 0 -66.04 0)
					(length 5.08)
					(name "IO_L12N_T1_MRCC_33"
						(effects
							(font
								(size 1.27 1.27)
							)
						)
					)
					(number "AD9"
						(effects
							(font
								(size 1.27 1.27)
							)
						)
					)
				)
				(pin bidirectional line
					(at 0 -68.58 0)
					(length 5.08)
					(name "IO_L13P_T2_MRCC_33"
						(effects
							(font
								(size 1.27 1.27)
							)
						)
					)
					(number "AB11"
						(effects
							(font
								(size 1.27 1.27)
							)
						)
					)
				)
				(pin bidirectional line
					(at 0 -71.12 0)
					(length 5.08)
					(name "IO_L13N_T2_MRCC_33"
						(effects
							(font
								(size 1.27 1.27)
							)
						)
					)
					(number "AC11"
						(effects
							(font
								(size 1.27 1.27)
							)
						)
					)
				)
				(pin bidirectional line
					(at 0 -73.66 0)
					(length 5.08)
					(name "IO_L14P_T2_SRCC_33"
						(effects
							(font
								(size 1.27 1.27)
							)
						)
					)
					(number "AA10"
						(effects
							(font
								(size 1.27 1.27)
							)
						)
					)
				)
				(pin bidirectional line
					(at 0 -76.2 0)
					(length 5.08)
					(name "IO_L14N_T2_SRCC_33"
						(effects
							(font
								(size 1.27 1.27)
							)
						)
					)
					(number "AB10"
						(effects
							(font
								(size 1.27 1.27)
							)
						)
					)
				)
				(pin bidirectional line
					(at 0 -78.74 0)
					(length 5.08)
					(name "IO_L15P_T2_DQS_33"
						(effects
							(font
								(size 1.27 1.27)
							)
						)
					)
					(number "AB12"
						(effects
							(font
								(size 1.27 1.27)
							)
						)
					)
				)
				(pin bidirectional line
					(at 0 -81.28 0)
					(length 5.08)
					(name "IO_L15N_T2_DQS_33"
						(effects
							(font
								(size 1.27 1.27)
							)
						)
					)
					(number "AC12"
						(effects
							(font
								(size 1.27 1.27)
							)
						)
					)
				)
				(pin bidirectional line
					(at 0 -83.82 0)
					(length 5.08)
					(name "IO_L16P_T2_33"
						(effects
							(font
								(size 1.27 1.27)
							)
						)
					)
					(number "AA13"
						(effects
							(font
								(size 1.27 1.27)
							)
						)
					)
				)
				(pin bidirectional line
					(at 0 -86.36 0)
					(length 5.08)
					(name "IO_L16N_T2_33"
						(effects
							(font
								(size 1.27 1.27)
							)
						)
					)
					(number "AA12"
						(effects
							(font
								(size 1.27 1.27)
							)
						)
					)
				)
				(pin bidirectional line
					(at 0 -88.9 0)
					(length 5.08)
					(name "IO_L17P_T2_33"
						(effects
							(font
								(size 1.27 1.27)
							)
						)
					)
					(number "AC13"
						(effects
							(font
								(size 1.27 1.27)
							)
						)
					)
				)
				(pin bidirectional line
					(at 0 -91.44 0)
					(length 5.08)
					(name "IO_L17N_T2_33"
						(effects
							(font
								(size 1.27 1.27)
							)
						)
					)
					(number "AD13"
						(effects
							(font
								(size 1.27 1.27)
							)
						)
					)
				)
				(pin bidirectional line
					(at 0 -93.98 0)
					(length 5.08)
					(name "IO_L18P_T2_33"
						(effects
							(font
								(size 1.27 1.27)
							)
						)
					)
					(number "Y13"
						(effects
							(font
								(size 1.27 1.27)
							)
						)
					)
				)
				(pin bidirectional line
					(at 0 -96.52 0)
					(length 5.08)
					(name "IO_L18N_T2_33"
						(effects
							(font
								(size 1.27 1.27)
							)
						)
					)
					(number "Y12"
						(effects
							(font
								(size 1.27 1.27)
							)
						)
					)
				)
				(pin bidirectional line
					(at 0 -99.06 0)
					(length 5.08)
					(name "IO_L19P_T3_33"
						(effects
							(font
								(size 1.27 1.27)
							)
						)
					)
					(number "AD11"
						(effects
							(font
								(size 1.27 1.27)
							)
						)
					)
				)
				(pin bidirectional line
					(at 0 -101.6 0)
					(length 5.08)
					(name "IO_L19N_T3_VREF_33"
						(effects
							(font
								(size 1.27 1.27)
							)
						)
					)
					(number "AE11"
						(effects
							(font
								(size 1.27 1.27)
							)
						)
					)
				)
				(pin bidirectional line
					(at 0 -104.14 0)
					(length 5.08)
					(name "IO_L20P_T3_33"
						(effects
							(font
								(size 1.27 1.27)
							)
						)
					)
					(number "AD10"
						(effects
							(font
								(size 1.27 1.27)
							)
						)
					)
				)
				(pin bidirectional line
					(at 0 -106.68 0)
					(length 5.08)
					(name "IO_L20N_T3_33"
						(effects
							(font
								(size 1.27 1.27)
							)
						)
					)
					(number "AE10"
						(effects
							(font
								(size 1.27 1.27)
							)
						)
					)
				)
				(pin bidirectional line
					(at 0 -109.22 0)
					(length 5.08)
					(name "IO_L21P_T3_DQS_33"
						(effects
							(font
								(size 1.27 1.27)
							)
						)
					)
					(number "AE12"
						(effects
							(font
								(size 1.27 1.27)
							)
						)
					)
				)
				(pin bidirectional line
					(at 0 -111.76 0)
					(length 5.08)
					(name "IO_L21N_T3_DQS_33"
						(effects
							(font
								(size 1.27 1.27)
							)
						)
					)
					(number "AF12"
						(effects
							(font
								(size 1.27 1.27)
							)
						)
					)
				)
				(pin bidirectional line
					(at 0 -114.3 0)
					(length 5.08)
					(name "IO_L22P_T3_33"
						(effects
							(font
								(size 1.27 1.27)
							)
						)
					)
					(number "AE8"
						(effects
							(font
								(size 1.27 1.27)
							)
						)
					)
				)
				(pin bidirectional line
					(at 0 -116.84 0)
					(length 5.08)
					(name "IO_L22N_T3_33"
						(effects
							(font
								(size 1.27 1.27)
							)
						)
					)
					(number "AF8"
						(effects
							(font
								(size 1.27 1.27)
							)
						)
					)
				)
				(pin bidirectional line
					(at 0 -119.38 0)
					(length 5.08)
					(name "IO_L23P_T3_33"
						(effects
							(font
								(size 1.27 1.27)
							)
						)
					)
					(number "AE13"
						(effects
							(font
								(size 1.27 1.27)
							)
						)
					)
				)
				(pin bidirectional line
					(at 0 -121.92 0)
					(length 5.08)
					(name "IO_L23N_T3_33"
						(effects
							(font
								(size 1.27 1.27)
							)
						)
					)
					(number "AF13"
						(effects
							(font
								(size 1.27 1.27)
							)
						)
					)
				)
				(pin bidirectional line
					(at 0 -124.46 0)
					(length 5.08)
					(name "IO_L24P_T3_33"
						(effects
							(font
								(size 1.27 1.27)
							)
						)
					)
					(number "AF10"
						(effects
							(font
								(size 1.27 1.27)
							)
						)
					)
				)
				(pin bidirectional line
					(at 0 -127 0)
					(length 5.08)
					(name "IO_L24N_T3_33"
						(effects
							(font
								(size 1.27 1.27)
							)
						)
					)
					(number "AF9"
						(effects
							(font
								(size 1.27 1.27)
							)
						)
					)
				)
				(pin bidirectional line
					(at 0 -129.54 0)
					(length 5.08)
					(name "IO_25_VRP_33"
						(effects
							(font
								(size 1.27 1.27)
							)
						)
					)
					(number "V12"
						(effects
							(font
								(size 1.27 1.27)
							)
						)
					)
				)
			)
			(symbol "XC7K160T-FFG676_8_1"
				(rectangle
					(start 5.08 -132.08)
					(end 33.02 2.54)
					(stroke
						(width 0.254)
						(type default)
					)
					(fill
						(type background)
					)
				)
				(polyline
					(pts
						(xy 22.86 -3.81) (xy 30.48 -3.81) (xy 30.48 -130.81) (xy 22.86 -130.81)
					)
					(stroke
						(width 0.254)
						(type default)
					)
					(fill
						(type background)
					)
				)
				(text "BANK 34"
					(at 24.13 -1.27 0)
					(effects
						(font
							(size 1.27 1.27)
							(thickness 0.15)
						)
						(justify left bottom)
					)
				)
				(pin power_in line
					(at 0 0 0)
					(length 5.08)
					(name "VCCO_34"
						(effects
							(font
								(size 1.27 1.27)
							)
						)
					)
					(number "AA1"
						(effects
							(font
								(size 1.27 1.27)
							)
						)
					)
				)
				(pin passive line
					(at 0 0 0)
					(length 5.08)
					(hide yes)
					(name "VCCO_34"
						(effects
							(font
								(size 1.27 1.27)
							)
						)
					)
					(number "AC5"
						(effects
							(font
								(size 1.27 1.27)
							)
						)
					)
				)
				(pin passive line
					(at 0 0 0)
					(length 5.08)
					(hide yes)
					(name "VCCO_34"
						(effects
							(font
								(size 1.27 1.27)
							)
						)
					)
					(number "AD2"
						(effects
							(font
								(size 1.27 1.27)
							)
						)
					)
				)
				(pin passive line
					(at 0 0 0)
					(length 5.08)
					(hide yes)
					(name "VCCO_34"
						(effects
							(font
								(size 1.27 1.27)
							)
						)
					)
					(number "AF6"
						(effects
							(font
								(size 1.27 1.27)
							)
						)
					)
				)
				(pin passive line
					(at 0 0 0)
					(length 5.08)
					(hide yes)
					(name "VCCO_34"
						(effects
							(font
								(size 1.27 1.27)
							)
						)
					)
					(number "U3"
						(effects
							(font
								(size 1.27 1.27)
							)
						)
					)
				)
				(pin passive line
					(at 0 0 0)
					(length 5.08)
					(hide yes)
					(name "VCCO_34"
						(effects
							(font
								(size 1.27 1.27)
							)
						)
					)
					(number "Y4"
						(effects
							(font
								(size 1.27 1.27)
							)
						)
					)
				)
				(pin bidirectional line
					(at 0 -5.08 0)
					(length 5.08)
					(name "IO_0_VRN_34"
						(effects
							(font
								(size 1.27 1.27)
							)
						)
					)
					(number "U4"
						(effects
							(font
								(size 1.27 1.27)
							)
						)
					)
				)
				(pin bidirectional line
					(at 0 -7.62 0)
					(length 5.08)
					(name "IO_L1P_T0_34"
						(effects
							(font
								(size 1.27 1.27)
							)
						)
					)
					(number "U6"
						(effects
							(font
								(size 1.27 1.27)
							)
						)
					)
				)
				(pin bidirectional line
					(at 0 -10.16 0)
					(length 5.08)
					(name "IO_L1N_T0_34"
						(effects
							(font
								(size 1.27 1.27)
							)
						)
					)
					(number "U5"
						(effects
							(font
								(size 1.27 1.27)
							)
						)
					)
				)
				(pin bidirectional line
					(at 0 -12.7 0)
					(length 5.08)
					(name "IO_L2P_T0_34"
						(effects
							(font
								(size 1.27 1.27)
							)
						)
					)
					(number "U2"
						(effects
							(font
								(size 1.27 1.27)
							)
						)
					)
				)
				(pin bidirectional line
					(at 0 -15.24 0)
					(length 5.08)
					(name "IO_L2N_T0_34"
						(effects
							(font
								(size 1.27 1.27)
							)
						)
					)
					(number "U1"
						(effects
							(font
								(size 1.27 1.27)
							)
						)
					)
				)
				(pin bidirectional line
					(at 0 -17.78 0)
					(length 5.08)
					(name "IO_L3P_T0_DQS_34"
						(effects
							(font
								(size 1.27 1.27)
							)
						)
					)
					(number "W6"
						(effects
							(font
								(size 1.27 1.27)
							)
						)
					)
				)
				(pin bidirectional line
					(at 0 -20.32 0)
					(length 5.08)
					(name "IO_L3N_T0_DQS_34"
						(effects
							(font
								(size 1.27 1.27)
							)
						)
					)
					(number "W5"
						(effects
							(font
								(size 1.27 1.27)
							)
						)
					)
				)
				(pin bidirectional line
					(at 0 -22.86 0)
					(length 5.08)
					(name "IO_L4P_T0_34"
						(effects
							(font
								(size 1.27 1.27)
							)
						)
					)
					(number "V3"
						(effects
							(font
								(size 1.27 1.27)
							)
						)
					)
				)
				(pin bidirectional line
					(at 0 -25.4 0)
					(length 5.08)
					(name "IO_L4N_T0_34"
						(effects
							(font
								(size 1.27 1.27)
							)
						)
					)
					(number "W3"
						(effects
							(font
								(size 1.27 1.27)
							)
						)
					)
				)
				(pin bidirectional line
					(at 0 -27.94 0)
					(length 5.08)
					(name "IO_L5P_T0_34"
						(effects
							(font
								(size 1.27 1.27)
							)
						)
					)
					(number "U7"
						(effects
							(font
								(size 1.27 1.27)
							)
						)
					)
				)
				(pin bidirectional line
					(at 0 -30.48 0)
					(length 5.08)
					(name "IO_L5N_T0_34"
						(effects
							(font
								(size 1.27 1.27)
							)
						)
					)
					(number "V6"
						(effects
							(font
								(size 1.27 1.27)
							)
						)
					)
				)
				(pin bidirectional line
					(at 0 -33.02 0)
					(length 5.08)
					(name "IO_L6P_T0_34"
						(effects
							(font
								(size 1.27 1.27)
							)
						)
					)
					(number "V4"
						(effects
							(font
								(size 1.27 1.27)
							)
						)
					)
				)
				(pin bidirectional line
					(at 0 -35.56 0)
					(length 5.08)
					(name "IO_L6N_T0_VREF_34"
						(effects
							(font
								(size 1.27 1.27)
							)
						)
					)
					(number "W4"
						(effects
							(font
								(size 1.27 1.27)
							)
						)
					)
				)
				(pin bidirectional line
					(at 0 -38.1 0)
					(length 5.08)
					(name "IO_L7P_T1_34"
						(effects
							(font
								(size 1.27 1.27)
							)
						)
					)
					(number "Y3"
						(effects
							(font
								(size 1.27 1.27)
							)
						)
					)
				)
				(pin bidirectional line
					(at 0 -40.64 0)
					(length 5.08)
					(name "IO_L7N_T1_34"
						(effects
							(font
								(size 1.27 1.27)
							)
						)
					)
					(number "Y2"
						(effects
							(font
								(size 1.27 1.27)
							)
						)
					)
				)
				(pin bidirectional line
					(at 0 -43.18 0)
					(length 5.08)
					(name "IO_L8P_T1_34"
						(effects
							(font
								(size 1.27 1.27)
							)
						)
					)
					(number "V2"
						(effects
							(font
								(size 1.27 1.27)
							)
						)
					)
				)
				(pin bidirectional line
					(at 0 -45.72 0)
					(length 5.08)
					(name "IO_L8N_T1_34"
						(effects
							(font
								(size 1.27 1.27)
							)
						)
					)
					(number "V1"
						(effects
							(font
								(size 1.27 1.27)
							)
						)
					)
				)
				(pin bidirectional line
					(at 0 -48.26 0)
					(length 5.08)
					(name "IO_L9P_T1_DQS_34"
						(effects
							(font
								(size 1.27 1.27)
							)
						)
					)
					(number "AB1"
						(effects
							(font
								(size 1.27 1.27)
							)
						)
					)
				)
				(pin bidirectional line
					(at 0 -50.8 0)
					(length 5.08)
					(name "IO_L9N_T1_DQS_34"
						(effects
							(font
								(size 1.27 1.27)
							)
						)
					)
					(number "AC1"
						(effects
							(font
								(size 1.27 1.27)
							)
						)
					)
				)
				(pin bidirectional line
					(at 0 -53.34 0)
					(length 5.08)
					(name "IO_L10P_T1_34"
						(effects
							(font
								(size 1.27 1.27)
							)
						)
					)
					(number "W1"
						(effects
							(font
								(size 1.27 1.27)
							)
						)
					)
				)
				(pin bidirectional line
					(at 0 -55.88 0)
					(length 5.08)
					(name "IO_L10N_T1_34"
						(effects
							(font
								(size 1.27 1.27)
							)
						)
					)
					(number "Y1"
						(effects
							(font
								(size 1.27 1.27)
							)
						)
					)
				)
				(pin bidirectional line
					(at 0 -58.42 0)
					(length 5.08)
					(name "IO_L11P_T1_SRCC_34"
						(effects
							(font
								(size 1.27 1.27)
							)
						)
					)
					(number "AB2"
						(effects
							(font
								(size 1.27 1.27)
							)
						)
					)
				)
				(pin bidirectional line
					(at 0 -60.96 0)
					(length 5.08)
					(name "IO_L11N_T1_SRCC_34"
						(effects
							(font
								(size 1.27 1.27)
							)
						)
					)
					(number "AC2"
						(effects
							(font
								(size 1.27 1.27)
							)
						)
					)
				)
				(pin bidirectional line
					(at 0 -63.5 0)
					(length 5.08)
					(name "IO_L12P_T1_MRCC_34"
						(effects
							(font
								(size 1.27 1.27)
							)
						)
					)
					(number "AA3"
						(effects
							(font
								(size 1.27 1.27)
							)
						)
					)
				)
				(pin bidirectional line
					(at 0 -66.04 0)
					(length 5.08)
					(name "IO_L12N_T1_MRCC_34"
						(effects
							(font
								(size 1.27 1.27)
							)
						)
					)
					(number "AA2"
						(effects
							(font
								(size 1.27 1.27)
							)
						)
					)
				)
				(pin bidirectional line
					(at 0 -68.58 0)
					(length 5.08)
					(name "IO_L13P_T2_MRCC_34"
						(effects
							(font
								(size 1.27 1.27)
							)
						)
					)
					(number "AA4"
						(effects
							(font
								(size 1.27 1.27)
							)
						)
					)
				)
				(pin bidirectional line
					(at 0 -71.12 0)
					(length 5.08)
					(name "IO_L13N_T2_MRCC_34"
						(effects
							(font
								(size 1.27 1.27)
							)
						)
					)
					(number "AB4"
						(effects
							(font
								(size 1.27 1.27)
							)
						)
					)
				)
				(pin bidirectional line
					(at 0 -73.66 0)
					(length 5.08)
					(name "IO_L14P_T2_SRCC_34"
						(effects
							(font
								(size 1.27 1.27)
							)
						)
					)
					(number "AC4"
						(effects
							(font
								(size 1.27 1.27)
							)
						)
					)
				)
				(pin bidirectional line
					(at 0 -76.2 0)
					(length 5.08)
					(name "IO_L14N_T2_SRCC_34"
						(effects
							(font
								(size 1.27 1.27)
							)
						)
					)
					(number "AC3"
						(effects
							(font
								(size 1.27 1.27)
							)
						)
					)
				)
				(pin bidirectional line
					(at 0 -78.74 0)
					(length 5.08)
					(name "IO_L15P_T2_DQS_34"
						(effects
							(font
								(size 1.27 1.27)
							)
						)
					)
					(number "AA5"
						(effects
							(font
								(size 1.27 1.27)
							)
						)
					)
				)
				(pin bidirectional line
					(at 0 -81.28 0)
					(length 5.08)
					(name "IO_L15N_T2_DQS_34"
						(effects
							(font
								(size 1.27 1.27)
							)
						)
					)
					(number "AB5"
						(effects
							(font
								(size 1.27 1.27)
							)
						)
					)
				)
				(pin bidirectional line
					(at 0 -83.82 0)
					(length 5.08)
					(name "IO_L16P_T2_34"
						(effects
							(font
								(size 1.27 1.27)
							)
						)
					)
					(number "AB6"
						(effects
							(font
								(size 1.27 1.27)
							)
						)
					)
				)
				(pin bidirectional line
					(at 0 -86.36 0)
					(length 5.08)
					(name "IO_L16N_T2_34"
						(effects
							(font
								(size 1.27 1.27)
							)
						)
					)
					(number "AC6"
						(effects
							(font
								(size 1.27 1.27)
							)
						)
					)
				)
				(pin bidirectional line
					(at 0 -88.9 0)
					(length 5.08)
					(name "IO_L17P_T2_34"
						(effects
							(font
								(size 1.27 1.27)
							)
						)
					)
					(number "Y6"
						(effects
							(font
								(size 1.27 1.27)
							)
						)
					)
				)
				(pin bidirectional line
					(at 0 -91.44 0)
					(length 5.08)
					(name "IO_L17N_T2_34"
						(effects
							(font
								(size 1.27 1.27)
							)
						)
					)
					(number "Y5"
						(effects
							(font
								(size 1.27 1.27)
							)
						)
					)
				)
				(pin bidirectional line
					(at 0 -93.98 0)
					(length 5.08)
					(name "IO_L18P_T2_34"
						(effects
							(font
								(size 1.27 1.27)
							)
						)
					)
					(number "AD6"
						(effects
							(font
								(size 1.27 1.27)
							)
						)
					)
				)
				(pin bidirectional line
					(at 0 -96.52 0)
					(length 5.08)
					(name "IO_L18N_T2_34"
						(effects
							(font
								(size 1.27 1.27)
							)
						)
					)
					(number "AD5"
						(effects
							(font
								(size 1.27 1.27)
							)
						)
					)
				)
				(pin bidirectional line
					(at 0 -99.06 0)
					(length 5.08)
					(name "IO_L19P_T3_34"
						(effects
							(font
								(size 1.27 1.27)
							)
						)
					)
					(number "AD4"
						(effects
							(font
								(size 1.27 1.27)
							)
						)
					)
				)
				(pin bidirectional line
					(at 0 -101.6 0)
					(length 5.08)
					(name "IO_L19N_T3_VREF_34"
						(effects
							(font
								(size 1.27 1.27)
							)
						)
					)
					(number "AD3"
						(effects
							(font
								(size 1.27 1.27)
							)
						)
					)
				)
				(pin bidirectional line
					(at 0 -104.14 0)
					(length 5.08)
					(name "IO_L20P_T3_34"
						(effects
							(font
								(size 1.27 1.27)
							)
						)
					)
					(number "AD1"
						(effects
							(font
								(size 1.27 1.27)
							)
						)
					)
				)
				(pin bidirectional line
					(at 0 -106.68 0)
					(length 5.08)
					(name "IO_L20N_T3_34"
						(effects
							(font
								(size 1.27 1.27)
							)
						)
					)
					(number "AE1"
						(effects
							(font
								(size 1.27 1.27)
							)
						)
					)
				)
				(pin bidirectional line
					(at 0 -109.22 0)
					(length 5.08)
					(name "IO_L21P_T3_DQS_34"
						(effects
							(font
								(size 1.27 1.27)
							)
						)
					)
					(number "AF5"
						(effects
							(font
								(size 1.27 1.27)
							)
						)
					)
				)
				(pin bidirectional line
					(at 0 -111.76 0)
					(length 5.08)
					(name "IO_L21N_T3_DQS_34"
						(effects
							(font
								(size 1.27 1.27)
							)
						)
					)
					(number "AF4"
						(effects
							(font
								(size 1.27 1.27)
							)
						)
					)
				)
				(pin bidirectional line
					(at 0 -114.3 0)
					(length 5.08)
					(name "IO_L22P_T3_34"
						(effects
							(font
								(size 1.27 1.27)
							)
						)
					)
					(number "AE3"
						(effects
							(font
								(size 1.27 1.27)
							)
						)
					)
				)
				(pin bidirectional line
					(at 0 -116.84 0)
					(length 5.08)
					(name "IO_L22N_T3_34"
						(effects
							(font
								(size 1.27 1.27)
							)
						)
					)
					(number "AE2"
						(effects
							(font
								(size 1.27 1.27)
							)
						)
					)
				)
				(pin bidirectional line
					(at 0 -119.38 0)
					(length 5.08)
					(name "IO_L23P_T3_34"
						(effects
							(font
								(size 1.27 1.27)
							)
						)
					)
					(number "AE6"
						(effects
							(font
								(size 1.27 1.27)
							)
						)
					)
				)
				(pin bidirectional line
					(at 0 -121.92 0)
					(length 5.08)
					(name "IO_L23N_T3_34"
						(effects
							(font
								(size 1.27 1.27)
							)
						)
					)
					(number "AE5"
						(effects
							(font
								(size 1.27 1.27)
							)
						)
					)
				)
				(pin bidirectional line
					(at 0 -124.46 0)
					(length 5.08)
					(name "IO_L24P_T3_34"
						(effects
							(font
								(size 1.27 1.27)
							)
						)
					)
					(number "AF3"
						(effects
							(font
								(size 1.27 1.27)
							)
						)
					)
				)
				(pin bidirectional line
					(at 0 -127 0)
					(length 5.08)
					(name "IO_L24N_T3_34"
						(effects
							(font
								(size 1.27 1.27)
							)
						)
					)
					(number "AF2"
						(effects
							(font
								(size 1.27 1.27)
							)
						)
					)
				)
				(pin bidirectional line
					(at 0 -129.54 0)
					(length 5.08)
					(name "IO_25_VRP_34"
						(effects
							(font
								(size 1.27 1.27)
							)
						)
					)
					(number "T7"
						(effects
							(font
								(size 1.27 1.27)
							)
						)
					)
				)
			)
			(symbol "XC7K160T-FFG676_9_1"
				(rectangle
					(start 5.08 6.35)
					(end 49.53 -58.42)
					(stroke
						(width 0.254)
						(type default)
					)
					(fill
						(type background)
					)
				)
				(polyline
					(pts
						(xy 16.51 2.54) (xy 24.13 2.54) (xy 24.13 -55.88) (xy 16.51 -55.88)
					)
					(stroke
						(width 0.254)
						(type default)
					)
					(fill
						(type background)
					)
				)
				(polyline
					(pts
						(xy 38.1 2.54) (xy 30.48 2.54) (xy 30.48 -55.88) (xy 38.1 -55.88)
					)
					(stroke
						(width 0.254)
						(type default)
					)
					(fill
						(type background)
					)
				)
				(text "GTX 115"
					(at 15.24 3.81 0)
					(effects
						(font
							(size 1.27 1.27)
							(thickness 0.15)
						)
						(justify left bottom)
					)
				)
				(text "GTX 116"
					(at 30.48 3.81 0)
					(effects
						(font
							(size 1.27 1.27)
							(thickness 0.15)
						)
						(justify left bottom)
					)
				)
				(pin bidirectional line
					(at 0 0 0)
					(length 5.08)
					(name "MGTXTXP0_115"
						(effects
							(font
								(size 1.27 1.27)
							)
						)
					)
					(number "P2"
						(effects
							(font
								(size 1.27 1.27)
							)
						)
					)
				)
				(pin bidirectional line
					(at 0 -2.54 0)
					(length 5.08)
					(name "MGTXTXN0_115"
						(effects
							(font
								(size 1.27 1.27)
							)
						)
					)
					(number "P1"
						(effects
							(font
								(size 1.27 1.27)
							)
						)
					)
				)
				(pin bidirectional line
					(at 0 -5.08 0)
					(length 5.08)
					(name "MGTXTXP1_115"
						(effects
							(font
								(size 1.27 1.27)
							)
						)
					)
					(number "M2"
						(effects
							(font
								(size 1.27 1.27)
							)
						)
					)
				)
				(pin bidirectional line
					(at 0 -7.62 0)
					(length 5.08)
					(name "MGTXTXN1_115"
						(effects
							(font
								(size 1.27 1.27)
							)
						)
					)
					(number "M1"
						(effects
							(font
								(size 1.27 1.27)
							)
						)
					)
				)
				(pin bidirectional line
					(at 0 -10.16 0)
					(length 5.08)
					(name "MGTXTXP2_115"
						(effects
							(font
								(size 1.27 1.27)
							)
						)
					)
					(number "K2"
						(effects
							(font
								(size 1.27 1.27)
							)
						)
					)
				)
				(pin bidirectional line
					(at 0 -12.7 0)
					(length 5.08)
					(name "MGTXTXN2_115"
						(effects
							(font
								(size 1.27 1.27)
							)
						)
					)
					(number "K1"
						(effects
							(font
								(size 1.27 1.27)
							)
						)
					)
				)
				(pin bidirectional line
					(at 0 -15.24 0)
					(length 5.08)
					(name "MGTXTXP3_115"
						(effects
							(font
								(size 1.27 1.27)
							)
						)
					)
					(number "H2"
						(effects
							(font
								(size 1.27 1.27)
							)
						)
					)
				)
				(pin bidirectional line
					(at 0 -17.78 0)
					(length 5.08)
					(name "MGTXTXN3_115"
						(effects
							(font
								(size 1.27 1.27)
							)
						)
					)
					(number "H1"
						(effects
							(font
								(size 1.27 1.27)
							)
						)
					)
				)
				(pin bidirectional line
					(at 0 -22.86 0)
					(length 5.08)
					(name "MGTXRXP0_115"
						(effects
							(font
								(size 1.27 1.27)
							)
						)
					)
					(number "R4"
						(effects
							(font
								(size 1.27 1.27)
							)
						)
					)
				)
				(pin bidirectional line
					(at 0 -25.4 0)
					(length 5.08)
					(name "MGTXRXN0_115"
						(effects
							(font
								(size 1.27 1.27)
							)
						)
					)
					(number "R3"
						(effects
							(font
								(size 1.27 1.27)
							)
						)
					)
				)
				(pin bidirectional line
					(at 0 -27.94 0)
					(length 5.08)
					(name "MGTXRXP1_115"
						(effects
							(font
								(size 1.27 1.27)
							)
						)
					)
					(number "N4"
						(effects
							(font
								(size 1.27 1.27)
							)
						)
					)
				)
				(pin bidirectional line
					(at 0 -30.48 0)
					(length 5.08)
					(name "MGTXRXN1_115"
						(effects
							(font
								(size 1.27 1.27)
							)
						)
					)
					(number "N3"
						(effects
							(font
								(size 1.27 1.27)
							)
						)
					)
				)
				(pin bidirectional line
					(at 0 -33.02 0)
					(length 5.08)
					(name "MGTXRXP2_115"
						(effects
							(font
								(size 1.27 1.27)
							)
						)
					)
					(number "L4"
						(effects
							(font
								(size 1.27 1.27)
							)
						)
					)
				)
				(pin bidirectional line
					(at 0 -35.56 0)
					(length 5.08)
					(name "MGTXRXN2_115"
						(effects
							(font
								(size 1.27 1.27)
							)
						)
					)
					(number "L3"
						(effects
							(font
								(size 1.27 1.27)
							)
						)
					)
				)
				(pin bidirectional line
					(at 0 -38.1 0)
					(length 5.08)
					(name "MGTXRXP3_115"
						(effects
							(font
								(size 1.27 1.27)
							)
						)
					)
					(number "J4"
						(effects
							(font
								(size 1.27 1.27)
							)
						)
					)
				)
				(pin bidirectional line
					(at 0 -40.64 0)
					(length 5.08)
					(name "MGTXRXN3_115"
						(effects
							(font
								(size 1.27 1.27)
							)
						)
					)
					(number "J3"
						(effects
							(font
								(size 1.27 1.27)
							)
						)
					)
				)
				(pin bidirectional line
					(at 0 -45.72 0)
					(length 5.08)
					(name "MGTREFCLK0P_115"
						(effects
							(font
								(size 1.27 1.27)
							)
						)
					)
					(number "H6"
						(effects
							(font
								(size 1.27 1.27)
							)
						)
					)
				)
				(pin bidirectional line
					(at 0 -48.26 0)
					(length 5.08)
					(name "MGTREFCLK0N_115"
						(effects
							(font
								(size 1.27 1.27)
							)
						)
					)
					(number "H5"
						(effects
							(font
								(size 1.27 1.27)
							)
						)
					)
				)
				(pin bidirectional line
					(at 0 -50.8 0)
					(length 5.08)
					(name "MGTREFCLK1P_115"
						(effects
							(font
								(size 1.27 1.27)
							)
						)
					)
					(number "K6"
						(effects
							(font
								(size 1.27 1.27)
							)
						)
					)
				)
				(pin bidirectional line
					(at 0 -53.34 0)
					(length 5.08)
					(name "MGTREFCLK1N_115"
						(effects
							(font
								(size 1.27 1.27)
							)
						)
					)
					(number "K5"
						(effects
							(font
								(size 1.27 1.27)
							)
						)
					)
				)
				(pin bidirectional line
					(at 54.61 0 180)
					(length 5.08)
					(name "MGTXTXP0_116"
						(effects
							(font
								(size 1.27 1.27)
							)
						)
					)
					(number "F2"
						(effects
							(font
								(size 1.27 1.27)
							)
						)
					)
				)
				(pin bidirectional line
					(at 54.61 -2.54 180)
					(length 5.08)
					(name "MGTXTXN0_116"
						(effects
							(font
								(size 1.27 1.27)
							)
						)
					)
					(number "F1"
						(effects
							(font
								(size 1.27 1.27)
							)
						)
					)
				)
				(pin bidirectional line
					(at 54.61 -5.08 180)
					(length 5.08)
					(name "MGTXTXP1_116"
						(effects
							(font
								(size 1.27 1.27)
							)
						)
					)
					(number "D2"
						(effects
							(font
								(size 1.27 1.27)
							)
						)
					)
				)
				(pin bidirectional line
					(at 54.61 -7.62 180)
					(length 5.08)
					(name "MGTXTXN1_116"
						(effects
							(font
								(size 1.27 1.27)
							)
						)
					)
					(number "D1"
						(effects
							(font
								(size 1.27 1.27)
							)
						)
					)
				)
				(pin bidirectional line
					(at 54.61 -10.16 180)
					(length 5.08)
					(name "MGTXTXP2_116"
						(effects
							(font
								(size 1.27 1.27)
							)
						)
					)
					(number "B2"
						(effects
							(font
								(size 1.27 1.27)
							)
						)
					)
				)
				(pin bidirectional line
					(at 54.61 -12.7 180)
					(length 5.08)
					(name "MGTXTXN2_116"
						(effects
							(font
								(size 1.27 1.27)
							)
						)
					)
					(number "B1"
						(effects
							(font
								(size 1.27 1.27)
							)
						)
					)
				)
				(pin bidirectional line
					(at 54.61 -15.24 180)
					(length 5.08)
					(name "MGTXTXP3_116"
						(effects
							(font
								(size 1.27 1.27)
							)
						)
					)
					(number "A4"
						(effects
							(font
								(size 1.27 1.27)
							)
						)
					)
				)
				(pin bidirectional line
					(at 54.61 -17.78 180)
					(length 5.08)
					(name "MGTXTXN3_116"
						(effects
							(font
								(size 1.27 1.27)
							)
						)
					)
					(number "A3"
						(effects
							(font
								(size 1.27 1.27)
							)
						)
					)
				)
				(pin bidirectional line
					(at 54.61 -22.86 180)
					(length 5.08)
					(name "MGTXRXP0_116"
						(effects
							(font
								(size 1.27 1.27)
							)
						)
					)
					(number "G4"
						(effects
							(font
								(size 1.27 1.27)
							)
						)
					)
				)
				(pin bidirectional line
					(at 54.61 -25.4 180)
					(length 5.08)
					(name "MGTXRXN0_116"
						(effects
							(font
								(size 1.27 1.27)
							)
						)
					)
					(number "G3"
						(effects
							(font
								(size 1.27 1.27)
							)
						)
					)
				)
				(pin bidirectional line
					(at 54.61 -27.94 180)
					(length 5.08)
					(name "MGTXRXP1_116"
						(effects
							(font
								(size 1.27 1.27)
							)
						)
					)
					(number "E4"
						(effects
							(font
								(size 1.27 1.27)
							)
						)
					)
				)
				(pin bidirectional line
					(at 54.61 -30.48 180)
					(length 5.08)
					(name "MGTXRXN1_116"
						(effects
							(font
								(size 1.27 1.27)
							)
						)
					)
					(number "E3"
						(effects
							(font
								(size 1.27 1.27)
							)
						)
					)
				)
				(pin bidirectional line
					(at 54.61 -33.02 180)
					(length 5.08)
					(name "MGTXRXP2_116"
						(effects
							(font
								(size 1.27 1.27)
							)
						)
					)
					(number "C4"
						(effects
							(font
								(size 1.27 1.27)
							)
						)
					)
				)
				(pin bidirectional line
					(at 54.61 -35.56 180)
					(length 5.08)
					(name "MGTXRXN2_116"
						(effects
							(font
								(size 1.27 1.27)
							)
						)
					)
					(number "C3"
						(effects
							(font
								(size 1.27 1.27)
							)
						)
					)
				)
				(pin bidirectional line
					(at 54.61 -38.1 180)
					(length 5.08)
					(name "MGTXRXP3_116"
						(effects
							(font
								(size 1.27 1.27)
							)
						)
					)
					(number "B6"
						(effects
							(font
								(size 1.27 1.27)
							)
						)
					)
				)
				(pin bidirectional line
					(at 54.61 -40.64 180)
					(length 5.08)
					(name "MGTXRXN3_116"
						(effects
							(font
								(size 1.27 1.27)
							)
						)
					)
					(number "B5"
						(effects
							(font
								(size 1.27 1.27)
							)
						)
					)
				)
				(pin bidirectional line
					(at 54.61 -45.72 180)
					(length 5.08)
					(name "MGTREFCLK0P_116"
						(effects
							(font
								(size 1.27 1.27)
							)
						)
					)
					(number "D6"
						(effects
							(font
								(size 1.27 1.27)
							)
						)
					)
				)
				(pin bidirectional line
					(at 54.61 -48.26 180)
					(length 5.08)
					(name "MGTREFCLK0N_116"
						(effects
							(font
								(size 1.27 1.27)
							)
						)
					)
					(number "D5"
						(effects
							(font
								(size 1.27 1.27)
							)
						)
					)
				)
				(pin bidirectional line
					(at 54.61 -50.8 180)
					(length 5.08)
					(name "MGTREFCLK1P_116"
						(effects
							(font
								(size 1.27 1.27)
							)
						)
					)
					(number "F6"
						(effects
							(font
								(size 1.27 1.27)
							)
						)
					)
				)
				(pin bidirectional line
					(at 54.61 -53.34 180)
					(length 5.08)
					(name "MGTREFCLK1N_116"
						(effects
							(font
								(size 1.27 1.27)
							)
						)
					)
					(number "F5"
						(effects
							(font
								(size 1.27 1.27)
							)
						)
					)
				)
			)
			(symbol "XC7K160T-FFG676_10_1"
				(rectangle
					(start 5.08 2.54)
					(end 39.37 -33.02)
					(stroke
						(width 0.254)
						(type default)
					)
					(fill
						(type background)
					)
				)
				(pin power_in line
					(at 0 0 0)
					(length 5.08)
					(name "VCCINT"
						(effects
							(font
								(size 1.27 1.27)
							)
						)
					)
					(number "J9"
						(effects
							(font
								(size 1.27 1.27)
							)
						)
					)
				)
				(pin passive line
					(at 0 0 0)
					(length 5.08)
					(hide yes)
					(name "VCCINT"
						(effects
							(font
								(size 1.27 1.27)
							)
						)
					)
					(number "K10"
						(effects
							(font
								(size 1.27 1.27)
							)
						)
					)
				)
				(pin passive line
					(at 0 0 0)
					(length 5.08)
					(hide yes)
					(name "VCCINT"
						(effects
							(font
								(size 1.27 1.27)
							)
						)
					)
					(number "K12"
						(effects
							(font
								(size 1.27 1.27)
							)
						)
					)
				)
				(pin passive line
					(at 0 0 0)
					(length 5.08)
					(hide yes)
					(name "VCCINT"
						(effects
							(font
								(size 1.27 1.27)
							)
						)
					)
					(number "K14"
						(effects
							(font
								(size 1.27 1.27)
							)
						)
					)
				)
				(pin passive line
					(at 0 0 0)
					(length 5.08)
					(hide yes)
					(name "VCCINT"
						(effects
							(font
								(size 1.27 1.27)
							)
						)
					)
					(number "K8"
						(effects
							(font
								(size 1.27 1.27)
							)
						)
					)
				)
				(pin passive line
					(at 0 0 0)
					(length 5.08)
					(hide yes)
					(name "VCCINT"
						(effects
							(font
								(size 1.27 1.27)
							)
						)
					)
					(number "L13"
						(effects
							(font
								(size 1.27 1.27)
							)
						)
					)
				)
				(pin passive line
					(at 0 0 0)
					(length 5.08)
					(hide yes)
					(name "VCCINT"
						(effects
							(font
								(size 1.27 1.27)
							)
						)
					)
					(number "L15"
						(effects
							(font
								(size 1.27 1.27)
							)
						)
					)
				)
				(pin passive line
					(at 0 0 0)
					(length 5.08)
					(hide yes)
					(name "VCCINT"
						(effects
							(font
								(size 1.27 1.27)
							)
						)
					)
					(number "L9"
						(effects
							(font
								(size 1.27 1.27)
							)
						)
					)
				)
				(pin passive line
					(at 0 0 0)
					(length 5.08)
					(hide yes)
					(name "VCCINT"
						(effects
							(font
								(size 1.27 1.27)
							)
						)
					)
					(number "M14"
						(effects
							(font
								(size 1.27 1.27)
							)
						)
					)
				)
				(pin passive line
					(at 0 0 0)
					(length 5.08)
					(hide yes)
					(name "VCCINT"
						(effects
							(font
								(size 1.27 1.27)
							)
						)
					)
					(number "M8"
						(effects
							(font
								(size 1.27 1.27)
							)
						)
					)
				)
				(pin passive line
					(at 0 0 0)
					(length 5.08)
					(hide yes)
					(name "VCCINT"
						(effects
							(font
								(size 1.27 1.27)
							)
						)
					)
					(number "N15"
						(effects
							(font
								(size 1.27 1.27)
							)
						)
					)
				)
				(pin passive line
					(at 0 0 0)
					(length 5.08)
					(hide yes)
					(name "VCCINT"
						(effects
							(font
								(size 1.27 1.27)
							)
						)
					)
					(number "N9"
						(effects
							(font
								(size 1.27 1.27)
							)
						)
					)
				)
				(pin passive line
					(at 0 0 0)
					(length 5.08)
					(hide yes)
					(name "VCCINT"
						(effects
							(font
								(size 1.27 1.27)
							)
						)
					)
					(number "P14"
						(effects
							(font
								(size 1.27 1.27)
							)
						)
					)
				)
				(pin passive line
					(at 0 0 0)
					(length 5.08)
					(hide yes)
					(name "VCCINT"
						(effects
							(font
								(size 1.27 1.27)
							)
						)
					)
					(number "R15"
						(effects
							(font
								(size 1.27 1.27)
							)
						)
					)
				)
				(pin passive line
					(at 0 0 0)
					(length 5.08)
					(hide yes)
					(name "VCCINT"
						(effects
							(font
								(size 1.27 1.27)
							)
						)
					)
					(number "T14"
						(effects
							(font
								(size 1.27 1.27)
							)
						)
					)
				)
				(pin passive line
					(at 0 0 0)
					(length 5.08)
					(hide yes)
					(name "VCCINT"
						(effects
							(font
								(size 1.27 1.27)
							)
						)
					)
					(number "U15"
						(effects
							(font
								(size 1.27 1.27)
							)
						)
					)
				)
				(pin power_in line
					(at 0 -5.08 0)
					(length 5.08)
					(name "VCCAUX"
						(effects
							(font
								(size 1.27 1.27)
							)
						)
					)
					(number "L11"
						(effects
							(font
								(size 1.27 1.27)
							)
						)
					)
				)
				(pin passive line
					(at 0 -5.08 0)
					(length 5.08)
					(hide yes)
					(name "VCCAUX"
						(effects
							(font
								(size 1.27 1.27)
							)
						)
					)
					(number "M10"
						(effects
							(font
								(size 1.27 1.27)
							)
						)
					)
				)
				(pin passive line
					(at 0 -5.08 0)
					(length 5.08)
					(hide yes)
					(name "VCCAUX"
						(effects
							(font
								(size 1.27 1.27)
							)
						)
					)
					(number "P10"
						(effects
							(font
								(size 1.27 1.27)
							)
						)
					)
				)
				(pin passive line
					(at 0 -5.08 0)
					(length 5.08)
					(hide yes)
					(name "VCCAUX"
						(effects
							(font
								(size 1.27 1.27)
							)
						)
					)
					(number "T10"
						(effects
							(font
								(size 1.27 1.27)
							)
						)
					)
				)
				(pin passive line
					(at 0 -5.08 0)
					(length 5.08)
					(hide yes)
					(name "VCCAUX"
						(effects
							(font
								(size 1.27 1.27)
							)
						)
					)
					(number "U11"
						(effects
							(font
								(size 1.27 1.27)
							)
						)
					)
				)
				(pin power_in line
					(at 0 -7.62 0)
					(length 5.08)
					(name "VCCAUX_IO_G0"
						(effects
							(font
								(size 1.27 1.27)
							)
						)
					)
					(number "P8"
						(effects
							(font
								(size 1.27 1.27)
							)
						)
					)
				)
				(pin passive line
					(at 0 -7.62 0)
					(length 5.08)
					(hide yes)
					(name "VCCAUX_IO_G0"
						(effects
							(font
								(size 1.27 1.27)
							)
						)
					)
					(number "R9"
						(effects
							(font
								(size 1.27 1.27)
							)
						)
					)
				)
				(pin passive line
					(at 0 -7.62 0)
					(length 5.08)
					(hide yes)
					(name "VCCAUX_IO_G0"
						(effects
							(font
								(size 1.27 1.27)
							)
						)
					)
					(number "T8"
						(effects
							(font
								(size 1.27 1.27)
							)
						)
					)
				)
				(pin power_in line
					(at 0 -12.7 0)
					(length 5.08)
					(name "VCCADC_0"
						(effects
							(font
								(size 1.27 1.27)
							)
						)
					)
					(number "M12"
						(effects
							(font
								(size 1.27 1.27)
							)
						)
					)
				)
				(pin power_in line
					(at 0 -15.24 0)
					(length 5.08)
					(name "GNDADC_0"
						(effects
							(font
								(size 1.27 1.27)
							)
						)
					)
					(number "M11"
						(effects
							(font
								(size 1.27 1.27)
							)
						)
					)
				)
				(pin power_in line
					(at 0 -20.32 0)
					(length 5.08)
					(name "VCCBATT_0"
						(effects
							(font
								(size 1.27 1.27)
							)
						)
					)
					(number "E8"
						(effects
							(font
								(size 1.27 1.27)
							)
						)
					)
				)
				(pin power_in line
					(at 0 -25.4 0)
					(length 5.08)
					(name "VCCBRAM"
						(effects
							(font
								(size 1.27 1.27)
							)
						)
					)
					(number "N13"
						(effects
							(font
								(size 1.27 1.27)
							)
						)
					)
				)
				(pin passive line
					(at 0 -25.4 0)
					(length 5.08)
					(hide yes)
					(name "VCCBRAM"
						(effects
							(font
								(size 1.27 1.27)
							)
						)
					)
					(number "R13"
						(effects
							(font
								(size 1.27 1.27)
							)
						)
					)
				)
				(pin passive line
					(at 0 -25.4 0)
					(length 5.08)
					(hide yes)
					(name "VCCBRAM"
						(effects
							(font
								(size 1.27 1.27)
							)
						)
					)
					(number "T12"
						(effects
							(font
								(size 1.27 1.27)
							)
						)
					)
				)
				(pin passive line
					(at 0 -25.4 0)
					(length 5.08)
					(hide yes)
					(name "VCCBRAM"
						(effects
							(font
								(size 1.27 1.27)
							)
						)
					)
					(number "U13"
						(effects
							(font
								(size 1.27 1.27)
							)
						)
					)
				)
				(pin power_in line
					(at 0 -30.48 0)
					(length 5.08)
					(name "GND"
						(effects
							(font
								(size 1.27 1.27)
							)
						)
					)
					(number "A1"
						(effects
							(font
								(size 1.27 1.27)
							)
						)
					)
				)
				(pin passive line
					(at 0 -30.48 0)
					(length 5.08)
					(hide yes)
					(name "GND"
						(effects
							(font
								(size 1.27 1.27)
							)
						)
					)
					(number "A16"
						(effects
							(font
								(size 1.27 1.27)
							)
						)
					)
				)
				(pin passive line
					(at 0 -30.48 0)
					(length 5.08)
					(hide yes)
					(name "GND"
						(effects
							(font
								(size 1.27 1.27)
							)
						)
					)
					(number "A2"
						(effects
							(font
								(size 1.27 1.27)
							)
						)
					)
				)
				(pin passive line
					(at 0 -30.48 0)
					(length 5.08)
					(hide yes)
					(name "GND"
						(effects
							(font
								(size 1.27 1.27)
							)
						)
					)
					(number "A26"
						(effects
							(font
								(size 1.27 1.27)
							)
						)
					)
				)
				(pin passive line
					(at 0 -30.48 0)
					(length 5.08)
					(hide yes)
					(name "GND"
						(effects
							(font
								(size 1.27 1.27)
							)
						)
					)
					(number "A5"
						(effects
							(font
								(size 1.27 1.27)
							)
						)
					)
				)
				(pin passive line
					(at 0 -30.48 0)
					(length 5.08)
					(hide yes)
					(name "GND"
						(effects
							(font
								(size 1.27 1.27)
							)
						)
					)
					(number "A6"
						(effects
							(font
								(size 1.27 1.27)
							)
						)
					)
				)
				(pin passive line
					(at 0 -30.48 0)
					(length 5.08)
					(hide yes)
					(name "GND"
						(effects
							(font
								(size 1.27 1.27)
							)
						)
					)
					(number "A7"
						(effects
							(font
								(size 1.27 1.27)
							)
						)
					)
				)
				(pin passive line
					(at 0 -30.48 0)
					(length 5.08)
					(hide yes)
					(name "GND"
						(effects
							(font
								(size 1.27 1.27)
							)
						)
					)
					(number "AA16"
						(effects
							(font
								(size 1.27 1.27)
							)
						)
					)
				)
				(pin passive line
					(at 0 -30.48 0)
					(length 5.08)
					(hide yes)
					(name "GND"
						(effects
							(font
								(size 1.27 1.27)
							)
						)
					)
					(number "AA26"
						(effects
							(font
								(size 1.27 1.27)
							)
						)
					)
				)
				(pin passive line
					(at 0 -30.48 0)
					(length 5.08)
					(hide yes)
					(name "GND"
						(effects
							(font
								(size 1.27 1.27)
							)
						)
					)
					(number "AA6"
						(effects
							(font
								(size 1.27 1.27)
							)
						)
					)
				)
				(pin passive line
					(at 0 -30.48 0)
					(length 5.08)
					(hide yes)
					(name "GND"
						(effects
							(font
								(size 1.27 1.27)
							)
						)
					)
					(number "AB13"
						(effects
							(font
								(size 1.27 1.27)
							)
						)
					)
				)
				(pin passive line
					(at 0 -30.48 0)
					(length 5.08)
					(hide yes)
					(name "GND"
						(effects
							(font
								(size 1.27 1.27)
							)
						)
					)
					(number "AB23"
						(effects
							(font
								(size 1.27 1.27)
							)
						)
					)
				)
				(pin passive line
					(at 0 -30.48 0)
					(length 5.08)
					(hide yes)
					(name "GND"
						(effects
							(font
								(size 1.27 1.27)
							)
						)
					)
					(number "AB3"
						(effects
							(font
								(size 1.27 1.27)
							)
						)
					)
				)
				(pin passive line
					(at 0 -30.48 0)
					(length 5.08)
					(hide yes)
					(name "GND"
						(effects
							(font
								(size 1.27 1.27)
							)
						)
					)
					(number "AC10"
						(effects
							(font
								(size 1.27 1.27)
							)
						)
					)
				)
				(pin passive line
					(at 0 -30.48 0)
					(length 5.08)
					(hide yes)
					(name "GND"
						(effects
							(font
								(size 1.27 1.27)
							)
						)
					)
					(number "AC20"
						(effects
							(font
								(size 1.27 1.27)
							)
						)
					)
				)
				(pin passive line
					(at 0 -30.48 0)
					(length 5.08)
					(hide yes)
					(name "GND"
						(effects
							(font
								(size 1.27 1.27)
							)
						)
					)
					(number "AD17"
						(effects
							(font
								(size 1.27 1.27)
							)
						)
					)
				)
				(pin passive line
					(at 0 -30.48 0)
					(length 5.08)
					(hide yes)
					(name "GND"
						(effects
							(font
								(size 1.27 1.27)
							)
						)
					)
					(number "AD7"
						(effects
							(font
								(size 1.27 1.27)
							)
						)
					)
				)
				(pin passive line
					(at 0 -30.48 0)
					(length 5.08)
					(hide yes)
					(name "GND"
						(effects
							(font
								(size 1.27 1.27)
							)
						)
					)
					(number "AE14"
						(effects
							(font
								(size 1.27 1.27)
							)
						)
					)
				)
				(pin passive line
					(at 0 -30.48 0)
					(length 5.08)
					(hide yes)
					(name "GND"
						(effects
							(font
								(size 1.27 1.27)
							)
						)
					)
					(number "AE24"
						(effects
							(font
								(size 1.27 1.27)
							)
						)
					)
				)
				(pin passive line
					(at 0 -30.48 0)
					(length 5.08)
					(hide yes)
					(name "GND"
						(effects
							(font
								(size 1.27 1.27)
							)
						)
					)
					(number "AE4"
						(effects
							(font
								(size 1.27 1.27)
							)
						)
					)
				)
				(pin passive line
					(at 0 -30.48 0)
					(length 5.08)
					(hide yes)
					(name "GND"
						(effects
							(font
								(size 1.27 1.27)
							)
						)
					)
					(number "AF1"
						(effects
							(font
								(size 1.27 1.27)
							)
						)
					)
				)
				(pin passive line
					(at 0 -30.48 0)
					(length 5.08)
					(hide yes)
					(name "GND"
						(effects
							(font
								(size 1.27 1.27)
							)
						)
					)
					(number "AF11"
						(effects
							(font
								(size 1.27 1.27)
							)
						)
					)
				)
				(pin passive line
					(at 0 -30.48 0)
					(length 5.08)
					(hide yes)
					(name "GND"
						(effects
							(font
								(size 1.27 1.27)
							)
						)
					)
					(number "AF21"
						(effects
							(font
								(size 1.27 1.27)
							)
						)
					)
				)
				(pin passive line
					(at 0 -30.48 0)
					(length 5.08)
					(hide yes)
					(name "GND"
						(effects
							(font
								(size 1.27 1.27)
							)
						)
					)
					(number "B13"
						(effects
							(font
								(size 1.27 1.27)
							)
						)
					)
				)
				(pin passive line
					(at 0 -30.48 0)
					(length 5.08)
					(hide yes)
					(name "GND"
						(effects
							(font
								(size 1.27 1.27)
							)
						)
					)
					(number "B23"
						(effects
							(font
								(size 1.27 1.27)
							)
						)
					)
				)
				(pin passive line
					(at 0 -30.48 0)
					(length 5.08)
					(hide yes)
					(name "GND"
						(effects
							(font
								(size 1.27 1.27)
							)
						)
					)
					(number "B4"
						(effects
							(font
								(size 1.27 1.27)
							)
						)
					)
				)
				(pin passive line
					(at 0 -30.48 0)
					(length 5.08)
					(hide yes)
					(name "GND"
						(effects
							(font
								(size 1.27 1.27)
							)
						)
					)
					(number "B7"
						(effects
							(font
								(size 1.27 1.27)
							)
						)
					)
				)
				(pin passive line
					(at 0 -30.48 0)
					(length 5.08)
					(hide yes)
					(name "GND"
						(effects
							(font
								(size 1.27 1.27)
							)
						)
					)
					(number "C1"
						(effects
							(font
								(size 1.27 1.27)
							)
						)
					)
				)
				(pin passive line
					(at 0 -30.48 0)
					(length 5.08)
					(hide yes)
					(name "GND"
						(effects
							(font
								(size 1.27 1.27)
							)
						)
					)
					(number "C10"
						(effects
							(font
								(size 1.27 1.27)
							)
						)
					)
				)
				(pin passive line
					(at 0 -30.48 0)
					(length 5.08)
					(hide yes)
					(name "GND"
						(effects
							(font
								(size 1.27 1.27)
							)
						)
					)
					(number "C20"
						(effects
							(font
								(size 1.27 1.27)
							)
						)
					)
				)
				(pin passive line
					(at 0 -30.48 0)
					(length 5.08)
					(hide yes)
					(name "GND"
						(effects
							(font
								(size 1.27 1.27)
							)
						)
					)
					(number "C5"
						(effects
							(font
								(size 1.27 1.27)
							)
						)
					)
				)
				(pin passive line
					(at 0 -30.48 0)
					(length 5.08)
					(hide yes)
					(name "GND"
						(effects
							(font
								(size 1.27 1.27)
							)
						)
					)
					(number "C7"
						(effects
							(font
								(size 1.27 1.27)
							)
						)
					)
				)
				(pin passive line
					(at 0 -30.48 0)
					(length 5.08)
					(hide yes)
					(name "GND"
						(effects
							(font
								(size 1.27 1.27)
							)
						)
					)
					(number "D17"
						(effects
							(font
								(size 1.27 1.27)
							)
						)
					)
				)
				(pin passive line
					(at 0 -30.48 0)
					(length 5.08)
					(hide yes)
					(name "GND"
						(effects
							(font
								(size 1.27 1.27)
							)
						)
					)
					(number "D4"
						(effects
							(font
								(size 1.27 1.27)
							)
						)
					)
				)
				(pin passive line
					(at 0 -30.48 0)
					(length 5.08)
					(hide yes)
					(name "GND"
						(effects
							(font
								(size 1.27 1.27)
							)
						)
					)
					(number "D7"
						(effects
							(font
								(size 1.27 1.27)
							)
						)
					)
				)
				(pin passive line
					(at 0 -30.48 0)
					(length 5.08)
					(hide yes)
					(name "GND"
						(effects
							(font
								(size 1.27 1.27)
							)
						)
					)
					(number "E1"
						(effects
							(font
								(size 1.27 1.27)
							)
						)
					)
				)
				(pin passive line
					(at 0 -30.48 0)
					(length 5.08)
					(hide yes)
					(name "GND"
						(effects
							(font
								(size 1.27 1.27)
							)
						)
					)
					(number "E14"
						(effects
							(font
								(size 1.27 1.27)
							)
						)
					)
				)
				(pin passive line
					(at 0 -30.48 0)
					(length 5.08)
					(hide yes)
					(name "GND"
						(effects
							(font
								(size 1.27 1.27)
							)
						)
					)
					(number "E2"
						(effects
							(font
								(size 1.27 1.27)
							)
						)
					)
				)
				(pin passive line
					(at 0 -30.48 0)
					(length 5.08)
					(hide yes)
					(name "GND"
						(effects
							(font
								(size 1.27 1.27)
							)
						)
					)
					(number "E24"
						(effects
							(font
								(size 1.27 1.27)
							)
						)
					)
				)
				(pin passive line
					(at 0 -30.48 0)
					(length 5.08)
					(hide yes)
					(name "GND"
						(effects
							(font
								(size 1.27 1.27)
							)
						)
					)
					(number "E5"
						(effects
							(font
								(size 1.27 1.27)
							)
						)
					)
				)
				(pin passive line
					(at 0 -30.48 0)
					(length 5.08)
					(hide yes)
					(name "GND"
						(effects
							(font
								(size 1.27 1.27)
							)
						)
					)
					(number "E7"
						(effects
							(font
								(size 1.27 1.27)
							)
						)
					)
				)
				(pin passive line
					(at 0 -30.48 0)
					(length 5.08)
					(hide yes)
					(name "GND"
						(effects
							(font
								(size 1.27 1.27)
							)
						)
					)
					(number "F11"
						(effects
							(font
								(size 1.27 1.27)
							)
						)
					)
				)
				(pin passive line
					(at 0 -30.48 0)
					(length 5.08)
					(hide yes)
					(name "GND"
						(effects
							(font
								(size 1.27 1.27)
							)
						)
					)
					(number "F21"
						(effects
							(font
								(size 1.27 1.27)
							)
						)
					)
				)
				(pin passive line
					(at 0 -30.48 0)
					(length 5.08)
					(hide yes)
					(name "GND"
						(effects
							(font
								(size 1.27 1.27)
							)
						)
					)
					(number "F3"
						(effects
							(font
								(size 1.27 1.27)
							)
						)
					)
				)
				(pin passive line
					(at 0 -30.48 0)
					(length 5.08)
					(hide yes)
					(name "GND"
						(effects
							(font
								(size 1.27 1.27)
							)
						)
					)
					(number "F4"
						(effects
							(font
								(size 1.27 1.27)
							)
						)
					)
				)
				(pin passive line
					(at 0 -30.48 0)
					(length 5.08)
					(hide yes)
					(name "GND"
						(effects
							(font
								(size 1.27 1.27)
							)
						)
					)
					(number "F7"
						(effects
							(font
								(size 1.27 1.27)
							)
						)
					)
				)
				(pin passive line
					(at 0 -30.48 0)
					(length 5.08)
					(hide yes)
					(name "GND"
						(effects
							(font
								(size 1.27 1.27)
							)
						)
					)
					(number "G1"
						(effects
							(font
								(size 1.27 1.27)
							)
						)
					)
				)
				(pin passive line
					(at 0 -30.48 0)
					(length 5.08)
					(hide yes)
					(name "GND"
						(effects
							(font
								(size 1.27 1.27)
							)
						)
					)
					(number "G18"
						(effects
							(font
								(size 1.27 1.27)
							)
						)
					)
				)
				(pin passive line
					(at 0 -30.48 0)
					(length 5.08)
					(hide yes)
					(name "GND"
						(effects
							(font
								(size 1.27 1.27)
							)
						)
					)
					(number "G5"
						(effects
							(font
								(size 1.27 1.27)
							)
						)
					)
				)
				(pin passive line
					(at 0 -30.48 0)
					(length 5.08)
					(hide yes)
					(name "GND"
						(effects
							(font
								(size 1.27 1.27)
							)
						)
					)
					(number "G8"
						(effects
							(font
								(size 1.27 1.27)
							)
						)
					)
				)
				(pin passive line
					(at 0 -30.48 0)
					(length 5.08)
					(hide yes)
					(name "GND"
						(effects
							(font
								(size 1.27 1.27)
							)
						)
					)
					(number "H15"
						(effects
							(font
								(size 1.27 1.27)
							)
						)
					)
				)
				(pin passive line
					(at 0 -30.48 0)
					(length 5.08)
					(hide yes)
					(name "GND"
						(effects
							(font
								(size 1.27 1.27)
							)
						)
					)
					(number "H25"
						(effects
							(font
								(size 1.27 1.27)
							)
						)
					)
				)
				(pin passive line
					(at 0 -30.48 0)
					(length 5.08)
					(hide yes)
					(name "GND"
						(effects
							(font
								(size 1.27 1.27)
							)
						)
					)
					(number "H4"
						(effects
							(font
								(size 1.27 1.27)
							)
						)
					)
				)
				(pin passive line
					(at 0 -30.48 0)
					(length 5.08)
					(hide yes)
					(name "GND"
						(effects
							(font
								(size 1.27 1.27)
							)
						)
					)
					(number "H7"
						(effects
							(font
								(size 1.27 1.27)
							)
						)
					)
				)
				(pin passive line
					(at 0 -30.48 0)
					(length 5.08)
					(hide yes)
					(name "GND"
						(effects
							(font
								(size 1.27 1.27)
							)
						)
					)
					(number "J1"
						(effects
							(font
								(size 1.27 1.27)
							)
						)
					)
				)
				(pin passive line
					(at 0 -30.48 0)
					(length 5.08)
					(hide yes)
					(name "GND"
						(effects
							(font
								(size 1.27 1.27)
							)
						)
					)
					(number "J12"
						(effects
							(font
								(size 1.27 1.27)
							)
						)
					)
				)
				(pin passive line
					(at 0 -30.48 0)
					(length 5.08)
					(hide yes)
					(name "GND"
						(effects
							(font
								(size 1.27 1.27)
							)
						)
					)
					(number "J2"
						(effects
							(font
								(size 1.27 1.27)
							)
						)
					)
				)
				(pin passive line
					(at 0 -30.48 0)
					(length 5.08)
					(hide yes)
					(name "GND"
						(effects
							(font
								(size 1.27 1.27)
							)
						)
					)
					(number "J22"
						(effects
							(font
								(size 1.27 1.27)
							)
						)
					)
				)
				(pin passive line
					(at 0 -30.48 0)
					(length 5.08)
					(hide yes)
					(name "GND"
						(effects
							(font
								(size 1.27 1.27)
							)
						)
					)
					(number "J5"
						(effects
							(font
								(size 1.27 1.27)
							)
						)
					)
				)
				(pin passive line
					(at 0 -30.48 0)
					(length 5.08)
					(hide yes)
					(name "GND"
						(effects
							(font
								(size 1.27 1.27)
							)
						)
					)
					(number "K11"
						(effects
							(font
								(size 1.27 1.27)
							)
						)
					)
				)
				(pin passive line
					(at 0 -30.48 0)
					(length 5.08)
					(hide yes)
					(name "GND"
						(effects
							(font
								(size 1.27 1.27)
							)
						)
					)
					(number "K13"
						(effects
							(font
								(size 1.27 1.27)
							)
						)
					)
				)
				(pin passive line
					(at 0 -30.48 0)
					(length 5.08)
					(hide yes)
					(name "GND"
						(effects
							(font
								(size 1.27 1.27)
							)
						)
					)
					(number "K19"
						(effects
							(font
								(size 1.27 1.27)
							)
						)
					)
				)
				(pin passive line
					(at 0 -30.48 0)
					(length 5.08)
					(hide yes)
					(name "GND"
						(effects
							(font
								(size 1.27 1.27)
							)
						)
					)
					(number "K3"
						(effects
							(font
								(size 1.27 1.27)
							)
						)
					)
				)
				(pin passive line
					(at 0 -30.48 0)
					(length 5.08)
					(hide yes)
					(name "GND"
						(effects
							(font
								(size 1.27 1.27)
							)
						)
					)
					(number "K4"
						(effects
							(font
								(size 1.27 1.27)
							)
						)
					)
				)
				(pin passive line
					(at 0 -30.48 0)
					(length 5.08)
					(hide yes)
					(name "GND"
						(effects
							(font
								(size 1.27 1.27)
							)
						)
					)
					(number "K7"
						(effects
							(font
								(size 1.27 1.27)
							)
						)
					)
				)
				(pin passive line
					(at 0 -30.48 0)
					(length 5.08)
					(hide yes)
					(name "GND"
						(effects
							(font
								(size 1.27 1.27)
							)
						)
					)
					(number "K9"
						(effects
							(font
								(size 1.27 1.27)
							)
						)
					)
				)
				(pin passive line
					(at 0 -30.48 0)
					(length 5.08)
					(hide yes)
					(name "GND"
						(effects
							(font
								(size 1.27 1.27)
							)
						)
					)
					(number "L1"
						(effects
							(font
								(size 1.27 1.27)
							)
						)
					)
				)
				(pin passive line
					(at 0 -30.48 0)
					(length 5.08)
					(hide yes)
					(name "GND"
						(effects
							(font
								(size 1.27 1.27)
							)
						)
					)
					(number "L10"
						(effects
							(font
								(size 1.27 1.27)
							)
						)
					)
				)
				(pin passive line
					(at 0 -30.48 0)
					(length 5.08)
					(hide yes)
					(name "GND"
						(effects
							(font
								(size 1.27 1.27)
							)
						)
					)
					(number "L12"
						(effects
							(font
								(size 1.27 1.27)
							)
						)
					)
				)
				(pin passive line
					(at 0 -30.48 0)
					(length 5.08)
					(hide yes)
					(name "GND"
						(effects
							(font
								(size 1.27 1.27)
							)
						)
					)
					(number "L14"
						(effects
							(font
								(size 1.27 1.27)
							)
						)
					)
				)
				(pin passive line
					(at 0 -30.48 0)
					(length 5.08)
					(hide yes)
					(name "GND"
						(effects
							(font
								(size 1.27 1.27)
							)
						)
					)
					(number "L16"
						(effects
							(font
								(size 1.27 1.27)
							)
						)
					)
				)
				(pin passive line
					(at 0 -30.48 0)
					(length 5.08)
					(hide yes)
					(name "GND"
						(effects
							(font
								(size 1.27 1.27)
							)
						)
					)
					(number "L26"
						(effects
							(font
								(size 1.27 1.27)
							)
						)
					)
				)
				(pin passive line
					(at 0 -30.48 0)
					(length 5.08)
					(hide yes)
					(name "GND"
						(effects
							(font
								(size 1.27 1.27)
							)
						)
					)
					(number "L5"
						(effects
							(font
								(size 1.27 1.27)
							)
						)
					)
				)
				(pin passive line
					(at 0 -30.48 0)
					(length 5.08)
					(hide yes)
					(name "GND"
						(effects
							(font
								(size 1.27 1.27)
							)
						)
					)
					(number "M13"
						(effects
							(font
								(size 1.27 1.27)
							)
						)
					)
				)
				(pin passive line
					(at 0 -30.48 0)
					(length 5.08)
					(hide yes)
					(name "GND"
						(effects
							(font
								(size 1.27 1.27)
							)
						)
					)
					(number "M15"
						(effects
							(font
								(size 1.27 1.27)
							)
						)
					)
				)
				(pin passive line
					(at 0 -30.48 0)
					(length 5.08)
					(hide yes)
					(name "GND"
						(effects
							(font
								(size 1.27 1.27)
							)
						)
					)
					(number "M23"
						(effects
							(font
								(size 1.27 1.27)
							)
						)
					)
				)
				(pin passive line
					(at 0 -30.48 0)
					(length 5.08)
					(hide yes)
					(name "GND"
						(effects
							(font
								(size 1.27 1.27)
							)
						)
					)
					(number "M4"
						(effects
							(font
								(size 1.27 1.27)
							)
						)
					)
				)
				(pin passive line
					(at 0 -30.48 0)
					(length 5.08)
					(hide yes)
					(name "GND"
						(effects
							(font
								(size 1.27 1.27)
							)
						)
					)
					(number "M7"
						(effects
							(font
								(size 1.27 1.27)
							)
						)
					)
				)
				(pin passive line
					(at 0 -30.48 0)
					(length 5.08)
					(hide yes)
					(name "GND"
						(effects
							(font
								(size 1.27 1.27)
							)
						)
					)
					(number "M9"
						(effects
							(font
								(size 1.27 1.27)
							)
						)
					)
				)
				(pin passive line
					(at 0 -30.48 0)
					(length 5.08)
					(hide yes)
					(name "GND"
						(effects
							(font
								(size 1.27 1.27)
							)
						)
					)
					(number "N1"
						(effects
							(font
								(size 1.27 1.27)
							)
						)
					)
				)
				(pin passive line
					(at 0 -30.48 0)
					(length 5.08)
					(hide yes)
					(name "GND"
						(effects
							(font
								(size 1.27 1.27)
							)
						)
					)
					(number "N10"
						(effects
							(font
								(size 1.27 1.27)
							)
						)
					)
				)
				(pin passive line
					(at 0 -30.48 0)
					(length 5.08)
					(hide yes)
					(name "GND"
						(effects
							(font
								(size 1.27 1.27)
							)
						)
					)
					(number "N14"
						(effects
							(font
								(size 1.27 1.27)
							)
						)
					)
				)
				(pin passive line
					(at 0 -30.48 0)
					(length 5.08)
					(hide yes)
					(name "GND"
						(effects
							(font
								(size 1.27 1.27)
							)
						)
					)
					(number "N2"
						(effects
							(font
								(size 1.27 1.27)
							)
						)
					)
				)
				(pin passive line
					(at 0 -30.48 0)
					(length 5.08)
					(hide yes)
					(name "GND"
						(effects
							(font
								(size 1.27 1.27)
							)
						)
					)
					(number "N20"
						(effects
							(font
								(size 1.27 1.27)
							)
						)
					)
				)
				(pin passive line
					(at 0 -30.48 0)
					(length 5.08)
					(hide yes)
					(name "GND"
						(effects
							(font
								(size 1.27 1.27)
							)
						)
					)
					(number "N5"
						(effects
							(font
								(size 1.27 1.27)
							)
						)
					)
				)
				(pin passive line
					(at 0 -30.48 0)
					(length 5.08)
					(hide yes)
					(name "GND"
						(effects
							(font
								(size 1.27 1.27)
							)
						)
					)
					(number "N7"
						(effects
							(font
								(size 1.27 1.27)
							)
						)
					)
				)
				(pin passive line
					(at 0 -30.48 0)
					(length 5.08)
					(hide yes)
					(name "GND"
						(effects
							(font
								(size 1.27 1.27)
							)
						)
					)
					(number "P13"
						(effects
							(font
								(size 1.27 1.27)
							)
						)
					)
				)
				(pin passive line
					(at 0 -30.48 0)
					(length 5.08)
					(hide yes)
					(name "GND"
						(effects
							(font
								(size 1.27 1.27)
							)
						)
					)
					(number "P15"
						(effects
							(font
								(size 1.27 1.27)
							)
						)
					)
				)
				(pin passive line
					(at 0 -30.48 0)
					(length 5.08)
					(hide yes)
					(name "GND"
						(effects
							(font
								(size 1.27 1.27)
							)
						)
					)
					(number "P17"
						(effects
							(font
								(size 1.27 1.27)
							)
						)
					)
				)
				(pin passive line
					(at 0 -30.48 0)
					(length 5.08)
					(hide yes)
					(name "GND"
						(effects
							(font
								(size 1.27 1.27)
							)
						)
					)
					(number "P3"
						(effects
							(font
								(size 1.27 1.27)
							)
						)
					)
				)
				(pin passive line
					(at 0 -30.48 0)
					(length 5.08)
					(hide yes)
					(name "GND"
						(effects
							(font
								(size 1.27 1.27)
							)
						)
					)
					(number "P4"
						(effects
							(font
								(size 1.27 1.27)
							)
						)
					)
				)
				(pin passive line
					(at 0 -30.48 0)
					(length 5.08)
					(hide yes)
					(name "GND"
						(effects
							(font
								(size 1.27 1.27)
							)
						)
					)
					(number "P9"
						(effects
							(font
								(size 1.27 1.27)
							)
						)
					)
				)
				(pin passive line
					(at 0 -30.48 0)
					(length 5.08)
					(hide yes)
					(name "GND"
						(effects
							(font
								(size 1.27 1.27)
							)
						)
					)
					(number "R1"
						(effects
							(font
								(size 1.27 1.27)
							)
						)
					)
				)
				(pin passive line
					(at 0 -30.48 0)
					(length 5.08)
					(hide yes)
					(name "GND"
						(effects
							(font
								(size 1.27 1.27)
							)
						)
					)
					(number "R10"
						(effects
							(font
								(size 1.27 1.27)
							)
						)
					)
				)
				(pin passive line
					(at 0 -30.48 0)
					(length 5.08)
					(hide yes)
					(name "GND"
						(effects
							(font
								(size 1.27 1.27)
							)
						)
					)
					(number "R14"
						(effects
							(font
								(size 1.27 1.27)
							)
						)
					)
				)
				(pin passive line
					(at 0 -30.48 0)
					(length 5.08)
					(hide yes)
					(name "GND"
						(effects
							(font
								(size 1.27 1.27)
							)
						)
					)
					(number "R2"
						(effects
							(font
								(size 1.27 1.27)
							)
						)
					)
				)
				(pin passive line
					(at 0 -30.48 0)
					(length 5.08)
					(hide yes)
					(name "GND"
						(effects
							(font
								(size 1.27 1.27)
							)
						)
					)
					(number "R24"
						(effects
							(font
								(size 1.27 1.27)
							)
						)
					)
				)
				(pin passive line
					(at 0 -30.48 0)
					(length 5.08)
					(hide yes)
					(name "GND"
						(effects
							(font
								(size 1.27 1.27)
							)
						)
					)
					(number "R5"
						(effects
							(font
								(size 1.27 1.27)
							)
						)
					)
				)
				(pin passive line
					(at 0 -30.48 0)
					(length 5.08)
					(hide yes)
					(name "GND"
						(effects
							(font
								(size 1.27 1.27)
							)
						)
					)
					(number "R8"
						(effects
							(font
								(size 1.27 1.27)
							)
						)
					)
				)
				(pin passive line
					(at 0 -30.48 0)
					(length 5.08)
					(hide yes)
					(name "GND"
						(effects
							(font
								(size 1.27 1.27)
							)
						)
					)
					(number "T1"
						(effects
							(font
								(size 1.27 1.27)
							)
						)
					)
				)
				(pin passive line
					(at 0 -30.48 0)
					(length 5.08)
					(hide yes)
					(name "GND"
						(effects
							(font
								(size 1.27 1.27)
							)
						)
					)
					(number "T11"
						(effects
							(font
								(size 1.27 1.27)
							)
						)
					)
				)
				(pin passive line
					(at 0 -30.48 0)
					(length 5.08)
					(hide yes)
					(name "GND"
						(effects
							(font
								(size 1.27 1.27)
							)
						)
					)
					(number "T13"
						(effects
							(font
								(size 1.27 1.27)
							)
						)
					)
				)
				(pin passive line
					(at 0 -30.48 0)
					(length 5.08)
					(hide yes)
					(name "GND"
						(effects
							(font
								(size 1.27 1.27)
							)
						)
					)
					(number "T15"
						(effects
							(font
								(size 1.27 1.27)
							)
						)
					)
				)
				(pin passive line
					(at 0 -30.48 0)
					(length 5.08)
					(hide yes)
					(name "GND"
						(effects
							(font
								(size 1.27 1.27)
							)
						)
					)
					(number "T21"
						(effects
							(font
								(size 1.27 1.27)
							)
						)
					)
				)
				(pin passive line
					(at 0 -30.48 0)
					(length 5.08)
					(hide yes)
					(name "GND"
						(effects
							(font
								(size 1.27 1.27)
							)
						)
					)
					(number "T3"
						(effects
							(font
								(size 1.27 1.27)
							)
						)
					)
				)
				(pin passive line
					(at 0 -30.48 0)
					(length 5.08)
					(hide yes)
					(name "GND"
						(effects
							(font
								(size 1.27 1.27)
							)
						)
					)
					(number "T4"
						(effects
							(font
								(size 1.27 1.27)
							)
						)
					)
				)
				(pin passive line
					(at 0 -30.48 0)
					(length 5.08)
					(hide yes)
					(name "GND"
						(effects
							(font
								(size 1.27 1.27)
							)
						)
					)
					(number "T9"
						(effects
							(font
								(size 1.27 1.27)
							)
						)
					)
				)
				(pin passive line
					(at 0 -30.48 0)
					(length 5.08)
					(hide yes)
					(name "GND"
						(effects
							(font
								(size 1.27 1.27)
							)
						)
					)
					(number "U10"
						(effects
							(font
								(size 1.27 1.27)
							)
						)
					)
				)
				(pin passive line
					(at 0 -30.48 0)
					(length 5.08)
					(hide yes)
					(name "GND"
						(effects
							(font
								(size 1.27 1.27)
							)
						)
					)
					(number "U12"
						(effects
							(font
								(size 1.27 1.27)
							)
						)
					)
				)
				(pin passive line
					(at 0 -30.48 0)
					(length 5.08)
					(hide yes)
					(name "GND"
						(effects
							(font
								(size 1.27 1.27)
							)
						)
					)
					(number "U14"
						(effects
							(font
								(size 1.27 1.27)
							)
						)
					)
				)
				(pin passive line
					(at 0 -30.48 0)
					(length 5.08)
					(hide yes)
					(name "GND"
						(effects
							(font
								(size 1.27 1.27)
							)
						)
					)
					(number "U18"
						(effects
							(font
								(size 1.27 1.27)
							)
						)
					)
				)
				(pin passive line
					(at 0 -30.48 0)
					(length 5.08)
					(hide yes)
					(name "GND"
						(effects
							(font
								(size 1.27 1.27)
							)
						)
					)
					(number "U8"
						(effects
							(font
								(size 1.27 1.27)
							)
						)
					)
				)
				(pin passive line
					(at 0 -30.48 0)
					(length 5.08)
					(hide yes)
					(name "GND"
						(effects
							(font
								(size 1.27 1.27)
							)
						)
					)
					(number "V15"
						(effects
							(font
								(size 1.27 1.27)
							)
						)
					)
				)
				(pin passive line
					(at 0 -30.48 0)
					(length 5.08)
					(hide yes)
					(name "GND"
						(effects
							(font
								(size 1.27 1.27)
							)
						)
					)
					(number "V25"
						(effects
							(font
								(size 1.27 1.27)
							)
						)
					)
				)
				(pin passive line
					(at 0 -30.48 0)
					(length 5.08)
					(hide yes)
					(name "GND"
						(effects
							(font
								(size 1.27 1.27)
							)
						)
					)
					(number "V5"
						(effects
							(font
								(size 1.27 1.27)
							)
						)
					)
				)
				(pin passive line
					(at 0 -30.48 0)
					(length 5.08)
					(hide yes)
					(name "GND"
						(effects
							(font
								(size 1.27 1.27)
							)
						)
					)
					(number "W12"
						(effects
							(font
								(size 1.27 1.27)
							)
						)
					)
				)
				(pin passive line
					(at 0 -30.48 0)
					(length 5.08)
					(hide yes)
					(name "GND"
						(effects
							(font
								(size 1.27 1.27)
							)
						)
					)
					(number "W2"
						(effects
							(font
								(size 1.27 1.27)
							)
						)
					)
				)
				(pin passive line
					(at 0 -30.48 0)
					(length 5.08)
					(hide yes)
					(name "GND"
						(effects
							(font
								(size 1.27 1.27)
							)
						)
					)
					(number "W22"
						(effects
							(font
								(size 1.27 1.27)
							)
						)
					)
				)
				(pin passive line
					(at 0 -30.48 0)
					(length 5.08)
					(hide yes)
					(name "GND"
						(effects
							(font
								(size 1.27 1.27)
							)
						)
					)
					(number "Y19"
						(effects
							(font
								(size 1.27 1.27)
							)
						)
					)
				)
				(pin passive line
					(at 0 -30.48 0)
					(length 5.08)
					(hide yes)
					(name "GND"
						(effects
							(font
								(size 1.27 1.27)
							)
						)
					)
					(number "Y9"
						(effects
							(font
								(size 1.27 1.27)
							)
						)
					)
				)
				(pin power_in line
					(at 44.45 0 180)
					(length 5.08)
					(name "MGTAVCC"
						(effects
							(font
								(size 1.27 1.27)
							)
						)
					)
					(number "C6"
						(effects
							(font
								(size 1.27 1.27)
							)
						)
					)
				)
				(pin passive line
					(at 44.45 0 180)
					(length 5.08)
					(hide yes)
					(name "MGTAVCC"
						(effects
							(font
								(size 1.27 1.27)
							)
						)
					)
					(number "E6"
						(effects
							(font
								(size 1.27 1.27)
							)
						)
					)
				)
				(pin passive line
					(at 44.45 0 180)
					(length 5.08)
					(hide yes)
					(name "MGTAVCC"
						(effects
							(font
								(size 1.27 1.27)
							)
						)
					)
					(number "G6"
						(effects
							(font
								(size 1.27 1.27)
							)
						)
					)
				)
				(pin passive line
					(at 44.45 0 180)
					(length 5.08)
					(hide yes)
					(name "MGTAVCC"
						(effects
							(font
								(size 1.27 1.27)
							)
						)
					)
					(number "J6"
						(effects
							(font
								(size 1.27 1.27)
							)
						)
					)
				)
				(pin passive line
					(at 44.45 0 180)
					(length 5.08)
					(hide yes)
					(name "MGTAVCC"
						(effects
							(font
								(size 1.27 1.27)
							)
						)
					)
					(number "L6"
						(effects
							(font
								(size 1.27 1.27)
							)
						)
					)
				)
				(pin power_in line
					(at 44.45 -5.08 180)
					(length 5.08)
					(name "MGTVCCAUX"
						(effects
							(font
								(size 1.27 1.27)
							)
						)
					)
					(number "N6"
						(effects
							(font
								(size 1.27 1.27)
							)
						)
					)
				)
				(pin power_in line
					(at 44.45 -10.16 180)
					(length 5.08)
					(name "MGTAVTT"
						(effects
							(font
								(size 1.27 1.27)
							)
						)
					)
					(number "B3"
						(effects
							(font
								(size 1.27 1.27)
							)
						)
					)
				)
				(pin passive line
					(at 44.45 -10.16 180)
					(length 5.08)
					(hide yes)
					(name "MGTAVTT"
						(effects
							(font
								(size 1.27 1.27)
							)
						)
					)
					(number "C2"
						(effects
							(font
								(size 1.27 1.27)
							)
						)
					)
				)
				(pin passive line
					(at 44.45 -10.16 180)
					(length 5.08)
					(hide yes)
					(name "MGTAVTT"
						(effects
							(font
								(size 1.27 1.27)
							)
						)
					)
					(number "D3"
						(effects
							(font
								(size 1.27 1.27)
							)
						)
					)
				)
				(pin passive line
					(at 44.45 -10.16 180)
					(length 5.08)
					(hide yes)
					(name "MGTAVTT"
						(effects
							(font
								(size 1.27 1.27)
							)
						)
					)
					(number "G2"
						(effects
							(font
								(size 1.27 1.27)
							)
						)
					)
				)
				(pin passive line
					(at 44.45 -10.16 180)
					(length 5.08)
					(hide yes)
					(name "MGTAVTT"
						(effects
							(font
								(size 1.27 1.27)
							)
						)
					)
					(number "H3"
						(effects
							(font
								(size 1.27 1.27)
							)
						)
					)
				)
				(pin passive line
					(at 44.45 -10.16 180)
					(length 5.08)
					(hide yes)
					(name "MGTAVTT"
						(effects
							(font
								(size 1.27 1.27)
							)
						)
					)
					(number "L2"
						(effects
							(font
								(size 1.27 1.27)
							)
						)
					)
				)
				(pin passive line
					(at 44.45 -10.16 180)
					(length 5.08)
					(hide yes)
					(name "MGTAVTT"
						(effects
							(font
								(size 1.27 1.27)
							)
						)
					)
					(number "M3"
						(effects
							(font
								(size 1.27 1.27)
							)
						)
					)
				)
				(pin power_in line
					(at 44.45 -15.24 180)
					(length 5.08)
					(name "MGTAVTTRCAL_115"
						(effects
							(font
								(size 1.27 1.27)
							)
						)
					)
					(number "M5"
						(effects
							(font
								(size 1.27 1.27)
							)
						)
					)
				)
				(pin power_in line
					(at 44.45 -17.78 180)
					(length 5.08)
					(name "MGTRREF_115"
						(effects
							(font
								(size 1.27 1.27)
							)
						)
					)
					(number "M6"
						(effects
							(font
								(size 1.27 1.27)
							)
						)
					)
				)
			)
			(symbol "XC7K160T-FFG676_11_1"
				(rectangle
					(start 5.08 2.54)
					(end 30.48 -38.1)
					(stroke
						(width 0.254)
						(type default)
					)
					(fill
						(type background)
					)
				)
				(pin power_in line
					(at 0 0 0)
					(length 5.08)
					(name "VCCO_0"
						(effects
							(font
								(size 1.27 1.27)
							)
						)
					)
					(number "L7"
						(effects
							(font
								(size 1.27 1.27)
							)
						)
					)
				)
				(pin passive line
					(at 0 0 0)
					(length 5.08)
					(hide yes)
					(name "VCCO_0"
						(effects
							(font
								(size 1.27 1.27)
							)
						)
					)
					(number "T6"
						(effects
							(font
								(size 1.27 1.27)
							)
						)
					)
				)
				(pin bidirectional line
					(at 0 -5.08 0)
					(length 5.08)
					(name "TDI_0"
						(effects
							(font
								(size 1.27 1.27)
							)
						)
					)
					(number "R6"
						(effects
							(font
								(size 1.27 1.27)
							)
						)
					)
				)
				(pin bidirectional line
					(at 0 -7.62 0)
					(length 5.08)
					(name "TDO_0"
						(effects
							(font
								(size 1.27 1.27)
							)
						)
					)
					(number "R7"
						(effects
							(font
								(size 1.27 1.27)
							)
						)
					)
				)
				(pin bidirectional line
					(at 0 -10.16 0)
					(length 5.08)
					(name "TMS_0"
						(effects
							(font
								(size 1.27 1.27)
							)
						)
					)
					(number "N8"
						(effects
							(font
								(size 1.27 1.27)
							)
						)
					)
				)
				(pin bidirectional line
					(at 0 -12.7 0)
					(length 5.08)
					(name "TCK_0"
						(effects
							(font
								(size 1.27 1.27)
							)
						)
					)
					(number "L8"
						(effects
							(font
								(size 1.27 1.27)
							)
						)
					)
				)
				(pin bidirectional line
					(at 0 -17.78 0)
					(length 5.08)
					(name "CCLK_0"
						(effects
							(font
								(size 1.27 1.27)
							)
						)
					)
					(number "C8"
						(effects
							(font
								(size 1.27 1.27)
							)
						)
					)
				)
				(pin bidirectional line
					(at 0 -20.32 0)
					(length 5.08)
					(name "M0_0"
						(effects
							(font
								(size 1.27 1.27)
							)
						)
					)
					(number "T5"
						(effects
							(font
								(size 1.27 1.27)
							)
						)
					)
				)
				(pin bidirectional line
					(at 0 -22.86 0)
					(length 5.08)
					(name "M1_0"
						(effects
							(font
								(size 1.27 1.27)
							)
						)
					)
					(number "T2"
						(effects
							(font
								(size 1.27 1.27)
							)
						)
					)
				)
				(pin bidirectional line
					(at 0 -25.4 0)
					(length 5.08)
					(name "M2_0"
						(effects
							(font
								(size 1.27 1.27)
							)
						)
					)
					(number "P5"
						(effects
							(font
								(size 1.27 1.27)
							)
						)
					)
				)
				(pin bidirectional line
					(at 0 -30.48 0)
					(length 5.08)
					(name "DONE_0"
						(effects
							(font
								(size 1.27 1.27)
							)
						)
					)
					(number "J7"
						(effects
							(font
								(size 1.27 1.27)
							)
						)
					)
				)
				(pin bidirectional line
					(at 0 -33.02 0)
					(length 5.08)
					(name "INIT_B_0"
						(effects
							(font
								(size 1.27 1.27)
							)
						)
					)
					(number "G7"
						(effects
							(font
								(size 1.27 1.27)
							)
						)
					)
				)
				(pin bidirectional line
					(at 0 -35.56 0)
					(length 5.08)
					(name "PROGRAM_B_0"
						(effects
							(font
								(size 1.27 1.27)
							)
						)
					)
					(number "P6"
						(effects
							(font
								(size 1.27 1.27)
							)
						)
					)
				)
				(pin bidirectional line
					(at 35.56 -5.08 180)
					(length 5.08)
					(name "CFGBVS_0"
						(effects
							(font
								(size 1.27 1.27)
							)
						)
					)
					(number "P7"
						(effects
							(font
								(size 1.27 1.27)
							)
						)
					)
				)
				(pin bidirectional line
					(at 35.56 -10.16 180)
					(length 5.08)
					(name "VP_0"
						(effects
							(font
								(size 1.27 1.27)
							)
						)
					)
					(number "N12"
						(effects
							(font
								(size 1.27 1.27)
							)
						)
					)
				)
				(pin bidirectional line
					(at 35.56 -12.7 180)
					(length 5.08)
					(name "VN_0"
						(effects
							(font
								(size 1.27 1.27)
							)
						)
					)
					(number "P11"
						(effects
							(font
								(size 1.27 1.27)
							)
						)
					)
				)
				(pin bidirectional line
					(at 35.56 -17.78 180)
					(length 5.08)
					(name "VREFP_0"
						(effects
							(font
								(size 1.27 1.27)
							)
						)
					)
					(number "P12"
						(effects
							(font
								(size 1.27 1.27)
							)
						)
					)
				)
				(pin bidirectional line
					(at 35.56 -20.32 180)
					(length 5.08)
					(name "VREFN_0"
						(effects
							(font
								(size 1.27 1.27)
							)
						)
					)
					(number "N11"
						(effects
							(font
								(size 1.27 1.27)
							)
						)
					)
				)
				(pin bidirectional line
					(at 35.56 -24.13 180)
					(length 5.08)
					(name "DXP_0"
						(effects
							(font
								(size 1.27 1.27)
							)
						)
					)
					(number "R12"
						(effects
							(font
								(size 1.27 1.27)
							)
						)
					)
				)
				(pin bidirectional line
					(at 35.56 -26.67 180)
					(length 5.08)
					(name "DXN_0"
						(effects
							(font
								(size 1.27 1.27)
							)
						)
					)
					(number "R11"
						(effects
							(font
								(size 1.27 1.27)
							)
						)
					)
				)
			)
		)
	(symbol "antmicroFerriteBeadsandChips:FB_120Z_2A_Murata-BLM18PG_0603"
			(pin_numbers
				(hide yes)
			)
			(pin_names
				(hide yes)
			)
			(exclude_from_sim no)
			(in_bom yes)
			(on_board yes)
			(property "Reference" "FB"
				(at 15.24 0 0)
				(effects
					(font
						(size 1.27 1.27)
						(thickness 0.15)
					)
					(justify left bottom)
				)
			)
			(property "Value" "FB_120Z_2A_Murata-BLM18PG_0603"
				(at 15.24 -2.54 0)
				(effects
					(font
						(size 1.27 1.27)
						(thickness 0.15)
					)
					(justify left bottom)
					(hide yes)
				)
			)
			(property "Footprint" "antmicro-footprints:FB_0603_1608Metric"
				(at 15.24 -7.62 0)
				(effects
					(font
						(size 1.27 1.27)
						(thickness 0.15)
					)
					(justify left bottom)
					(hide yes)
				)
			)
			(property "Datasheet" "https://www.murata.com/en-us/products/productdata/8796738650142/ENFA0003.pdf"
				(at 15.24 -10.16 0)
				(effects
					(font
						(size 1.27 1.27)
						(thickness 0.15)
					)
					(justify left bottom)
					(hide yes)
				)
			)
			(property "Description" "Ferrite Bead, 0603 [1608 Metric], 120 ohm, 2 A, BLM18P, 0.05 ohm, ± 25%, DC power line"
				(at 0 0 0)
				(effects
					(font
						(size 1.27 1.27)
					)
					(hide yes)
				)
			)
			(property "Val" "120Z/2A"
				(at 15.24 -5.08 0)
				(effects
					(font
						(size 1.27 1.27)
					)
					(justify left bottom)
				)
			)
			(property "MPN" "BLM18PG121SN1D"
				(at 15.24 -12.7 0)
				(effects
					(font
						(size 1.27 1.27)
						(thickness 0.15)
					)
					(justify left bottom)
					(hide yes)
				)
			)
			(property "Manufacturer" "Murata"
				(at 15.24 -15.24 0)
				(effects
					(font
						(size 1.27 1.27)
						(thickness 0.15)
					)
					(justify left bottom)
					(hide yes)
				)
			)
			(property "Current" ""
				(at 20.32 -22.86 0)
				(effects
					(font
						(size 1.27 1.27)
						(thickness 0.15)
					)
					(justify left bottom)
					(hide yes)
				)
			)
			(property "Author" "Antmicro"
				(at 15.24 -17.78 0)
				(effects
					(font
						(size 1.27 1.27)
						(thickness 0.15)
					)
					(justify left bottom)
					(hide yes)
				)
			)
			(property "License" "Apache-2.0"
				(at 15.24 -20.32 0)
				(effects
					(font
						(size 1.27 1.27)
						(thickness 0.15)
					)
					(justify left bottom)
					(hide yes)
				)
			)
			(property "ki_keywords" "0603, SMT, FERRITE BEAD, PASSIVE"
				(at 0 0 0)
				(effects
					(font
						(size 1.27 1.27)
					)
					(hide yes)
				)
			)
			(symbol "FB_120Z_2A_Murata-BLM18PG_0603_0_1"
				(polyline
					(pts
						(xy 1.651 0) (xy 1.2446 0)
					)
					(stroke
						(width 0)
						(type default)
					)
					(fill
						(type none)
					)
				)
				(polyline
					(pts
						(xy 2.2606 -1.8288) (xy 1.0414 -1.1176) (xy 2.7432 1.8288) (xy 3.9624 1.1176) (xy 2.2606 -1.8288)
					)
					(stroke
						(width 0)
						(type default)
					)
					(fill
						(type none)
					)
				)
				(polyline
					(pts
						(xy 3.81 0) (xy 3.3274 0)
					)
					(stroke
						(width 0)
						(type default)
					)
					(fill
						(type none)
					)
				)
			)
			(symbol "FB_120Z_2A_Murata-BLM18PG_0603_1_1"
				(pin passive line
					(at 0 0 0)
					(length 1.27)
					(name "~"
						(effects
							(font
								(size 1.27 1.27)
							)
						)
					)
					(number "1"
						(effects
							(font
								(size 1.27 1.27)
							)
						)
					)
				)
				(pin passive line
					(at 5.08 0 180)
					(length 1.27)
					(name "~"
						(effects
							(font
								(size 1.27 1.27)
							)
						)
					)
					(number "2"
						(effects
							(font
								(size 1.27 1.27)
							)
						)
					)
				)
			)
		)
	(symbol "antmicroFerriteBeadsandChips:FB_600Z_0.5A_Murata-BLM18AG_0603"
			(pin_numbers
				(hide yes)
			)
			(pin_names
				(hide yes)
			)
			(exclude_from_sim no)
			(in_bom yes)
			(on_board yes)
			(property "Reference" "FB"
				(at 15.24 0 0)
				(effects
					(font
						(size 1.27 1.27)
						(thickness 0.15)
					)
					(justify left bottom)
				)
			)
			(property "Value" "FB_600Z_0.5A_Murata-BLM18AG_0603"
				(at 15.24 -2.54 0)
				(effects
					(font
						(size 1.27 1.27)
						(thickness 0.15)
					)
					(justify left bottom)
					(hide yes)
				)
			)
			(property "Footprint" "antmicro-footprints:FB_0603_1608Metric"
				(at 15.24 -7.62 0)
				(effects
					(font
						(size 1.27 1.27)
						(thickness 0.15)
					)
					(justify left bottom)
					(hide yes)
				)
			)
			(property "Datasheet" "https://www.murata.com/en-us/products/productdata/8796738650142/ENFA0003.pdf"
				(at 15.24 -10.16 0)
				(effects
					(font
						(size 1.27 1.27)
						(thickness 0.15)
					)
					(justify left bottom)
					(hide yes)
				)
			)
			(property "Description" "Ferrite Bead, 0603 [1608 Metric], 600 ohm, 500 mA, BLM18A, 0.38 ohm, ± 25%, General use"
				(at 0 0 0)
				(effects
					(font
						(size 1.27 1.27)
					)
					(hide yes)
				)
			)
			(property "Val" "600Z/0.5A"
				(at 15.24 -5.08 0)
				(effects
					(font
						(size 1.27 1.27)
					)
					(justify left bottom)
				)
			)
			(property "MPN" "BLM18AG601SN1D"
				(at 15.24 -12.7 0)
				(effects
					(font
						(size 1.27 1.27)
						(thickness 0.15)
					)
					(justify left bottom)
					(hide yes)
				)
			)
			(property "Manufacturer" "Murata"
				(at 15.24 -15.24 0)
				(effects
					(font
						(size 1.27 1.27)
						(thickness 0.15)
					)
					(justify left bottom)
					(hide yes)
				)
			)
			(property "Current" ""
				(at 20.32 -22.86 0)
				(effects
					(font
						(size 1.27 1.27)
						(thickness 0.15)
					)
					(justify left bottom)
					(hide yes)
				)
			)
			(property "Author" "Antmicro"
				(at 15.24 -17.78 0)
				(effects
					(font
						(size 1.27 1.27)
						(thickness 0.15)
					)
					(justify left bottom)
					(hide yes)
				)
			)
			(property "License" "Apache-2.0"
				(at 15.24 -20.32 0)
				(effects
					(font
						(size 1.27 1.27)
						(thickness 0.15)
					)
					(justify left bottom)
					(hide yes)
				)
			)
			(property "ki_keywords" "0603, SMT, FERRITE BEAD, PASSIVE"
				(at 0 0 0)
				(effects
					(font
						(size 1.27 1.27)
					)
					(hide yes)
				)
			)
			(symbol "FB_600Z_0.5A_Murata-BLM18AG_0603_0_1"
				(polyline
					(pts
						(xy 1.651 0) (xy 1.2446 0)
					)
					(stroke
						(width 0)
						(type default)
					)
					(fill
						(type none)
					)
				)
				(polyline
					(pts
						(xy 2.2606 -1.8288) (xy 1.0414 -1.1176) (xy 2.7432 1.8288) (xy 3.9624 1.1176) (xy 2.2606 -1.8288)
					)
					(stroke
						(width 0)
						(type default)
					)
					(fill
						(type none)
					)
				)
				(polyline
					(pts
						(xy 3.81 0) (xy 3.3274 0)
					)
					(stroke
						(width 0)
						(type default)
					)
					(fill
						(type none)
					)
				)
			)
			(symbol "FB_600Z_0.5A_Murata-BLM18AG_0603_1_1"
				(pin passive line
					(at 0 0 0)
					(length 1.27)
					(name "~"
						(effects
							(font
								(size 1.27 1.27)
							)
						)
					)
					(number "1"
						(effects
							(font
								(size 1.27 1.27)
							)
						)
					)
				)
				(pin passive line
					(at 5.08 0 180)
					(length 1.27)
					(name "~"
						(effects
							(font
								(size 1.27 1.27)
							)
						)
					)
					(number "2"
						(effects
							(font
								(size 1.27 1.27)
							)
						)
					)
				)
			)
		)
	(symbol "antmicroFixedInductors:L_1u5_17A_Bourns-SRP6050CA"
			(pin_numbers
				(hide yes)
			)
			(pin_names
				(hide yes)
			)
			(exclude_from_sim no)
			(in_bom yes)
			(on_board yes)
			(property "Reference" "L"
				(at 13.97 0 0)
				(effects
					(font
						(size 1.27 1.27)
						(thickness 0.15)
					)
					(justify left bottom)
				)
			)
			(property "Value" "L_1u5_17A_Bourns-SRP6050CA"
				(at 13.97 -2.54 0)
				(effects
					(font
						(size 1.27 1.27)
						(thickness 0.15)
					)
					(justify left bottom)
					(hide yes)
				)
			)
			(property "Footprint" "antmicro-footprints:L_Bourns-SRP6050CA"
				(at 13.97 -7.62 0)
				(effects
					(font
						(size 1.27 1.27)
						(thickness 0.15)
					)
					(justify left bottom)
					(hide yes)
				)
			)
			(property "Datasheet" "https://www.bourns.com/docs/Product-Datasheets/SRP6050CA.pdf"
				(at 13.97 -10.16 0)
				(effects
					(font
						(size 1.27 1.27)
						(thickness 0.15)
					)
					(justify left bottom)
					(hide yes)
				)
			)
			(property "Description" "Power Inductor (SMT), 1.5 µH, 17 A, Shielded, 19.5 A, SRP6050CA"
				(at 0 0 0)
				(effects
					(font
						(size 1.27 1.27)
					)
					(hide yes)
				)
			)
			(property "Val" "1u5/17A"
				(at 13.97 -5.08 0)
				(effects
					(font
						(size 1.27 1.27)
						(thickness 0.15)
					)
					(justify left bottom)
				)
			)
			(property "Manufacturer" "Bourns"
				(at 13.97 -12.7 0)
				(effects
					(font
						(size 1.27 1.27)
						(thickness 0.15)
					)
					(justify left bottom)
					(hide yes)
				)
			)
			(property "MPN" "SRP6050CA-1R5M"
				(at 13.97 -15.24 0)
				(effects
					(font
						(size 1.27 1.27)
						(thickness 0.15)
					)
					(justify left bottom)
					(hide yes)
				)
			)
			(property "ISat" "19.5 A"
				(at 13.97 -16.51 0)
				(effects
					(font
						(size 1.27 1.27)
					)
					(justify left)
					(hide yes)
				)
			)
			(property "IMax" "17 A"
				(at 13.97 -20.32 0)
				(effects
					(font
						(size 1.27 1.27)
						(thickness 0.15)
					)
					(justify left bottom)
					(hide yes)
				)
			)
			(property "Size" "6.6x6.6"
				(at 13.97 -22.86 0)
				(effects
					(font
						(size 1.27 1.27)
						(thickness 0.15)
					)
					(justify left bottom)
					(hide yes)
				)
			)
			(property "Author" "Antmicro"
				(at 13.97 -25.4 0)
				(effects
					(font
						(size 1.27 1.27)
						(thickness 0.15)
					)
					(justify left bottom)
					(hide yes)
				)
			)
			(property "License" "Apache-2.0"
				(at 13.97 -27.94 0)
				(effects
					(font
						(size 1.27 1.27)
						(thickness 0.15)
					)
					(justify left bottom)
					(hide yes)
				)
			)
			(property "ki_keywords" "SMT, INDUCTOR, PASSIVE"
				(at 0 0 0)
				(effects
					(font
						(size 1.27 1.27)
					)
					(hide yes)
				)
			)
			(symbol "L_1u5_17A_Bourns-SRP6050CA_0_1"
				(arc
					(start 0.508 0)
					(mid 1.016 0.5058)
					(end 1.524 0)
					(stroke
						(width 0)
						(type default)
					)
					(fill
						(type none)
					)
				)
				(arc
					(start 1.524 0)
					(mid 2.032 0.5058)
					(end 2.54 0)
					(stroke
						(width 0)
						(type default)
					)
					(fill
						(type none)
					)
				)
				(arc
					(start 2.54 0)
					(mid 3.048 0.5058)
					(end 3.556 0)
					(stroke
						(width 0)
						(type default)
					)
					(fill
						(type none)
					)
				)
				(arc
					(start 3.556 0)
					(mid 4.064 0.5058)
					(end 4.572 0)
					(stroke
						(width 0)
						(type default)
					)
					(fill
						(type none)
					)
				)
			)
			(symbol "L_1u5_17A_Bourns-SRP6050CA_1_1"
				(pin passive line
					(at 0 0 0)
					(length 0.508)
					(name "~"
						(effects
							(font
								(size 1.27 1.27)
							)
						)
					)
					(number "1"
						(effects
							(font
								(size 1.27 1.27)
							)
						)
					)
				)
				(pin passive line
					(at 5.08 0 180)
					(length 0.508)
					(name "~"
						(effects
							(font
								(size 1.27 1.27)
							)
						)
					)
					(number "2"
						(effects
							(font
								(size 1.27 1.27)
							)
						)
					)
				)
			)
		)
	(symbol "antmicroFuses:F_4A_1206"
			(pin_numbers
				(hide yes)
			)
			(pin_names
				(offset 0.9906)
				(hide yes)
			)
			(exclude_from_sim no)
			(in_bom yes)
			(on_board yes)
			(property "Reference" "F"
				(at 20.32 -5.08 0)
				(effects
					(font
						(size 1.27 1.27)
						(thickness 0.15)
					)
					(justify left bottom)
				)
			)
			(property "Value" "F_4A_1206"
				(at 20.32 -7.62 0)
				(effects
					(font
						(size 1.27 1.27)
						(thickness 0.15)
					)
					(justify left bottom)
					(hide yes)
				)
			)
			(property "Footprint" "antmicro-footprints:F_1206_3216Metric"
				(at 20.32 -10.16 0)
				(effects
					(font
						(size 1.27 1.27)
						(thickness 0.15)
					)
					(justify left bottom)
					(hide yes)
				)
			)
			(property "Datasheet" "https://www.littelfuse.com/media?resourcetype=datasheets&itemid=dbe9bcd7-6072-4adf-bf5b-d33e52a6b90f&filename=littelfuse-fuse-466-datasheet"
				(at 20.32 -12.7 0)
				(effects
					(font
						(size 1.27 1.27)
						(thickness 0.15)
					)
					(justify left bottom)
					(hide yes)
				)
			)
			(property "Description" "Fuse, Surface Mount, 4 A, Very Fast Acting, 32 V, 32 V, 1206 (3216 Metric), 466"
				(at 0 0 0)
				(effects
					(font
						(size 1.27 1.27)
					)
					(hide yes)
				)
			)
			(property "Manufacturer" "Littelfuse"
				(at 20.32 -15.24 0)
				(effects
					(font
						(size 1.27 1.27)
						(thickness 0.15)
					)
					(justify left bottom)
					(hide yes)
				)
			)
			(property "MPN" "0466004.NR "
				(at 20.32 -17.78 0)
				(effects
					(font
						(size 1.27 1.27)
						(thickness 0.15)
					)
					(justify left bottom)
				)
			)
			(property "Author" "Antmicro"
				(at 20.32 -20.32 0)
				(effects
					(font
						(size 1.27 1.27)
						(thickness 0.15)
					)
					(justify left bottom)
					(hide yes)
				)
			)
			(property "License" "Apache-2.0"
				(at 20.32 -22.86 0)
				(effects
					(font
						(size 1.27 1.27)
						(thickness 0.15)
					)
					(justify left bottom)
					(hide yes)
				)
			)
			(property "ki_keywords" "FUSE, PASSIVE"
				(at 0 0 0)
				(effects
					(font
						(size 1.27 1.27)
					)
					(hide yes)
				)
			)
			(symbol "F_4A_1206_0_1"
				(rectangle
					(start 1.27 0.508)
					(end 3.81 -0.508)
					(stroke
						(width 0)
						(type default)
					)
					(fill
						(type none)
					)
				)
				(polyline
					(pts
						(xy 1.27 0) (xy 3.81 0)
					)
					(stroke
						(width 0)
						(type default)
					)
					(fill
						(type none)
					)
				)
			)
			(symbol "F_4A_1206_1_1"
				(pin passive line
					(at 0 0 0)
					(length 1.27)
					(name "~"
						(effects
							(font
								(size 1.27 1.27)
							)
						)
					)
					(number "1"
						(effects
							(font
								(size 1.27 1.27)
							)
						)
					)
				)
				(pin passive line
					(at 5.08 0 180)
					(length 1.27)
					(name "~"
						(effects
							(font
								(size 1.27 1.27)
							)
						)
					)
					(number "2"
						(effects
							(font
								(size 1.27 1.27)
							)
						)
					)
				)
			)
		)
	(symbol "antmicroGenericPinHeaders:PinHeader_2x7_P2mm_SMD_Shrouded_no-locator"
			(exclude_from_sim no)
			(in_bom yes)
			(on_board yes)
			(property "Reference" "J"
				(at 25.4 -2.54 0)
				(effects
					(font
						(size 1.27 1.27)
						(thickness 0.15)
					)
					(justify left bottom)
				)
			)
			(property "Value" "PinHeader_2x7_P2mm_SMD_Shrouded_no-locator"
				(at 25.4 -5.08 0)
				(effects
					(font
						(size 1.27 1.27)
						(thickness 0.15)
					)
					(justify left bottom)
					(hide yes)
				)
			)
			(property "Footprint" "antmicro-footprints:PinHeader_2x7_P2mm_SMD_Shrouded_no-locator"
				(at 25.4 -7.62 0)
				(effects
					(font
						(size 1.27 1.27)
						(thickness 0.15)
					)
					(justify left bottom)
					(hide yes)
				)
			)
			(property "Datasheet" "https://www.molex.com/pdm_docs/ps/PS-87831-027-001.pdf"
				(at 25.4 -10.16 0)
				(effects
					(font
						(size 1.27 1.27)
						(thickness 0.15)
					)
					(justify left bottom)
					(hide yes)
				)
			)
			(property "Description" "Pin Header, Signal, Wire-to-Board, 2 mm, 2 Rows, 14 Contacts, Surface Mount Straight"
				(at 0 0 0)
				(effects
					(font
						(size 1.27 1.27)
					)
					(hide yes)
				)
			)
			(property "MPN" "878321412"
				(at 25.4 -12.7 0)
				(effects
					(font
						(size 1.27 1.27)
						(thickness 0.15)
					)
					(justify left bottom)
				)
			)
			(property "Manufacturer" "Molex"
				(at 25.4 -15.24 0)
				(effects
					(font
						(size 1.27 1.27)
						(thickness 0.15)
					)
					(justify left bottom)
					(hide yes)
				)
			)
			(property "Author" "Antmicro"
				(at 25.4 -17.78 0)
				(effects
					(font
						(size 1.27 1.27)
						(thickness 0.15)
					)
					(justify left bottom)
					(hide yes)
				)
			)
			(property "License" "Apache-2.0"
				(at 25.4 -20.32 0)
				(effects
					(font
						(size 1.27 1.27)
						(thickness 0.15)
					)
					(justify left bottom)
					(hide yes)
				)
			)
			(property "ki_keywords" "PINSTRIP, HEADER "
				(at 0 0 0)
				(effects
					(font
						(size 1.27 1.27)
					)
					(hide yes)
				)
			)
			(symbol "PinHeader_2x7_P2mm_SMD_Shrouded_no-locator_1_1"
				(rectangle
					(start 2.54 1.27)
					(end 7.62 -16.51)
					(stroke
						(width 0.254)
						(type default)
					)
					(fill
						(type background)
					)
				)
				(rectangle
					(start 3.556 0.254)
					(end 4.064 -0.254)
					(stroke
						(width 0.254)
						(type default)
					)
					(fill
						(type background)
					)
				)
				(rectangle
					(start 3.556 -2.286)
					(end 4.064 -2.794)
					(stroke
						(width 0.254)
						(type default)
					)
					(fill
						(type background)
					)
				)
				(rectangle
					(start 3.556 -4.826)
					(end 4.064 -5.334)
					(stroke
						(width 0.254)
						(type default)
					)
					(fill
						(type background)
					)
				)
				(rectangle
					(start 3.556 -7.366)
					(end 4.064 -7.874)
					(stroke
						(width 0.254)
						(type default)
					)
					(fill
						(type background)
					)
				)
				(rectangle
					(start 3.556 -9.906)
					(end 4.064 -10.414)
					(stroke
						(width 0.254)
						(type default)
					)
					(fill
						(type background)
					)
				)
				(rectangle
					(start 3.556 -12.446)
					(end 4.064 -12.954)
					(stroke
						(width 0.254)
						(type default)
					)
					(fill
						(type background)
					)
				)
				(rectangle
					(start 3.556 -14.986)
					(end 4.064 -15.494)
					(stroke
						(width 0.254)
						(type default)
					)
					(fill
						(type background)
					)
				)
				(rectangle
					(start 6.096 0.254)
					(end 6.604 -0.254)
					(stroke
						(width 0.254)
						(type default)
					)
					(fill
						(type background)
					)
				)
				(rectangle
					(start 6.096 -2.286)
					(end 6.604 -2.794)
					(stroke
						(width 0.254)
						(type default)
					)
					(fill
						(type background)
					)
				)
				(rectangle
					(start 6.096 -4.826)
					(end 6.604 -5.334)
					(stroke
						(width 0.254)
						(type default)
					)
					(fill
						(type background)
					)
				)
				(rectangle
					(start 6.096 -7.366)
					(end 6.604 -7.874)
					(stroke
						(width 0.254)
						(type default)
					)
					(fill
						(type background)
					)
				)
				(rectangle
					(start 6.096 -9.906)
					(end 6.604 -10.414)
					(stroke
						(width 0.254)
						(type default)
					)
					(fill
						(type background)
					)
				)
				(rectangle
					(start 6.096 -12.446)
					(end 6.604 -12.954)
					(stroke
						(width 0.254)
						(type default)
					)
					(fill
						(type background)
					)
				)
				(rectangle
					(start 6.096 -14.986)
					(end 6.604 -15.494)
					(stroke
						(width 0.254)
						(type default)
					)
					(fill
						(type background)
					)
				)
				(pin passive line
					(at 0 0 0)
					(length 2.54)
					(name "~"
						(effects
							(font
								(size 1.27 1.27)
							)
						)
					)
					(number "1"
						(effects
							(font
								(size 1.27 1.27)
							)
						)
					)
				)
				(pin passive line
					(at 0 -2.54 0)
					(length 2.54)
					(name "~"
						(effects
							(font
								(size 1.27 1.27)
							)
						)
					)
					(number "3"
						(effects
							(font
								(size 1.27 1.27)
							)
						)
					)
				)
				(pin passive line
					(at 0 -5.08 0)
					(length 2.54)
					(name "~"
						(effects
							(font
								(size 1.27 1.27)
							)
						)
					)
					(number "5"
						(effects
							(font
								(size 1.27 1.27)
							)
						)
					)
				)
				(pin passive line
					(at 0 -7.62 0)
					(length 2.54)
					(name "~"
						(effects
							(font
								(size 1.27 1.27)
							)
						)
					)
					(number "7"
						(effects
							(font
								(size 1.27 1.27)
							)
						)
					)
				)
				(pin passive line
					(at 0 -10.16 0)
					(length 2.54)
					(name "~"
						(effects
							(font
								(size 1.27 1.27)
							)
						)
					)
					(number "9"
						(effects
							(font
								(size 1.27 1.27)
							)
						)
					)
				)
				(pin passive line
					(at 0 -12.7 0)
					(length 2.54)
					(name "~"
						(effects
							(font
								(size 1.27 1.27)
							)
						)
					)
					(number "11"
						(effects
							(font
								(size 1.27 1.27)
							)
						)
					)
				)
				(pin passive line
					(at 0 -15.24 0)
					(length 2.54)
					(name "~"
						(effects
							(font
								(size 1.27 1.27)
							)
						)
					)
					(number "13"
						(effects
							(font
								(size 1.27 1.27)
							)
						)
					)
				)
				(pin passive line
					(at 10.16 0 180)
					(length 2.54)
					(name "~"
						(effects
							(font
								(size 1.27 1.27)
							)
						)
					)
					(number "2"
						(effects
							(font
								(size 1.27 1.27)
							)
						)
					)
				)
				(pin passive line
					(at 10.16 -2.54 180)
					(length 2.54)
					(name "~"
						(effects
							(font
								(size 1.27 1.27)
							)
						)
					)
					(number "4"
						(effects
							(font
								(size 1.27 1.27)
							)
						)
					)
				)
				(pin passive line
					(at 10.16 -5.08 180)
					(length 2.54)
					(name "~"
						(effects
							(font
								(size 1.27 1.27)
							)
						)
					)
					(number "6"
						(effects
							(font
								(size 1.27 1.27)
							)
						)
					)
				)
				(pin passive line
					(at 10.16 -7.62 180)
					(length 2.54)
					(name "~"
						(effects
							(font
								(size 1.27 1.27)
							)
						)
					)
					(number "8"
						(effects
							(font
								(size 1.27 1.27)
							)
						)
					)
				)
				(pin passive line
					(at 10.16 -10.16 180)
					(length 2.54)
					(name "~"
						(effects
							(font
								(size 1.27 1.27)
							)
						)
					)
					(number "10"
						(effects
							(font
								(size 1.27 1.27)
							)
						)
					)
				)
				(pin passive line
					(at 10.16 -12.7 180)
					(length 2.54)
					(name "~"
						(effects
							(font
								(size 1.27 1.27)
							)
						)
					)
					(number "12"
						(effects
							(font
								(size 1.27 1.27)
							)
						)
					)
				)
				(pin passive line
					(at 10.16 -15.24 180)
					(length 2.54)
					(name "~"
						(effects
							(font
								(size 1.27 1.27)
							)
						)
					)
					(number "14"
						(effects
							(font
								(size 1.27 1.27)
							)
						)
					)
				)
			)
		)
	(symbol "antmicroInterfaceAnalogSwitchesMultiplexersDemultiplexers:TS5A3359_VSSOP"
			(exclude_from_sim no)
			(in_bom yes)
			(on_board yes)
			(property "Reference" "U"
				(at 41.91 -2.54 0)
				(effects
					(font
						(size 1.27 1.27)
						(thickness 0.15)
					)
					(justify left bottom)
				)
			)
			(property "Value" "TS5A3359_VSSOP"
				(at 41.91 -5.08 0)
				(effects
					(font
						(size 1.27 1.27)
						(thickness 0.15)
					)
					(justify left bottom)
				)
			)
			(property "Footprint" "antmicro-footprints:VSSOP-8_2.3x2mm_P0.5mm"
				(at 41.91 -7.62 0)
				(effects
					(font
						(size 1.27 1.27)
						(thickness 0.15)
					)
					(justify left bottom)
					(hide yes)
				)
			)
			(property "Datasheet" "https://www.ti.com/general/docs/suppproductinfo.tsp?distId=26&gotoUrl=http%3A%2F%2Fwww.ti.com%2Flit%2Fgpn%2Fts5a3359"
				(at 41.91 -10.16 0)
				(effects
					(font
						(size 1.27 1.27)
						(thickness 0.15)
					)
					(justify left bottom)
					(hide yes)
				)
			)
			(property "Description" "Interface analog switch/multiplexer/demultiplexer"
				(at 0 0 0)
				(effects
					(font
						(size 1.27 1.27)
					)
					(hide yes)
				)
			)
			(property "MPN" "TS5A3359DCUR"
				(at 41.91 -12.7 0)
				(effects
					(font
						(size 1.27 1.27)
						(thickness 0.15)
					)
					(justify left bottom)
					(hide yes)
				)
			)
			(property "Manufacturer" "Texas Instruments"
				(at 41.91 -15.24 0)
				(effects
					(font
						(size 1.27 1.27)
						(thickness 0.15)
					)
					(justify left bottom)
					(hide yes)
				)
			)
			(property "Author" "Antmicro"
				(at 41.91 -17.78 0)
				(effects
					(font
						(size 1.27 1.27)
						(thickness 0.15)
					)
					(justify left bottom)
					(hide yes)
				)
			)
			(property "License" "Apache-2.0"
				(at 41.91 -20.32 0)
				(effects
					(font
						(size 1.27 1.27)
						(thickness 0.15)
					)
					(justify left bottom)
					(hide yes)
				)
			)
			(property "ki_keywords" "IC"
				(at 0 0 0)
				(effects
					(font
						(size 1.27 1.27)
					)
					(hide yes)
				)
			)
			(symbol "TS5A3359_VSSOP_1_1"
				(rectangle
					(start 2.54 2.54)
					(end 24.13 -15.24)
					(stroke
						(width 0.254)
						(type default)
					)
					(fill
						(type background)
					)
				)
				(polyline
					(pts
						(xy 7.62 0) (xy 10.16 0)
					)
					(stroke
						(width 0.254)
						(type default)
					)
					(fill
						(type background)
					)
				)
				(polyline
					(pts
						(xy 7.62 -2.54) (xy 10.16 -2.54)
					)
					(stroke
						(width 0.254)
						(type default)
					)
					(fill
						(type background)
					)
				)
				(polyline
					(pts
						(xy 7.62 -5.08) (xy 10.16 -5.08)
					)
					(stroke
						(width 0.254)
						(type default)
					)
					(fill
						(type background)
					)
				)
				(polyline
					(pts
						(xy 7.62 -10.16) (xy 13.208 -10.16)
					)
					(stroke
						(width 0.254)
						(type default)
					)
					(fill
						(type background)
					)
				)
				(polyline
					(pts
						(xy 7.62 -12.7) (xy 13.208 -12.7)
					)
					(stroke
						(width 0.254)
						(type default)
					)
					(fill
						(type background)
					)
				)
				(arc
					(start 10.4902 -0.2794)
					(mid 10.3147 0.0129)
					(end 10.4902 0.3048)
					(stroke
						(width 0.254)
						(type default)
					)
					(fill
						(type background)
					)
				)
				(arc
					(start 10.4902 -2.8194)
					(mid 10.3147 -2.5271)
					(end 10.4902 -2.2352)
					(stroke
						(width 0.254)
						(type default)
					)
					(fill
						(type background)
					)
				)
				(arc
					(start 10.4902 -5.3594)
					(mid 10.3147 -5.0671)
					(end 10.4902 -4.7752)
					(stroke
						(width 0.254)
						(type default)
					)
					(fill
						(type background)
					)
				)
				(arc
					(start 10.4902 0.3048)
					(mid 10.829 0.2941)
					(end 10.9982 0)
					(stroke
						(width 0.254)
						(type default)
					)
					(fill
						(type background)
					)
				)
				(arc
					(start 10.4902 -2.2352)
					(mid 10.829 -2.2459)
					(end 10.9982 -2.54)
					(stroke
						(width 0.254)
						(type default)
					)
					(fill
						(type background)
					)
				)
				(arc
					(start 10.4902 -4.7752)
					(mid 10.829 -4.7859)
					(end 10.9982 -5.08)
					(stroke
						(width 0.254)
						(type default)
					)
					(fill
						(type background)
					)
				)
				(arc
					(start 10.9982 0)
					(mid 10.8272 -0.2881)
					(end 10.4902 -0.2794)
					(stroke
						(width 0.254)
						(type default)
					)
					(fill
						(type background)
					)
				)
				(arc
					(start 10.9982 -2.54)
					(mid 10.8272 -2.8281)
					(end 10.4902 -2.8194)
					(stroke
						(width 0.254)
						(type default)
					)
					(fill
						(type background)
					)
				)
				(arc
					(start 10.9982 -5.08)
					(mid 10.8272 -5.3681)
					(end 10.4902 -5.3594)
					(stroke
						(width 0.254)
						(type default)
					)
					(fill
						(type background)
					)
				)
				(polyline
					(pts
						(xy 13.716 -1.778) (xy 13.716 -12.7)
					)
					(stroke
						(width 0.254)
						(type default)
					)
					(fill
						(type background)
					)
				)
				(polyline
					(pts
						(xy 15.494 -2.54) (xy 11.684 -0.762)
					)
					(stroke
						(width 0.254)
						(type default)
					)
					(fill
						(type background)
					)
				)
				(arc
					(start 15.8242 -2.8194)
					(mid 15.6513 -2.5287)
					(end 15.8242 -2.2352)
					(stroke
						(width 0.254)
						(type default)
					)
					(fill
						(type background)
					)
				)
				(arc
					(start 15.8242 -2.2352)
					(mid 16.161 -2.249)
					(end 16.3322 -2.54)
					(stroke
						(width 0.254)
						(type default)
					)
					(fill
						(type background)
					)
				)
				(arc
					(start 16.3322 -2.54)
					(mid 16.1606 -2.8308)
					(end 15.8242 -2.8194)
					(stroke
						(width 0.254)
						(type default)
					)
					(fill
						(type background)
					)
				)
				(polyline
					(pts
						(xy 19.05 -2.54) (xy 16.51 -2.54)
					)
					(stroke
						(width 0.254)
						(type default)
					)
					(fill
						(type background)
					)
				)
				(pin passive line
					(at 0 0 0)
					(length 2.54)
					(name "NO1"
						(effects
							(font
								(size 1.27 1.27)
							)
						)
					)
					(number "1"
						(effects
							(font
								(size 1.27 1.27)
							)
						)
					)
				)
				(pin passive line
					(at 0 -2.54 0)
					(length 2.54)
					(name "NO2"
						(effects
							(font
								(size 1.27 1.27)
							)
						)
					)
					(number "2"
						(effects
							(font
								(size 1.27 1.27)
							)
						)
					)
				)
				(pin passive line
					(at 0 -5.08 0)
					(length 2.54)
					(name "NO3"
						(effects
							(font
								(size 1.27 1.27)
							)
						)
					)
					(number "3"
						(effects
							(font
								(size 1.27 1.27)
							)
						)
					)
				)
				(pin passive line
					(at 0 -10.16 0)
					(length 2.54)
					(name "IN1"
						(effects
							(font
								(size 1.27 1.27)
							)
						)
					)
					(number "6"
						(effects
							(font
								(size 1.27 1.27)
							)
						)
					)
				)
				(pin passive line
					(at 0 -12.7 0)
					(length 2.54)
					(name "IN2"
						(effects
							(font
								(size 1.27 1.27)
							)
						)
					)
					(number "5"
						(effects
							(font
								(size 1.27 1.27)
							)
						)
					)
				)
				(pin passive line
					(at 26.67 0 180)
					(length 2.54)
					(name "VCC"
						(effects
							(font
								(size 1.27 1.27)
							)
						)
					)
					(number "8"
						(effects
							(font
								(size 1.27 1.27)
							)
						)
					)
				)
				(pin passive line
					(at 26.67 -2.54 180)
					(length 2.54)
					(name "COM"
						(effects
							(font
								(size 1.27 1.27)
							)
						)
					)
					(number "7"
						(effects
							(font
								(size 1.27 1.27)
							)
						)
					)
				)
				(pin passive line
					(at 26.67 -12.7 180)
					(length 2.54)
					(name "GND"
						(effects
							(font
								(size 1.27 1.27)
							)
						)
					)
					(number "4"
						(effects
							(font
								(size 1.27 1.27)
							)
						)
					)
				)
			)
		)
	(symbol "antmicroInterfaceControllers:FT4232H_VQFN"
			(exclude_from_sim no)
			(in_bom yes)
			(on_board yes)
			(property "Reference" "U"
				(at 55.88 -2.54 0)
				(effects
					(font
						(size 1.27 1.27)
						(thickness 0.15)
					)
					(justify left bottom)
				)
			)
			(property "Value" "FT4232H_VQFN"
				(at 55.88 -5.08 0)
				(effects
					(font
						(size 1.27 1.27)
						(thickness 0.15)
					)
					(justify left bottom)
				)
			)
			(property "Footprint" "antmicro-footprints:QFN-56-1EP_8x8mm_P0.5mm"
				(at 55.88 -7.62 0)
				(effects
					(font
						(size 1.27 1.27)
						(thickness 0.15)
					)
					(justify left bottom)
					(hide yes)
				)
			)
			(property "Datasheet" "https://www.ftdichip.com/Support/Documents/DataSheets/ICs/DS_FT4232H.pdf"
				(at 55.88 -10.16 0)
				(effects
					(font
						(size 1.27 1.27)
						(thickness 0.15)
					)
					(justify left bottom)
					(hide yes)
				)
			)
			(property "Description" "Interface Bridges, USB to UART, MPSSE, 1.62 V, 1.98 V, VQFN, 56 Pins, -40 °C"
				(at 0 0 0)
				(effects
					(font
						(size 1.27 1.27)
					)
					(hide yes)
				)
			)
			(property "Manufacturer" "FTDI Chip"
				(at 55.88 -12.7 0)
				(effects
					(font
						(size 1.27 1.27)
						(thickness 0.15)
					)
					(justify left bottom)
					(hide yes)
				)
			)
			(property "MPN" "FT4232H-56Q-REEL"
				(at 55.88 -15.24 0)
				(effects
					(font
						(size 1.27 1.27)
						(thickness 0.15)
					)
					(justify left bottom)
					(hide yes)
				)
			)
			(property "Author" "Antmicro"
				(at 55.88 -17.78 0)
				(effects
					(font
						(size 1.27 1.27)
						(thickness 0.15)
					)
					(justify left bottom)
					(hide yes)
				)
			)
			(property "License" "Apache-2.0"
				(at 55.88 -20.32 0)
				(effects
					(font
						(size 1.27 1.27)
						(thickness 0.15)
					)
					(justify left bottom)
					(hide yes)
				)
			)
			(property "ki_keywords" "SMT, INTERFACE, IC, CONTROLLER, USB, UART, I2C, SPI, JTAG"
				(at 0 0 0)
				(effects
					(font
						(size 1.27 1.27)
					)
					(hide yes)
				)
			)
			(symbol "FT4232H_VQFN_1_1"
				(rectangle
					(start 2.54 2.54)
					(end 38.1 -93.98)
					(stroke
						(width 0.254)
						(type default)
					)
					(fill
						(type background)
					)
				)
				(pin power_in line
					(at 0 0 0)
					(length 2.54)
					(name "V_{REGIN}"
						(effects
							(font
								(size 1.27 1.27)
							)
						)
					)
					(number "44"
						(effects
							(font
								(size 1.27 1.27)
							)
						)
					)
				)
				(pin power_in line
					(at 0 -2.54 0)
					(length 2.54)
					(name "V_{CCIO}"
						(effects
							(font
								(size 1.27 1.27)
							)
						)
					)
					(number "16"
						(effects
							(font
								(size 1.27 1.27)
							)
						)
					)
				)
				(pin passive line
					(at 0 -2.54 0)
					(length 2.54)
					(hide yes)
					(name "V_{CCIO}"
						(effects
							(font
								(size 1.27 1.27)
							)
						)
					)
					(number "36"
						(effects
							(font
								(size 1.27 1.27)
							)
						)
					)
				)
				(pin passive line
					(at 0 -2.54 0)
					(length 2.54)
					(hide yes)
					(name "V_{CCIO}"
						(effects
							(font
								(size 1.27 1.27)
							)
						)
					)
					(number "50"
						(effects
							(font
								(size 1.27 1.27)
							)
						)
					)
				)
				(pin power_out line
					(at 0 -6.35 0)
					(length 2.54)
					(name "V_{REGOUT}"
						(effects
							(font
								(size 1.27 1.27)
							)
						)
					)
					(number "43"
						(effects
							(font
								(size 1.27 1.27)
							)
						)
					)
				)
				(pin power_in line
					(at 0 -10.16 0)
					(length 2.54)
					(name "V_{PHY}"
						(effects
							(font
								(size 1.27 1.27)
							)
						)
					)
					(number "5"
						(effects
							(font
								(size 1.27 1.27)
							)
						)
					)
				)
				(pin power_in line
					(at 0 -12.7 0)
					(length 2.54)
					(name "V_{PLL}"
						(effects
							(font
								(size 1.27 1.27)
							)
						)
					)
					(number "9"
						(effects
							(font
								(size 1.27 1.27)
							)
						)
					)
				)
				(pin power_in line
					(at 0 -15.24 0)
					(length 2.54)
					(name "V_{CORE}"
						(effects
							(font
								(size 1.27 1.27)
							)
						)
					)
					(number "2"
						(effects
							(font
								(size 1.27 1.27)
							)
						)
					)
				)
				(pin passive line
					(at 0 -15.24 0)
					(length 2.54)
					(hide yes)
					(name "V_{CORE}"
						(effects
							(font
								(size 1.27 1.27)
							)
						)
					)
					(number "31"
						(effects
							(font
								(size 1.27 1.27)
							)
						)
					)
				)
				(pin bidirectional line
					(at 0 -22.86 0)
					(length 2.54)
					(name "D+"
						(effects
							(font
								(size 1.27 1.27)
							)
						)
					)
					(number "8"
						(effects
							(font
								(size 1.27 1.27)
							)
						)
					)
				)
				(pin bidirectional line
					(at 0 -25.4 0)
					(length 2.54)
					(name "D-"
						(effects
							(font
								(size 1.27 1.27)
							)
						)
					)
					(number "7"
						(effects
							(font
								(size 1.27 1.27)
							)
						)
					)
				)
				(pin input line
					(at 0 -36.83 0)
					(length 2.54)
					(name "~{RESET}"
						(effects
							(font
								(size 1.27 1.27)
							)
						)
					)
					(number "11"
						(effects
							(font
								(size 1.27 1.27)
							)
						)
					)
				)
				(pin bidirectional line
					(at 0 -44.45 0)
					(length 2.54)
					(name "EECS"
						(effects
							(font
								(size 1.27 1.27)
							)
						)
					)
					(number "1"
						(effects
							(font
								(size 1.27 1.27)
							)
						)
					)
				)
				(pin output line
					(at 0 -46.99 0)
					(length 2.54)
					(name "EECLK"
						(effects
							(font
								(size 1.27 1.27)
							)
						)
					)
					(number "56"
						(effects
							(font
								(size 1.27 1.27)
							)
						)
					)
				)
				(pin bidirectional line
					(at 0 -49.53 0)
					(length 2.54)
					(name "EEDATA"
						(effects
							(font
								(size 1.27 1.27)
							)
						)
					)
					(number "55"
						(effects
							(font
								(size 1.27 1.27)
							)
						)
					)
				)
				(pin input line
					(at 0 -54.61 0)
					(length 2.54)
					(name "OSCI"
						(effects
							(font
								(size 1.27 1.27)
							)
						)
					)
					(number "3"
						(effects
							(font
								(size 1.27 1.27)
							)
						)
					)
				)
				(pin output line
					(at 0 -59.69 0)
					(length 2.54)
					(name "OSCO"
						(effects
							(font
								(size 1.27 1.27)
							)
						)
					)
					(number "4"
						(effects
							(font
								(size 1.27 1.27)
							)
						)
					)
				)
				(pin input line
					(at 0 -77.47 0)
					(length 2.54)
					(name "REF"
						(effects
							(font
								(size 1.27 1.27)
							)
						)
					)
					(number "6"
						(effects
							(font
								(size 1.27 1.27)
							)
						)
					)
				)
				(pin input line
					(at 0 -88.9 0)
					(length 2.54)
					(name "TEST"
						(effects
							(font
								(size 1.27 1.27)
							)
						)
					)
					(number "10"
						(effects
							(font
								(size 1.27 1.27)
							)
						)
					)
				)
				(pin power_in line
					(at 0 -91.44 0)
					(length 2.54)
					(name "GND"
						(effects
							(font
								(size 1.27 1.27)
							)
						)
					)
					(number "21"
						(effects
							(font
								(size 1.27 1.27)
							)
						)
					)
				)
				(pin passive line
					(at 0 -91.44 0)
					(length 2.54)
					(hide yes)
					(name "GND"
						(effects
							(font
								(size 1.27 1.27)
							)
						)
					)
					(number "41"
						(effects
							(font
								(size 1.27 1.27)
							)
						)
					)
				)
				(pin passive line
					(at 0 -91.44 0)
					(length 2.54)
					(hide yes)
					(name "GND"
						(effects
							(font
								(size 1.27 1.27)
							)
						)
					)
					(number "45"
						(effects
							(font
								(size 1.27 1.27)
							)
						)
					)
				)
				(pin passive line
					(at 0 -91.44 0)
					(length 2.54)
					(hide yes)
					(name "GND"
						(effects
							(font
								(size 1.27 1.27)
							)
						)
					)
					(number "57"
						(effects
							(font
								(size 1.27 1.27)
							)
						)
					)
				)
				(pin bidirectional line
					(at 40.64 0 180)
					(length 2.54)
					(name "ADBUS0"
						(effects
							(font
								(size 1.27 1.27)
							)
						)
					)
					(number "12"
						(effects
							(font
								(size 1.27 1.27)
							)
						)
					)
				)
				(pin bidirectional line
					(at 40.64 -2.54 180)
					(length 2.54)
					(name "ADBUS1"
						(effects
							(font
								(size 1.27 1.27)
							)
						)
					)
					(number "13"
						(effects
							(font
								(size 1.27 1.27)
							)
						)
					)
				)
				(pin bidirectional line
					(at 40.64 -5.08 180)
					(length 2.54)
					(name "ADBUS2"
						(effects
							(font
								(size 1.27 1.27)
							)
						)
					)
					(number "14"
						(effects
							(font
								(size 1.27 1.27)
							)
						)
					)
				)
				(pin bidirectional line
					(at 40.64 -7.62 180)
					(length 2.54)
					(name "ADBUS3"
						(effects
							(font
								(size 1.27 1.27)
							)
						)
					)
					(number "15"
						(effects
							(font
								(size 1.27 1.27)
							)
						)
					)
				)
				(pin bidirectional line
					(at 40.64 -10.16 180)
					(length 2.54)
					(name "ADBUS4"
						(effects
							(font
								(size 1.27 1.27)
							)
						)
					)
					(number "17"
						(effects
							(font
								(size 1.27 1.27)
							)
						)
					)
				)
				(pin bidirectional line
					(at 40.64 -12.7 180)
					(length 2.54)
					(name "ADBUS5"
						(effects
							(font
								(size 1.27 1.27)
							)
						)
					)
					(number "18"
						(effects
							(font
								(size 1.27 1.27)
							)
						)
					)
				)
				(pin bidirectional line
					(at 40.64 -15.24 180)
					(length 2.54)
					(name "ADBUS6"
						(effects
							(font
								(size 1.27 1.27)
							)
						)
					)
					(number "19"
						(effects
							(font
								(size 1.27 1.27)
							)
						)
					)
				)
				(pin bidirectional line
					(at 40.64 -17.78 180)
					(length 2.54)
					(name "ADBUS7"
						(effects
							(font
								(size 1.27 1.27)
							)
						)
					)
					(number "20"
						(effects
							(font
								(size 1.27 1.27)
							)
						)
					)
				)
				(pin bidirectional line
					(at 40.64 -21.59 180)
					(length 2.54)
					(name "BDBUS0"
						(effects
							(font
								(size 1.27 1.27)
							)
						)
					)
					(number "22"
						(effects
							(font
								(size 1.27 1.27)
							)
						)
					)
				)
				(pin bidirectional line
					(at 40.64 -24.13 180)
					(length 2.54)
					(name "BDBUS1"
						(effects
							(font
								(size 1.27 1.27)
							)
						)
					)
					(number "23"
						(effects
							(font
								(size 1.27 1.27)
							)
						)
					)
				)
				(pin bidirectional line
					(at 40.64 -26.67 180)
					(length 2.54)
					(name "BDBUS2"
						(effects
							(font
								(size 1.27 1.27)
							)
						)
					)
					(number "24"
						(effects
							(font
								(size 1.27 1.27)
							)
						)
					)
				)
				(pin bidirectional line
					(at 40.64 -29.21 180)
					(length 2.54)
					(name "BDBUS3"
						(effects
							(font
								(size 1.27 1.27)
							)
						)
					)
					(number "25"
						(effects
							(font
								(size 1.27 1.27)
							)
						)
					)
				)
				(pin bidirectional line
					(at 40.64 -31.75 180)
					(length 2.54)
					(name "BDBUS4"
						(effects
							(font
								(size 1.27 1.27)
							)
						)
					)
					(number "26"
						(effects
							(font
								(size 1.27 1.27)
							)
						)
					)
				)
				(pin bidirectional line
					(at 40.64 -34.29 180)
					(length 2.54)
					(name "BDBUS5"
						(effects
							(font
								(size 1.27 1.27)
							)
						)
					)
					(number "27"
						(effects
							(font
								(size 1.27 1.27)
							)
						)
					)
				)
				(pin bidirectional line
					(at 40.64 -36.83 180)
					(length 2.54)
					(name "BDBUS6"
						(effects
							(font
								(size 1.27 1.27)
							)
						)
					)
					(number "28"
						(effects
							(font
								(size 1.27 1.27)
							)
						)
					)
				)
				(pin bidirectional line
					(at 40.64 -39.37 180)
					(length 2.54)
					(name "BDBUS7"
						(effects
							(font
								(size 1.27 1.27)
							)
						)
					)
					(number "29"
						(effects
							(font
								(size 1.27 1.27)
							)
						)
					)
				)
				(pin bidirectional line
					(at 40.64 -43.18 180)
					(length 2.54)
					(name "CDBUS0"
						(effects
							(font
								(size 1.27 1.27)
							)
						)
					)
					(number "32"
						(effects
							(font
								(size 1.27 1.27)
							)
						)
					)
				)
				(pin bidirectional line
					(at 40.64 -45.72 180)
					(length 2.54)
					(name "CDBUS1"
						(effects
							(font
								(size 1.27 1.27)
							)
						)
					)
					(number "33"
						(effects
							(font
								(size 1.27 1.27)
							)
						)
					)
				)
				(pin bidirectional line
					(at 40.64 -48.26 180)
					(length 2.54)
					(name "CDBUS2"
						(effects
							(font
								(size 1.27 1.27)
							)
						)
					)
					(number "34"
						(effects
							(font
								(size 1.27 1.27)
							)
						)
					)
				)
				(pin bidirectional line
					(at 40.64 -50.8 180)
					(length 2.54)
					(name "CDBUS3"
						(effects
							(font
								(size 1.27 1.27)
							)
						)
					)
					(number "35"
						(effects
							(font
								(size 1.27 1.27)
							)
						)
					)
				)
				(pin bidirectional line
					(at 40.64 -53.34 180)
					(length 2.54)
					(name "CDBUS4"
						(effects
							(font
								(size 1.27 1.27)
							)
						)
					)
					(number "37"
						(effects
							(font
								(size 1.27 1.27)
							)
						)
					)
				)
				(pin bidirectional line
					(at 40.64 -55.88 180)
					(length 2.54)
					(name "CDBUS5"
						(effects
							(font
								(size 1.27 1.27)
							)
						)
					)
					(number "38"
						(effects
							(font
								(size 1.27 1.27)
							)
						)
					)
				)
				(pin bidirectional line
					(at 40.64 -58.42 180)
					(length 2.54)
					(name "CDBUS6"
						(effects
							(font
								(size 1.27 1.27)
							)
						)
					)
					(number "39"
						(effects
							(font
								(size 1.27 1.27)
							)
						)
					)
				)
				(pin bidirectional line
					(at 40.64 -60.96 180)
					(length 2.54)
					(name "CDBUS7"
						(effects
							(font
								(size 1.27 1.27)
							)
						)
					)
					(number "40"
						(effects
							(font
								(size 1.27 1.27)
							)
						)
					)
				)
				(pin bidirectional line
					(at 40.64 -64.77 180)
					(length 2.54)
					(name "DDBUS0"
						(effects
							(font
								(size 1.27 1.27)
							)
						)
					)
					(number "42"
						(effects
							(font
								(size 1.27 1.27)
							)
						)
					)
				)
				(pin bidirectional line
					(at 40.64 -67.31 180)
					(length 2.54)
					(name "DDBUS1"
						(effects
							(font
								(size 1.27 1.27)
							)
						)
					)
					(number "46"
						(effects
							(font
								(size 1.27 1.27)
							)
						)
					)
				)
				(pin bidirectional line
					(at 40.64 -69.85 180)
					(length 2.54)
					(name "DDBUS2"
						(effects
							(font
								(size 1.27 1.27)
							)
						)
					)
					(number "47"
						(effects
							(font
								(size 1.27 1.27)
							)
						)
					)
				)
				(pin bidirectional line
					(at 40.64 -72.39 180)
					(length 2.54)
					(name "DDBUS3"
						(effects
							(font
								(size 1.27 1.27)
							)
						)
					)
					(number "48"
						(effects
							(font
								(size 1.27 1.27)
							)
						)
					)
				)
				(pin bidirectional line
					(at 40.64 -74.93 180)
					(length 2.54)
					(name "DDBUS4"
						(effects
							(font
								(size 1.27 1.27)
							)
						)
					)
					(number "49"
						(effects
							(font
								(size 1.27 1.27)
							)
						)
					)
				)
				(pin bidirectional line
					(at 40.64 -77.47 180)
					(length 2.54)
					(name "DDBUS5"
						(effects
							(font
								(size 1.27 1.27)
							)
						)
					)
					(number "51"
						(effects
							(font
								(size 1.27 1.27)
							)
						)
					)
				)
				(pin bidirectional line
					(at 40.64 -80.01 180)
					(length 2.54)
					(name "DDBUS6"
						(effects
							(font
								(size 1.27 1.27)
							)
						)
					)
					(number "52"
						(effects
							(font
								(size 1.27 1.27)
							)
						)
					)
				)
				(pin bidirectional line
					(at 40.64 -82.55 180)
					(length 2.54)
					(name "DDBUS7"
						(effects
							(font
								(size 1.27 1.27)
							)
						)
					)
					(number "53"
						(effects
							(font
								(size 1.27 1.27)
							)
						)
					)
				)
				(pin output line
					(at 40.64 -87.63 180)
					(length 2.54)
					(name "~{PWR_{EN}}"
						(effects
							(font
								(size 1.27 1.27)
							)
						)
					)
					(number "54"
						(effects
							(font
								(size 1.27 1.27)
							)
						)
					)
				)
				(pin output line
					(at 40.64 -90.17 180)
					(length 2.54)
					(name "~{SUSPEND}"
						(effects
							(font
								(size 1.27 1.27)
							)
						)
					)
					(number "30"
						(effects
							(font
								(size 1.27 1.27)
							)
						)
					)
				)
			)
		)
	(symbol "antmicroInterfaceControllers:KSZ9031RNXCA"
			(exclude_from_sim no)
			(in_bom yes)
			(on_board yes)
			(property "Reference" "U"
				(at 76.2 -5.08 0)
				(effects
					(font
						(size 1.27 1.27)
						(thickness 0.15)
					)
					(justify left bottom)
				)
			)
			(property "Value" "KSZ9031RNXCA"
				(at 76.2 -7.62 0)
				(effects
					(font
						(size 1.27 1.27)
						(thickness 0.15)
					)
					(justify left bottom)
				)
			)
			(property "Footprint" "antmicro-footprints:QFN-48-1EP_7x7x0.9mm_P0.5mm_EP3.5x3.5mm"
				(at 76.2 -10.16 0)
				(effects
					(font
						(size 1.27 1.27)
						(thickness 0.15)
					)
					(justify left bottom)
					(hide yes)
				)
			)
			(property "Datasheet" "http://ww1.microchip.com/downloads/en/DeviceDoc/00002117F.pdf"
				(at 76.2 -12.7 0)
				(effects
					(font
						(size 1.27 1.27)
						(thickness 0.15)
					)
					(justify left bottom)
					(hide yes)
				)
			)
			(property "Description" "Ethernet Controller, 1000 Mbps, IEEE 802.3, 1.14 V, 3.465 V, QFN, 48 Pins"
				(at 0 0 0)
				(effects
					(font
						(size 1.27 1.27)
					)
					(hide yes)
				)
			)
			(property "Manufacturer" "Microchip Technology"
				(at 76.2 -15.24 0)
				(effects
					(font
						(size 1.27 1.27)
						(thickness 0.15)
					)
					(justify left bottom)
					(hide yes)
				)
			)
			(property "MPN" "KSZ9031RNXCA"
				(at 76.2 -17.78 0)
				(effects
					(font
						(size 1.27 1.27)
						(thickness 0.15)
					)
					(justify left bottom)
					(hide yes)
				)
			)
			(property "Author" "Antmicro"
				(at 76.2 -20.32 0)
				(effects
					(font
						(size 1.27 1.27)
						(thickness 0.15)
					)
					(justify left bottom)
					(hide yes)
				)
			)
			(property "License" "Apache-2.0"
				(at 76.2 -22.86 0)
				(effects
					(font
						(size 1.27 1.27)
						(thickness 0.15)
					)
					(justify left bottom)
					(hide yes)
				)
			)
			(property "ki_keywords" "SMT, TRANSCEIVER, IC, ETHERNET, PHY"
				(at 0 0 0)
				(effects
					(font
						(size 1.27 1.27)
					)
					(hide yes)
				)
			)
			(symbol "KSZ9031RNXCA_1_1"
				(rectangle
					(start 2.54 2.54)
					(end 41.91 -62.23)
					(stroke
						(width 0.254)
						(type default)
					)
					(fill
						(type background)
					)
				)
				(text "10/100/1000"
					(at 21.59 -1.27 0)
					(effects
						(font
							(size 1.27 1.27)
							(thickness 0.15)
						)
						(justify bottom)
					)
				)
				(text "Ethernet PHY"
					(at 21.59 -3.81 0)
					(effects
						(font
							(size 1.27 1.27)
							(thickness 0.15)
						)
						(justify bottom)
					)
				)
				(pin power_in line
					(at 0 0 0)
					(length 2.54)
					(name "DVDDH"
						(effects
							(font
								(size 1.27 1.27)
							)
						)
					)
					(number "16"
						(effects
							(font
								(size 1.27 1.27)
							)
						)
					)
				)
				(pin passive line
					(at 0 0 0)
					(length 2.54)
					(hide yes)
					(name "DVDDH"
						(effects
							(font
								(size 1.27 1.27)
							)
						)
					)
					(number "34"
						(effects
							(font
								(size 1.27 1.27)
							)
						)
					)
				)
				(pin passive line
					(at 0 0 0)
					(length 2.54)
					(hide yes)
					(name "DVDDH"
						(effects
							(font
								(size 1.27 1.27)
							)
						)
					)
					(number "40"
						(effects
							(font
								(size 1.27 1.27)
							)
						)
					)
				)
				(pin power_in line
					(at 0 -3.81 0)
					(length 2.54)
					(name "AVDDH"
						(effects
							(font
								(size 1.27 1.27)
							)
						)
					)
					(number "1"
						(effects
							(font
								(size 1.27 1.27)
							)
						)
					)
				)
				(pin passive line
					(at 0 -3.81 0)
					(length 2.54)
					(hide yes)
					(name "AVDDH"
						(effects
							(font
								(size 1.27 1.27)
							)
						)
					)
					(number "12"
						(effects
							(font
								(size 1.27 1.27)
							)
						)
					)
				)
				(pin input line
					(at 0 -7.62 0)
					(length 2.54)
					(name "~{RESET}"
						(effects
							(font
								(size 1.27 1.27)
							)
						)
					)
					(number "42"
						(effects
							(font
								(size 1.27 1.27)
							)
						)
					)
				)
				(pin input line
					(at 0 -10.16 0)
					(length 2.54)
					(name "~{INT/PME}"
						(effects
							(font
								(size 1.27 1.27)
							)
						)
					)
					(number "38"
						(effects
							(font
								(size 1.27 1.27)
							)
						)
					)
				)
				(pin input line
					(at 0 -13.97 0)
					(length 2.54)
					(name "MDC"
						(effects
							(font
								(size 1.27 1.27)
							)
						)
					)
					(number "36"
						(effects
							(font
								(size 1.27 1.27)
							)
						)
					)
				)
				(pin input line
					(at 0 -16.51 0)
					(length 2.54)
					(name "MDIO"
						(effects
							(font
								(size 1.27 1.27)
							)
						)
					)
					(number "37"
						(effects
							(font
								(size 1.27 1.27)
							)
						)
					)
				)
				(pin input line
					(at 0 -20.32 0)
					(length 2.54)
					(name "TX_EN"
						(effects
							(font
								(size 1.27 1.27)
							)
						)
					)
					(number "25"
						(effects
							(font
								(size 1.27 1.27)
							)
						)
					)
				)
				(pin input line
					(at 0 -22.86 0)
					(length 2.54)
					(name "TXD0"
						(effects
							(font
								(size 1.27 1.27)
							)
						)
					)
					(number "19"
						(effects
							(font
								(size 1.27 1.27)
							)
						)
					)
				)
				(pin input line
					(at 0 -25.4 0)
					(length 2.54)
					(name "TXD1"
						(effects
							(font
								(size 1.27 1.27)
							)
						)
					)
					(number "20"
						(effects
							(font
								(size 1.27 1.27)
							)
						)
					)
				)
				(pin input line
					(at 0 -27.94 0)
					(length 2.54)
					(name "TXD2"
						(effects
							(font
								(size 1.27 1.27)
							)
						)
					)
					(number "21"
						(effects
							(font
								(size 1.27 1.27)
							)
						)
					)
				)
				(pin input line
					(at 0 -30.48 0)
					(length 2.54)
					(name "TXD3"
						(effects
							(font
								(size 1.27 1.27)
							)
						)
					)
					(number "22"
						(effects
							(font
								(size 1.27 1.27)
							)
						)
					)
				)
				(pin input clock
					(at 0 -33.02 0)
					(length 2.54)
					(name "GTX_CLK"
						(effects
							(font
								(size 1.27 1.27)
							)
						)
					)
					(number "24"
						(effects
							(font
								(size 1.27 1.27)
							)
						)
					)
				)
				(pin input line
					(at 0 -36.83 0)
					(length 2.54)
					(name "RX_DV/CLK125_EN"
						(effects
							(font
								(size 1.27 1.27)
							)
						)
					)
					(number "33"
						(effects
							(font
								(size 1.27 1.27)
							)
						)
					)
				)
				(pin input line
					(at 0 -39.37 0)
					(length 2.54)
					(name "RXD0/MODE0"
						(effects
							(font
								(size 1.27 1.27)
							)
						)
					)
					(number "32"
						(effects
							(font
								(size 1.27 1.27)
							)
						)
					)
				)
				(pin input line
					(at 0 -41.91 0)
					(length 2.54)
					(name "RXD1/MODE1"
						(effects
							(font
								(size 1.27 1.27)
							)
						)
					)
					(number "31"
						(effects
							(font
								(size 1.27 1.27)
							)
						)
					)
				)
				(pin input line
					(at 0 -44.45 0)
					(length 2.54)
					(name "RXD2/MODE2"
						(effects
							(font
								(size 1.27 1.27)
							)
						)
					)
					(number "28"
						(effects
							(font
								(size 1.27 1.27)
							)
						)
					)
				)
				(pin input line
					(at 0 -46.99 0)
					(length 2.54)
					(name "RXD3/MODE3"
						(effects
							(font
								(size 1.27 1.27)
							)
						)
					)
					(number "27"
						(effects
							(font
								(size 1.27 1.27)
							)
						)
					)
				)
				(pin input clock
					(at 0 -49.53 0)
					(length 2.54)
					(name "RX_CLK/PHYAD2"
						(effects
							(font
								(size 1.27 1.27)
							)
						)
					)
					(number "35"
						(effects
							(font
								(size 1.27 1.27)
							)
						)
					)
				)
				(pin input clock
					(at 0 -53.34 0)
					(length 2.54)
					(name "CLK125_NDO/LED_MODE"
						(effects
							(font
								(size 1.27 1.27)
							)
						)
					)
					(number "41"
						(effects
							(font
								(size 1.27 1.27)
							)
						)
					)
				)
				(pin input line
					(at 0 -57.15 0)
					(length 2.54)
					(name "XI"
						(effects
							(font
								(size 1.27 1.27)
							)
						)
					)
					(number "46"
						(effects
							(font
								(size 1.27 1.27)
							)
						)
					)
				)
				(pin input line
					(at 0 -59.69 0)
					(length 2.54)
					(name "XO"
						(effects
							(font
								(size 1.27 1.27)
							)
						)
					)
					(number "45"
						(effects
							(font
								(size 1.27 1.27)
							)
						)
					)
				)
				(pin no_connect line
					(at 25.4 -62.23 90)
					(length 2.54)
					(hide yes)
					(name "NC"
						(effects
							(font
								(size 1.27 1.27)
							)
						)
					)
					(number "13"
						(effects
							(font
								(size 1.27 1.27)
							)
						)
					)
				)
				(pin no_connect line
					(at 28.575 -62.23 90)
					(length 2.54)
					(hide yes)
					(name "NC"
						(effects
							(font
								(size 1.27 1.27)
							)
						)
					)
					(number "47"
						(effects
							(font
								(size 1.27 1.27)
							)
						)
					)
				)
				(pin power_in line
					(at 44.45 0 180)
					(length 2.54)
					(name "DVDDL"
						(effects
							(font
								(size 1.27 1.27)
							)
						)
					)
					(number "14"
						(effects
							(font
								(size 1.27 1.27)
							)
						)
					)
				)
				(pin passive line
					(at 44.45 0 180)
					(length 2.54)
					(hide yes)
					(name "DVDDL"
						(effects
							(font
								(size 1.27 1.27)
							)
						)
					)
					(number "18"
						(effects
							(font
								(size 1.27 1.27)
							)
						)
					)
				)
				(pin passive line
					(at 44.45 0 180)
					(length 2.54)
					(hide yes)
					(name "DVDDL"
						(effects
							(font
								(size 1.27 1.27)
							)
						)
					)
					(number "23"
						(effects
							(font
								(size 1.27 1.27)
							)
						)
					)
				)
				(pin passive line
					(at 44.45 0 180)
					(length 2.54)
					(hide yes)
					(name "DVDDL"
						(effects
							(font
								(size 1.27 1.27)
							)
						)
					)
					(number "26"
						(effects
							(font
								(size 1.27 1.27)
							)
						)
					)
				)
				(pin passive line
					(at 44.45 0 180)
					(length 2.54)
					(hide yes)
					(name "DVDDL"
						(effects
							(font
								(size 1.27 1.27)
							)
						)
					)
					(number "30"
						(effects
							(font
								(size 1.27 1.27)
							)
						)
					)
				)
				(pin passive line
					(at 44.45 0 180)
					(length 2.54)
					(hide yes)
					(name "DVDDL"
						(effects
							(font
								(size 1.27 1.27)
							)
						)
					)
					(number "39"
						(effects
							(font
								(size 1.27 1.27)
							)
						)
					)
				)
				(pin power_in line
					(at 44.45 -3.81 180)
					(length 2.54)
					(name "AVDDL"
						(effects
							(font
								(size 1.27 1.27)
							)
						)
					)
					(number "4"
						(effects
							(font
								(size 1.27 1.27)
							)
						)
					)
				)
				(pin passive line
					(at 44.45 -3.81 180)
					(length 2.54)
					(hide yes)
					(name "AVDDL"
						(effects
							(font
								(size 1.27 1.27)
							)
						)
					)
					(number "9"
						(effects
							(font
								(size 1.27 1.27)
							)
						)
					)
				)
				(pin power_in line
					(at 44.45 -6.35 180)
					(length 2.54)
					(name "AVDDL_PLL"
						(effects
							(font
								(size 1.27 1.27)
							)
						)
					)
					(number "44"
						(effects
							(font
								(size 1.27 1.27)
							)
						)
					)
				)
				(pin input line
					(at 44.45 -8.89 180)
					(length 2.54)
					(name "LDO_O"
						(effects
							(font
								(size 1.27 1.27)
							)
						)
					)
					(number "43"
						(effects
							(font
								(size 1.27 1.27)
							)
						)
					)
				)
				(pin bidirectional line
					(at 44.45 -13.97 180)
					(length 2.54)
					(name "TXRXP_A"
						(effects
							(font
								(size 1.27 1.27)
							)
						)
					)
					(number "2"
						(effects
							(font
								(size 1.27 1.27)
							)
						)
					)
				)
				(pin bidirectional line
					(at 44.45 -16.51 180)
					(length 2.54)
					(name "TXRXM_A"
						(effects
							(font
								(size 1.27 1.27)
							)
						)
					)
					(number "3"
						(effects
							(font
								(size 1.27 1.27)
							)
						)
					)
				)
				(pin bidirectional line
					(at 44.45 -20.32 180)
					(length 2.54)
					(name "TXRXP_B"
						(effects
							(font
								(size 1.27 1.27)
							)
						)
					)
					(number "5"
						(effects
							(font
								(size 1.27 1.27)
							)
						)
					)
				)
				(pin bidirectional line
					(at 44.45 -22.86 180)
					(length 2.54)
					(name "TXRXM_B"
						(effects
							(font
								(size 1.27 1.27)
							)
						)
					)
					(number "6"
						(effects
							(font
								(size 1.27 1.27)
							)
						)
					)
				)
				(pin bidirectional line
					(at 44.45 -26.67 180)
					(length 2.54)
					(name "TXRXP_C"
						(effects
							(font
								(size 1.27 1.27)
							)
						)
					)
					(number "7"
						(effects
							(font
								(size 1.27 1.27)
							)
						)
					)
				)
				(pin bidirectional line
					(at 44.45 -29.21 180)
					(length 2.54)
					(name "TXRXM_C"
						(effects
							(font
								(size 1.27 1.27)
							)
						)
					)
					(number "8"
						(effects
							(font
								(size 1.27 1.27)
							)
						)
					)
				)
				(pin bidirectional line
					(at 44.45 -33.02 180)
					(length 2.54)
					(name "TXRXP_D"
						(effects
							(font
								(size 1.27 1.27)
							)
						)
					)
					(number "10"
						(effects
							(font
								(size 1.27 1.27)
							)
						)
					)
				)
				(pin bidirectional line
					(at 44.45 -35.56 180)
					(length 2.54)
					(name "TXRXM_D"
						(effects
							(font
								(size 1.27 1.27)
							)
						)
					)
					(number "11"
						(effects
							(font
								(size 1.27 1.27)
							)
						)
					)
				)
				(pin bidirectional line
					(at 44.45 -41.91 180)
					(length 2.54)
					(name "LED1/PHAD0/PME_N1"
						(effects
							(font
								(size 1.27 1.27)
							)
						)
					)
					(number "17"
						(effects
							(font
								(size 1.27 1.27)
							)
						)
					)
				)
				(pin bidirectional line
					(at 44.45 -44.45 180)
					(length 2.54)
					(name "LED2/PHYAD1"
						(effects
							(font
								(size 1.27 1.27)
							)
						)
					)
					(number "15"
						(effects
							(font
								(size 1.27 1.27)
							)
						)
					)
				)
				(pin output line
					(at 44.45 -49.53 180)
					(length 2.54)
					(name "ISET"
						(effects
							(font
								(size 1.27 1.27)
							)
						)
					)
					(number "48"
						(effects
							(font
								(size 1.27 1.27)
							)
						)
					)
				)
				(pin power_in line
					(at 44.45 -57.15 180)
					(length 2.54)
					(name "PAD_GND"
						(effects
							(font
								(size 1.27 1.27)
							)
						)
					)
					(number "49"
						(effects
							(font
								(size 1.27 1.27)
							)
						)
					)
				)
				(pin power_in line
					(at 44.45 -59.69 180)
					(length 2.54)
					(name "VSS"
						(effects
							(font
								(size 1.27 1.27)
							)
						)
					)
					(number "29"
						(effects
							(font
								(size 1.27 1.27)
							)
						)
					)
				)
			)
		)
	(symbol "antmicroLEDIndicationDiscrete:LED_G_0603_KP-1608CGCK"
			(pin_names
				(hide yes)
			)
			(exclude_from_sim no)
			(in_bom yes)
			(on_board yes)
			(property "Reference" "D"
				(at 22.86 -5.08 0)
				(effects
					(font
						(size 1.27 1.27)
						(thickness 0.15)
					)
					(justify left bottom)
				)
			)
			(property "Value" "LED_G_0603_KP-1608CGCK"
				(at 22.86 -7.62 0)
				(effects
					(font
						(size 1.27 1.27)
						(thickness 0.15)
					)
					(justify left bottom)
				)
			)
			(property "Footprint" "antmicro-footprints:LED_0603_1608Metric_G"
				(at 22.86 -10.16 0)
				(effects
					(font
						(size 1.27 1.27)
						(thickness 0.15)
					)
					(justify left bottom)
					(hide yes)
				)
			)
			(property "Datasheet" "http://www.farnell.com/datasheets/2045956.pdf"
				(at 22.86 -12.7 0)
				(effects
					(font
						(size 1.27 1.27)
						(thickness 0.15)
					)
					(justify left bottom)
					(hide yes)
				)
			)
			(property "Description" "LED, Low Power, Green, SMT, 0603, 20 mA, 2.1 V, 570 nm"
				(at 0 0 0)
				(effects
					(font
						(size 1.27 1.27)
					)
					(hide yes)
				)
			)
			(property "MPN" "KP-1608CGCK"
				(at 22.86 -15.24 0)
				(effects
					(font
						(size 1.27 1.27)
						(thickness 0.15)
					)
					(justify left bottom)
					(hide yes)
				)
			)
			(property "Manufacturer" "Kingbright"
				(at 22.86 -17.78 0)
				(effects
					(font
						(size 1.27 1.27)
						(thickness 0.15)
					)
					(justify left bottom)
					(hide yes)
				)
			)
			(property "Author" "Antmicro"
				(at 22.86 -20.32 0)
				(effects
					(font
						(size 1.27 1.27)
						(thickness 0.15)
					)
					(justify left bottom)
					(hide yes)
				)
			)
			(property "License" "Apache-2.0"
				(at 22.86 -22.86 0)
				(effects
					(font
						(size 1.27 1.27)
						(thickness 0.15)
					)
					(justify left bottom)
					(hide yes)
				)
			)
			(property "ki_keywords" "0603, SMT, LED, SEMICONDUCTOR"
				(at 0 0 0)
				(effects
					(font
						(size 1.27 1.27)
					)
					(hide yes)
				)
			)
			(symbol "LED_G_0603_KP-1608CGCK_1_1"
				(polyline
					(pts
						(xy 2.54 1.27) (xy 2.54 -1.27) (xy 5.08 0) (xy 2.54 1.27)
					)
					(stroke
						(width 0.254)
						(type default)
					)
					(fill
						(type outline)
					)
				)
				(polyline
					(pts
						(xy 3.683 2.286) (xy 3.683 1.778) (xy 3.683 2.286) (xy 3.175 2.286) (xy 3.683 2.286) (xy 2.794 1.397)
					)
					(stroke
						(width 0.254)
						(type default)
					)
					(fill
						(type none)
					)
				)
				(polyline
					(pts
						(xy 4.699 2.032) (xy 4.699 1.524) (xy 4.699 2.032) (xy 4.191 2.032) (xy 4.699 2.032) (xy 3.683 1.016)
					)
					(stroke
						(width 0.254)
						(type default)
					)
					(fill
						(type none)
					)
				)
				(polyline
					(pts
						(xy 5.08 1.27) (xy 5.08 -1.27)
					)
					(stroke
						(width 0.254)
						(type default)
					)
					(fill
						(type none)
					)
				)
				(pin passive line
					(at 0 0 0)
					(length 2.54)
					(name "1"
						(effects
							(font
								(size 1.27 1.27)
							)
						)
					)
					(number "1"
						(effects
							(font
								(size 1.27 1.27)
							)
						)
					)
				)
				(pin passive line
					(at 7.62 0 180)
					(length 2.54)
					(name "2"
						(effects
							(font
								(size 1.27 1.27)
							)
						)
					)
					(number "2"
						(effects
							(font
								(size 1.27 1.27)
							)
						)
					)
				)
			)
		)
	(symbol "antmicroLEDIndicationDiscrete:LED_RGY_0606_APTF1616SURKCGKSYKC"
			(exclude_from_sim no)
			(in_bom yes)
			(on_board yes)
			(property "Reference" "D"
				(at 33.02 -3.81 0)
				(effects
					(font
						(size 1.27 1.27)
						(thickness 0.15)
					)
					(justify left bottom)
				)
			)
			(property "Value" "LED_RGY_0606_APTF1616SURKCGKSYKC"
				(at 33.02 -6.35 0)
				(effects
					(font
						(size 1.27 1.27)
						(thickness 0.15)
					)
					(justify left bottom)
				)
			)
			(property "Footprint" "antmicro-footprints:LED_RGY_1.6x1.6mm_APTF1616"
				(at 33.02 -8.89 0)
				(effects
					(font
						(size 1.27 1.27)
						(thickness 0.15)
					)
					(justify left bottom)
					(hide yes)
				)
			)
			(property "Datasheet" "http://www.mouser.com/datasheet/2/216/APTF1616SURKCGKSYKC-1145193.pdf"
				(at 33.02 -11.43 0)
				(effects
					(font
						(size 1.27 1.27)
						(thickness 0.15)
					)
					(justify left bottom)
					(hide yes)
				)
			)
			(property "Description" "Green, Red, Yellow 570nm Green, 630nm Red, 590nm Yellow LED Indication - Discrete 2.1V Green, 1.95V Red, 2V Yellow 4-SMD, No Lead"
				(at 33.02 -13.97 0)
				(effects
					(font
						(size 1.27 1.27)
						(thickness 0.15)
					)
					(justify left bottom)
					(hide yes)
				)
			)
			(property "MPN" "APTF1616SURKCGKSYKC"
				(at 33.02 -16.51 0)
				(effects
					(font
						(size 1.27 1.27)
						(thickness 0.15)
					)
					(justify left bottom)
					(hide yes)
				)
			)
			(property "Manufacturer" "Kingbright"
				(at 33.02 -19.05 0)
				(effects
					(font
						(size 1.27 1.27)
						(thickness 0.15)
					)
					(justify left bottom)
					(hide yes)
				)
			)
			(property "Author" "Antmicro"
				(at 33.02 -21.59 0)
				(effects
					(font
						(size 1.27 1.27)
						(thickness 0.15)
					)
					(justify left bottom)
					(hide yes)
				)
			)
			(property "License" "Apache-2.0"
				(at 33.02 -24.13 0)
				(effects
					(font
						(size 1.27 1.27)
						(thickness 0.15)
					)
					(justify left bottom)
					(hide yes)
				)
			)
			(property "ki_keywords" "LED"
				(at 0 0 0)
				(effects
					(font
						(size 1.27 1.27)
					)
					(hide yes)
				)
			)
			(symbol "LED_RGY_0606_APTF1616SURKCGKSYKC_1_1"
				(polyline
					(pts
						(xy 6.35 -3.81) (xy 5.08 -3.81)
					)
					(stroke
						(width 0.254)
						(type default)
					)
					(fill
						(type none)
					)
				)
				(polyline
					(pts
						(xy 6.35 -3.81) (xy 6.35 -7.62) (xy 8.89 -7.62)
					)
					(stroke
						(width 0.254)
						(type default)
					)
					(fill
						(type none)
					)
				)
				(polyline
					(pts
						(xy 8.89 1.27) (xy 8.89 -1.27) (xy 11.43 0) (xy 8.89 1.27)
					)
					(stroke
						(width 0.254)
						(type default)
					)
					(fill
						(type outline)
					)
				)
				(polyline
					(pts
						(xy 8.89 -2.54) (xy 8.89 -5.08) (xy 11.43 -3.81) (xy 8.89 -2.54)
					)
					(stroke
						(width 0.254)
						(type default)
					)
					(fill
						(type outline)
					)
				)
				(polyline
					(pts
						(xy 8.89 -3.81) (xy 6.35 -3.81) (xy 6.35 0) (xy 8.89 0)
					)
					(stroke
						(width 0.254)
						(type default)
					)
					(fill
						(type none)
					)
				)
				(polyline
					(pts
						(xy 8.89 -6.35) (xy 8.89 -8.89) (xy 11.43 -7.62) (xy 8.89 -6.35)
					)
					(stroke
						(width 0.254)
						(type default)
					)
					(fill
						(type outline)
					)
				)
				(polyline
					(pts
						(xy 10.033 2.286) (xy 10.033 1.778) (xy 10.033 2.286) (xy 9.525 2.286) (xy 10.033 2.286) (xy 9.144 1.397)
					)
					(stroke
						(width 0.254)
						(type default)
					)
					(fill
						(type none)
					)
				)
				(polyline
					(pts
						(xy 10.033 -1.524) (xy 10.033 -2.032) (xy 10.033 -1.524) (xy 9.525 -1.524) (xy 10.033 -1.524)
						(xy 9.144 -2.413)
					)
					(stroke
						(width 0.254)
						(type default)
					)
					(fill
						(type none)
					)
				)
				(polyline
					(pts
						(xy 10.033 -5.334) (xy 10.033 -5.842) (xy 10.033 -5.334) (xy 9.525 -5.334) (xy 10.033 -5.334)
						(xy 9.144 -6.223)
					)
					(stroke
						(width 0.254)
						(type default)
					)
					(fill
						(type none)
					)
				)
				(polyline
					(pts
						(xy 11.049 2.032) (xy 11.049 1.524) (xy 11.049 2.032) (xy 10.541 2.032) (xy 11.049 2.032) (xy 10.033 1.016)
					)
					(stroke
						(width 0.254)
						(type default)
					)
					(fill
						(type none)
					)
				)
				(polyline
					(pts
						(xy 11.049 -1.778) (xy 11.049 -2.286) (xy 11.049 -1.778) (xy 10.541 -1.778) (xy 11.049 -1.778)
						(xy 10.033 -2.794)
					)
					(stroke
						(width 0.254)
						(type default)
					)
					(fill
						(type none)
					)
				)
				(polyline
					(pts
						(xy 11.049 -5.588) (xy 11.049 -6.096) (xy 11.049 -5.588) (xy 10.541 -5.588) (xy 11.049 -5.588)
						(xy 10.033 -6.604)
					)
					(stroke
						(width 0.254)
						(type default)
					)
					(fill
						(type none)
					)
				)
				(polyline
					(pts
						(xy 11.43 1.27) (xy 11.43 -1.27)
					)
					(stroke
						(width 0.254)
						(type default)
					)
					(fill
						(type none)
					)
				)
				(polyline
					(pts
						(xy 11.43 -2.54) (xy 11.43 -5.08)
					)
					(stroke
						(width 0.254)
						(type default)
					)
					(fill
						(type none)
					)
				)
				(polyline
					(pts
						(xy 11.43 -6.35) (xy 11.43 -8.89)
					)
					(stroke
						(width 0.254)
						(type default)
					)
					(fill
						(type none)
					)
				)
				(polyline
					(pts
						(xy 12.7 0) (xy 11.43 0)
					)
					(stroke
						(width 0.254)
						(type default)
					)
					(fill
						(type none)
					)
				)
				(polyline
					(pts
						(xy 12.7 -3.81) (xy 11.43 -3.81)
					)
					(stroke
						(width 0.254)
						(type default)
					)
					(fill
						(type none)
					)
				)
				(polyline
					(pts
						(xy 12.7 -7.62) (xy 11.43 -7.62)
					)
					(stroke
						(width 0.254)
						(type default)
					)
					(fill
						(type none)
					)
				)
				(rectangle
					(start 16.51 2.54)
					(end 2.54 -10.16)
					(stroke
						(width 0.254)
						(type default)
					)
					(fill
						(type background)
					)
				)
				(pin passive line
					(at 0 -3.81 0)
					(length 2.54)
					(name "A"
						(effects
							(font
								(size 1.27 1.27)
							)
						)
					)
					(number "1"
						(effects
							(font
								(size 1.27 1.27)
							)
						)
					)
				)
				(pin passive line
					(at 19.05 0 180)
					(length 2.54)
					(name "C_{R}"
						(effects
							(font
								(size 1.27 1.27)
							)
						)
					)
					(number "2"
						(effects
							(font
								(size 1.27 1.27)
							)
						)
					)
				)
				(pin passive line
					(at 19.05 -3.81 180)
					(length 2.54)
					(name "C_{G}"
						(effects
							(font
								(size 1.27 1.27)
							)
						)
					)
					(number "3"
						(effects
							(font
								(size 1.27 1.27)
							)
						)
					)
				)
				(pin passive line
					(at 19.05 -7.62 180)
					(length 2.54)
					(name "C_{Y}"
						(effects
							(font
								(size 1.27 1.27)
							)
						)
					)
					(number "4"
						(effects
							(font
								(size 1.27 1.27)
							)
						)
					)
				)
			)
		)
	(symbol "antmicroLogicShiftRegisters:SN74HC595B"
			(exclude_from_sim no)
			(in_bom yes)
			(on_board yes)
			(property "Reference" "U"
				(at 35.56 -5.08 0)
				(effects
					(font
						(size 1.27 1.27)
						(thickness 0.15)
					)
					(justify left bottom)
				)
			)
			(property "Value" "SN74HC595B"
				(at 35.56 -7.62 0)
				(effects
					(font
						(size 1.27 1.27)
						(thickness 0.15)
					)
					(justify left bottom)
				)
			)
			(property "Footprint" "antmicro-footprints:X1QFN-16-1EP_2.5x2.5mm"
				(at 35.56 -10.16 0)
				(effects
					(font
						(size 1.27 1.27)
						(thickness 0.15)
					)
					(justify left bottom)
					(hide yes)
				)
			)
			(property "Datasheet" "https://www.ti.com/general/docs/suppproductinfo.tsp?distId=26&gotoUrl=https://www.ti.com/lit/gpn/sn74hc595b"
				(at 35.56 -12.7 0)
				(effects
					(font
						(size 1.27 1.27)
						(thickness 0.15)
					)
					(justify left bottom)
					(hide yes)
				)
			)
			(property "Description" "Shift Register, 74HC595, Serial to Parallel, 1 Element, 8 bit, X1QFN, 16 Pins"
				(at 0 0 0)
				(effects
					(font
						(size 1.27 1.27)
					)
					(hide yes)
				)
			)
			(property "Manufacturer" "Texas Instruments"
				(at 35.56 -15.24 0)
				(effects
					(font
						(size 1.27 1.27)
						(thickness 0.15)
					)
					(justify left bottom)
					(hide yes)
				)
			)
			(property "MPN" "SN74HC595BRWNR"
				(at 35.56 -17.78 0)
				(effects
					(font
						(size 1.27 1.27)
						(thickness 0.15)
					)
					(justify left bottom)
					(hide yes)
				)
			)
			(property "Author" "Antmicro"
				(at 35.56 -20.32 0)
				(effects
					(font
						(size 1.27 1.27)
						(thickness 0.15)
					)
					(justify left bottom)
					(hide yes)
				)
			)
			(property "License" "Apache-2.0"
				(at 35.56 -22.86 0)
				(effects
					(font
						(size 1.27 1.27)
						(thickness 0.15)
					)
					(justify left bottom)
					(hide yes)
				)
			)
			(property "ki_keywords" "SMT, LOGIC, IC, LEVEL-SHIFTER, VOLTAGE"
				(at 0 0 0)
				(effects
					(font
						(size 1.27 1.27)
					)
					(hide yes)
				)
			)
			(symbol "SN74HC595B_1_1"
				(rectangle
					(start 2.54 2.54)
					(end 17.78 -22.86)
					(stroke
						(width 0.254)
						(type default)
					)
					(fill
						(type background)
					)
				)
				(pin power_in line
					(at 0 0 0)
					(length 2.54)
					(name "VCC"
						(effects
							(font
								(size 1.27 1.27)
							)
						)
					)
					(number "16"
						(effects
							(font
								(size 1.27 1.27)
							)
						)
					)
				)
				(pin input line
					(at 0 -5.08 0)
					(length 2.54)
					(name "~{OE}"
						(effects
							(font
								(size 1.27 1.27)
							)
						)
					)
					(number "13"
						(effects
							(font
								(size 1.27 1.27)
							)
						)
					)
				)
				(pin input line
					(at 0 -7.62 0)
					(length 2.54)
					(name "~{SRCLR}"
						(effects
							(font
								(size 1.27 1.27)
							)
						)
					)
					(number "10"
						(effects
							(font
								(size 1.27 1.27)
							)
						)
					)
				)
				(pin input line
					(at 0 -10.16 0)
					(length 2.54)
					(name "SRCLK"
						(effects
							(font
								(size 1.27 1.27)
							)
						)
					)
					(number "11"
						(effects
							(font
								(size 1.27 1.27)
							)
						)
					)
				)
				(pin input line
					(at 0 -12.7 0)
					(length 2.54)
					(name "RCLK"
						(effects
							(font
								(size 1.27 1.27)
							)
						)
					)
					(number "12"
						(effects
							(font
								(size 1.27 1.27)
							)
						)
					)
				)
				(pin input line
					(at 0 -15.24 0)
					(length 2.54)
					(name "SER"
						(effects
							(font
								(size 1.27 1.27)
							)
						)
					)
					(number "14"
						(effects
							(font
								(size 1.27 1.27)
							)
						)
					)
				)
				(pin power_in line
					(at 0 -20.32 0)
					(length 2.54)
					(name "GND"
						(effects
							(font
								(size 1.27 1.27)
							)
						)
					)
					(number "8"
						(effects
							(font
								(size 1.27 1.27)
							)
						)
					)
				)
				(pin no_connect line
					(at 10.16 -22.86 90)
					(length 2.54)
					(hide yes)
					(name "EP"
						(effects
							(font
								(size 1.27 1.27)
							)
						)
					)
					(number "17"
						(effects
							(font
								(size 1.27 1.27)
							)
						)
					)
				)
				(pin output line
					(at 20.32 0 180)
					(length 2.54)
					(name "QA"
						(effects
							(font
								(size 1.27 1.27)
							)
						)
					)
					(number "15"
						(effects
							(font
								(size 1.27 1.27)
							)
						)
					)
				)
				(pin output line
					(at 20.32 -2.54 180)
					(length 2.54)
					(name "QB"
						(effects
							(font
								(size 1.27 1.27)
							)
						)
					)
					(number "1"
						(effects
							(font
								(size 1.27 1.27)
							)
						)
					)
				)
				(pin output line
					(at 20.32 -5.08 180)
					(length 2.54)
					(name "QC"
						(effects
							(font
								(size 1.27 1.27)
							)
						)
					)
					(number "2"
						(effects
							(font
								(size 1.27 1.27)
							)
						)
					)
				)
				(pin output line
					(at 20.32 -7.62 180)
					(length 2.54)
					(name "QD"
						(effects
							(font
								(size 1.27 1.27)
							)
						)
					)
					(number "3"
						(effects
							(font
								(size 1.27 1.27)
							)
						)
					)
				)
				(pin output line
					(at 20.32 -10.16 180)
					(length 2.54)
					(name "QE"
						(effects
							(font
								(size 1.27 1.27)
							)
						)
					)
					(number "4"
						(effects
							(font
								(size 1.27 1.27)
							)
						)
					)
				)
				(pin output line
					(at 20.32 -12.7 180)
					(length 2.54)
					(name "QF"
						(effects
							(font
								(size 1.27 1.27)
							)
						)
					)
					(number "5"
						(effects
							(font
								(size 1.27 1.27)
							)
						)
					)
				)
				(pin output line
					(at 20.32 -15.24 180)
					(length 2.54)
					(name "QG"
						(effects
							(font
								(size 1.27 1.27)
							)
						)
					)
					(number "6"
						(effects
							(font
								(size 1.27 1.27)
							)
						)
					)
				)
				(pin output line
					(at 20.32 -17.78 180)
					(length 2.54)
					(name "QH"
						(effects
							(font
								(size 1.27 1.27)
							)
						)
					)
					(number "7"
						(effects
							(font
								(size 1.27 1.27)
							)
						)
					)
				)
				(pin output line
					(at 20.32 -20.32 180)
					(length 2.54)
					(name "QH'"
						(effects
							(font
								(size 1.27 1.27)
							)
						)
					)
					(number "9"
						(effects
							(font
								(size 1.27 1.27)
							)
						)
					)
				)
			)
		)
	(symbol "antmicroLogicTranslatorsLevelShifters:PCA9517ADP"
			(exclude_from_sim no)
			(in_bom yes)
			(on_board yes)
			(property "Reference" "U"
				(at 33.02 -2.54 0)
				(effects
					(font
						(size 1.27 1.27)
						(thickness 0.15)
					)
					(justify left bottom)
				)
			)
			(property "Value" "PCA9517ADP"
				(at 33.02 -5.08 0)
				(effects
					(font
						(size 1.27 1.27)
						(thickness 0.15)
					)
					(justify left bottom)
				)
			)
			(property "Footprint" "antmicro-footprints:TSSOP-8_3x3mm_P0.65mm"
				(at 33.02 -7.62 0)
				(effects
					(font
						(size 1.27 1.27)
						(thickness 0.15)
					)
					(justify left bottom)
					(hide yes)
				)
			)
			(property "Datasheet" "https://www.nxp.com/docs/en/data-sheet/PCA9517A.pdf"
				(at 33.02 -10.16 0)
				(effects
					(font
						(size 1.27 1.27)
						(thickness 0.15)
					)
					(justify left bottom)
					(hide yes)
				)
			)
			(property "Description" "Bus Repeater, 0.9 V to 5.5 V, TSSOP-8"
				(at 0 0 0)
				(effects
					(font
						(size 1.27 1.27)
					)
					(hide yes)
				)
			)
			(property "MPN" "PCA9517ADP,118"
				(at 33.02 -12.7 0)
				(effects
					(font
						(size 1.27 1.27)
						(thickness 0.15)
					)
					(justify left bottom)
					(hide yes)
				)
			)
			(property "Manufacturer" "NXP"
				(at 33.02 -15.24 0)
				(effects
					(font
						(size 1.27 1.27)
						(thickness 0.15)
					)
					(justify left bottom)
					(hide yes)
				)
			)
			(property "Author" "Antmicro"
				(at 33.02 -17.78 0)
				(effects
					(font
						(size 1.27 1.27)
						(thickness 0.15)
					)
					(justify left bottom)
					(hide yes)
				)
			)
			(property "License" "Apache-2.0"
				(at 33.02 -20.32 0)
				(effects
					(font
						(size 1.27 1.27)
						(thickness 0.15)
					)
					(justify left bottom)
					(hide yes)
				)
			)
			(property "ki_keywords" "SMT, LEVEL-SHIFTER, IC, I2C"
				(at 0 0 0)
				(effects
					(font
						(size 1.27 1.27)
					)
					(hide yes)
				)
			)
			(symbol "PCA9517ADP_1_1"
				(rectangle
					(start 15.24 2.54)
					(end 2.54 -10.16)
					(stroke
						(width 0.254)
						(type default)
					)
					(fill
						(type background)
					)
				)
				(pin power_in line
					(at 0 0 0)
					(length 2.54)
					(name "V_{CC(A)}"
						(effects
							(font
								(size 1.27 1.27)
							)
						)
					)
					(number "1"
						(effects
							(font
								(size 1.27 1.27)
							)
						)
					)
				)
				(pin input line
					(at 0 -2.54 0)
					(length 2.54)
					(name "SCLA"
						(effects
							(font
								(size 1.27 1.27)
							)
						)
					)
					(number "2"
						(effects
							(font
								(size 1.27 1.27)
							)
						)
					)
				)
				(pin bidirectional line
					(at 0 -5.08 0)
					(length 2.54)
					(name "SDAA"
						(effects
							(font
								(size 1.27 1.27)
							)
						)
					)
					(number "3"
						(effects
							(font
								(size 1.27 1.27)
							)
						)
					)
				)
				(pin power_in line
					(at 0 -7.62 0)
					(length 2.54)
					(name "GND"
						(effects
							(font
								(size 1.27 1.27)
							)
						)
					)
					(number "4"
						(effects
							(font
								(size 1.27 1.27)
							)
						)
					)
				)
				(pin power_in line
					(at 17.78 0 180)
					(length 2.54)
					(name "V_{CC(B)}"
						(effects
							(font
								(size 1.27 1.27)
							)
						)
					)
					(number "8"
						(effects
							(font
								(size 1.27 1.27)
							)
						)
					)
				)
				(pin input line
					(at 17.78 -2.54 180)
					(length 2.54)
					(name "SCLB"
						(effects
							(font
								(size 1.27 1.27)
							)
						)
					)
					(number "7"
						(effects
							(font
								(size 1.27 1.27)
							)
						)
					)
				)
				(pin bidirectional line
					(at 17.78 -5.08 180)
					(length 2.54)
					(name "SDAB"
						(effects
							(font
								(size 1.27 1.27)
							)
						)
					)
					(number "6"
						(effects
							(font
								(size 1.27 1.27)
							)
						)
					)
				)
				(pin input line
					(at 17.78 -7.62 180)
					(length 2.54)
					(name "EN"
						(effects
							(font
								(size 1.27 1.27)
							)
						)
					)
					(number "5"
						(effects
							(font
								(size 1.27 1.27)
							)
						)
					)
				)
			)
		)
	(symbol "antmicroLogicTranslatorsLevelShifters:TXS0102DQER"
			(exclude_from_sim no)
			(in_bom yes)
			(on_board yes)
			(property "Reference" "U"
				(at 33.02 -5.08 0)
				(effects
					(font
						(size 1.27 1.27)
						(thickness 0.15)
					)
					(justify left bottom)
				)
			)
			(property "Value" "TXS0102DQER"
				(at 33.02 -7.62 0)
				(effects
					(font
						(size 1.27 1.27)
						(thickness 0.15)
					)
					(justify left bottom)
				)
			)
			(property "Footprint" "antmicro-footprints:X2SON8_1.4x1x0.32mm_P0.35mm"
				(at 33.02 -10.16 0)
				(effects
					(font
						(size 1.27 1.27)
						(thickness 0.15)
					)
					(justify left bottom)
					(hide yes)
				)
			)
			(property "Datasheet" "https://www.ti.com/lit/ds/symlink/txs0102.pdf?ts=1637914596981&ref_url=https%253A%252F%252Fwww.ti.com%252Fstore%252Fti%252Fen%252Fp%252Fproduct%252F%253Fp%253DTXS0102DCTR%2526keyMatch%253DTXS0102DCTR%2526tisearch%253Dsearch-everything%2526usecase%253DOPN"
				(at 33.02 -12.7 0)
				(effects
					(font
						(size 1.27 1.27)
						(thickness 0.15)
					)
					(justify left bottom)
					(hide yes)
				)
			)
			(property "Description" "Level shifter"
				(at 0 0 0)
				(effects
					(font
						(size 1.27 1.27)
					)
					(hide yes)
				)
			)
			(property "MPN" "TXS0102DQER"
				(at 33.02 -15.24 0)
				(effects
					(font
						(size 1.27 1.27)
						(thickness 0.15)
					)
					(justify left bottom)
					(hide yes)
				)
			)
			(property "Manufacturer" "Texas Instruments"
				(at 33.02 -17.78 0)
				(effects
					(font
						(size 1.27 1.27)
						(thickness 0.15)
					)
					(justify left bottom)
					(hide yes)
				)
			)
			(property "Author" "Antmicro"
				(at 33.02 -20.32 0)
				(effects
					(font
						(size 1.27 1.27)
						(thickness 0.15)
					)
					(justify left bottom)
					(hide yes)
				)
			)
			(property "License" "Apache-2.0"
				(at 33.02 -22.86 0)
				(effects
					(font
						(size 1.27 1.27)
						(thickness 0.15)
					)
					(justify left bottom)
					(hide yes)
				)
			)
			(property "ki_keywords" "IC"
				(at 0 0 0)
				(effects
					(font
						(size 1.27 1.27)
					)
					(hide yes)
				)
			)
			(symbol "TXS0102DQER_1_1"
				(rectangle
					(start 2.54 0)
					(end 15.24 -12.7)
					(stroke
						(width 0.254)
						(type default)
					)
					(fill
						(type background)
					)
				)
				(polyline
					(pts
						(xy 5.715 -7.62) (xy 6.985 -7.62)
					)
					(stroke
						(width 0.254)
						(type default)
					)
					(fill
						(type background)
					)
				)
				(polyline
					(pts
						(xy 6.985 -5.08) (xy 5.715 -5.08)
					)
					(stroke
						(width 0.254)
						(type default)
					)
					(fill
						(type background)
					)
				)
				(polyline
					(pts
						(xy 8.255 -4.445) (xy 6.985 -4.445) (xy 6.985 -5.715) (xy 8.255 -5.715)
					)
					(stroke
						(width 0.254)
						(type default)
					)
					(fill
						(type background)
					)
				)
				(polyline
					(pts
						(xy 8.255 -4.445) (xy 9.525 -3.81) (xy 9.525 -5.08) (xy 8.255 -4.445)
					)
					(stroke
						(width 0.254)
						(type default)
					)
					(fill
						(type background)
					)
				)
				(polyline
					(pts
						(xy 8.255 -5.08) (xy 8.255 -6.35) (xy 9.525 -5.715) (xy 8.255 -5.08)
					)
					(stroke
						(width 0.254)
						(type default)
					)
					(fill
						(type background)
					)
				)
				(polyline
					(pts
						(xy 8.255 -6.985) (xy 6.985 -6.985) (xy 6.985 -8.255) (xy 8.255 -8.255)
					)
					(stroke
						(width 0.254)
						(type default)
					)
					(fill
						(type background)
					)
				)
				(polyline
					(pts
						(xy 8.255 -6.985) (xy 9.525 -6.35) (xy 9.525 -7.62) (xy 8.255 -6.985)
					)
					(stroke
						(width 0.254)
						(type default)
					)
					(fill
						(type background)
					)
				)
				(polyline
					(pts
						(xy 8.255 -7.62) (xy 8.255 -8.89) (xy 9.525 -8.255) (xy 8.255 -7.62)
					)
					(stroke
						(width 0.254)
						(type default)
					)
					(fill
						(type background)
					)
				)
				(polyline
					(pts
						(xy 9.525 -4.445) (xy 10.795 -4.445) (xy 10.795 -5.715) (xy 9.525 -5.715)
					)
					(stroke
						(width 0.254)
						(type default)
					)
					(fill
						(type background)
					)
				)
				(polyline
					(pts
						(xy 9.525 -6.985) (xy 10.795 -6.985) (xy 10.795 -8.255) (xy 9.525 -8.255)
					)
					(stroke
						(width 0.254)
						(type default)
					)
					(fill
						(type background)
					)
				)
				(polyline
					(pts
						(xy 10.795 -5.08) (xy 12.065 -5.08)
					)
					(stroke
						(width 0.254)
						(type default)
					)
					(fill
						(type background)
					)
				)
				(polyline
					(pts
						(xy 12.065 -7.62) (xy 10.795 -7.62)
					)
					(stroke
						(width 0.254)
						(type default)
					)
					(fill
						(type background)
					)
				)
				(pin power_in line
					(at 0 -2.54 0)
					(length 2.54)
					(name "VCCA"
						(effects
							(font
								(size 1.27 1.27)
							)
						)
					)
					(number "1"
						(effects
							(font
								(size 1.27 1.27)
							)
						)
					)
				)
				(pin bidirectional line
					(at 0 -5.08 0)
					(length 2.54)
					(name "A1"
						(effects
							(font
								(size 1.27 1.27)
							)
						)
					)
					(number "2"
						(effects
							(font
								(size 1.27 1.27)
							)
						)
					)
				)
				(pin bidirectional line
					(at 0 -7.62 0)
					(length 2.54)
					(name "A2"
						(effects
							(font
								(size 1.27 1.27)
							)
						)
					)
					(number "3"
						(effects
							(font
								(size 1.27 1.27)
							)
						)
					)
				)
				(pin tri_state line
					(at 0 -10.16 0)
					(length 2.54)
					(name "OE"
						(effects
							(font
								(size 1.27 1.27)
							)
						)
					)
					(number "5"
						(effects
							(font
								(size 1.27 1.27)
							)
						)
					)
				)
				(pin power_in line
					(at 17.78 -2.54 180)
					(length 2.54)
					(name "VCCB"
						(effects
							(font
								(size 1.27 1.27)
							)
						)
					)
					(number "8"
						(effects
							(font
								(size 1.27 1.27)
							)
						)
					)
				)
				(pin bidirectional line
					(at 17.78 -5.08 180)
					(length 2.54)
					(name "B1"
						(effects
							(font
								(size 1.27 1.27)
							)
						)
					)
					(number "7"
						(effects
							(font
								(size 1.27 1.27)
							)
						)
					)
				)
				(pin bidirectional line
					(at 17.78 -7.62 180)
					(length 2.54)
					(name "B2"
						(effects
							(font
								(size 1.27 1.27)
							)
						)
					)
					(number "6"
						(effects
							(font
								(size 1.27 1.27)
							)
						)
					)
				)
				(pin power_in line
					(at 17.78 -10.16 180)
					(length 2.54)
					(name "GND"
						(effects
							(font
								(size 1.27 1.27)
							)
						)
					)
					(number "4"
						(effects
							(font
								(size 1.27 1.27)
							)
						)
					)
				)
			)
		)
	(symbol "antmicroLogicTranslatorsLevelShifters:TXU0304BQAR"
			(exclude_from_sim no)
			(in_bom yes)
			(on_board yes)
			(property "Reference" "U"
				(at 31.75 0 0)
				(effects
					(font
						(size 1.27 1.27)
						(thickness 0.15)
					)
					(justify left bottom)
				)
			)
			(property "Value" "TXU0304BQAR"
				(at 31.75 -2.54 0)
				(effects
					(font
						(size 1.27 1.27)
						(thickness 0.15)
					)
					(justify left bottom)
				)
			)
			(property "Footprint" "antmicro-footprints:DHVQFN-14-1EP_2.5x3mm"
				(at 31.75 -5.08 0)
				(effects
					(font
						(size 1.27 1.27)
						(thickness 0.15)
					)
					(justify left bottom)
					(hide yes)
				)
			)
			(property "Datasheet" "https://www.ti.com/lit/ds/symlink/txu0304.pdf?ts=1637748643258&ref_url=https%253A%252F%252Fwww.ti.com%252Fproduct%252FTXU0304"
				(at 31.75 -7.62 0)
				(effects
					(font
						(size 1.27 1.27)
						(thickness 0.15)
					)
					(justify left bottom)
					(hide yes)
				)
			)
			(property "Description" "Logic translator/level shifter"
				(at 0 0 0)
				(effects
					(font
						(size 1.27 1.27)
					)
					(hide yes)
				)
			)
			(property "MPN" "TXU0304BQAR"
				(at 31.75 -10.16 0)
				(effects
					(font
						(size 1.27 1.27)
						(thickness 0.15)
					)
					(justify left bottom)
					(hide yes)
				)
			)
			(property "Manufacturer" "Texas Instruments"
				(at 31.75 -12.7 0)
				(effects
					(font
						(size 1.27 1.27)
						(thickness 0.15)
					)
					(justify left bottom)
					(hide yes)
				)
			)
			(property "Author" "Antmicro"
				(at 31.75 -15.24 0)
				(effects
					(font
						(size 1.27 1.27)
						(thickness 0.15)
					)
					(justify left bottom)
					(hide yes)
				)
			)
			(property "License" "Apache-2.0"
				(at 31.75 -17.78 0)
				(effects
					(font
						(size 1.27 1.27)
						(thickness 0.15)
					)
					(justify left bottom)
					(hide yes)
				)
			)
			(property "ki_keywords" "SMT, LOGIC, IC, LEVEL-SHIFTER"
				(at 0 0 0)
				(effects
					(font
						(size 1.27 1.27)
					)
					(hide yes)
				)
			)
			(symbol "TXU0304BQAR_1_1"
				(rectangle
					(start 2.54 2.54)
					(end 15.24 -17.78)
					(stroke
						(width 0.254)
						(type default)
					)
					(fill
						(type background)
					)
				)
				(polyline
					(pts
						(xy 6.35 -7.62) (xy 10.16 -7.62)
					)
					(stroke
						(width 0.254)
						(type default)
					)
					(fill
						(type background)
					)
				)
				(polyline
					(pts
						(xy 6.35 -12.7) (xy 10.16 -12.7)
					)
					(stroke
						(width 0.254)
						(type default)
					)
					(fill
						(type background)
					)
				)
				(polyline
					(pts
						(xy 7.62 -4.445) (xy 7.62 -5.715) (xy 8.89 -5.08) (xy 7.62 -4.445)
					)
					(stroke
						(width 0.254)
						(type default)
					)
					(fill
						(type outline)
					)
				)
				(polyline
					(pts
						(xy 7.62 -6.985) (xy 7.62 -8.255) (xy 8.89 -7.62) (xy 7.62 -6.985)
					)
					(stroke
						(width 0.254)
						(type default)
					)
					(fill
						(type outline)
					)
				)
				(polyline
					(pts
						(xy 7.62 -12.7) (xy 8.89 -12.065) (xy 8.89 -13.335) (xy 7.62 -12.7)
					)
					(stroke
						(width 0.254)
						(type default)
					)
					(fill
						(type outline)
					)
				)
				(polyline
					(pts
						(xy 8.89 -10.16) (xy 7.62 -10.795) (xy 7.62 -9.525) (xy 8.89 -10.16)
					)
					(stroke
						(width 0.254)
						(type default)
					)
					(fill
						(type outline)
					)
				)
				(polyline
					(pts
						(xy 10.16 -5.08) (xy 6.35 -5.08)
					)
					(stroke
						(width 0.254)
						(type default)
					)
					(fill
						(type background)
					)
				)
				(polyline
					(pts
						(xy 10.16 -10.16) (xy 6.35 -10.16)
					)
					(stroke
						(width 0.254)
						(type default)
					)
					(fill
						(type background)
					)
				)
				(pin power_in line
					(at 0 0 0)
					(length 2.54)
					(name "VCCA"
						(effects
							(font
								(size 1.27 1.27)
							)
						)
					)
					(number "1"
						(effects
							(font
								(size 1.27 1.27)
							)
						)
					)
				)
				(pin input line
					(at 0 -5.08 0)
					(length 2.54)
					(name "A1"
						(effects
							(font
								(size 1.27 1.27)
							)
						)
					)
					(number "2"
						(effects
							(font
								(size 1.27 1.27)
							)
						)
					)
				)
				(pin input line
					(at 0 -7.62 0)
					(length 2.54)
					(name "A2"
						(effects
							(font
								(size 1.27 1.27)
							)
						)
					)
					(number "3"
						(effects
							(font
								(size 1.27 1.27)
							)
						)
					)
				)
				(pin input line
					(at 0 -10.16 0)
					(length 2.54)
					(name "A3"
						(effects
							(font
								(size 1.27 1.27)
							)
						)
					)
					(number "4"
						(effects
							(font
								(size 1.27 1.27)
							)
						)
					)
				)
				(pin output line
					(at 0 -12.7 0)
					(length 2.54)
					(name "A4Y"
						(effects
							(font
								(size 1.27 1.27)
							)
						)
					)
					(number "5"
						(effects
							(font
								(size 1.27 1.27)
							)
						)
					)
				)
				(pin power_in line
					(at 0 -15.24 0)
					(length 2.54)
					(name "GND"
						(effects
							(font
								(size 1.27 1.27)
							)
						)
					)
					(number "15"
						(effects
							(font
								(size 1.27 1.27)
							)
						)
					)
				)
				(pin passive line
					(at 0 -15.24 0)
					(length 2.54)
					(hide yes)
					(name "GND"
						(effects
							(font
								(size 1.27 1.27)
							)
						)
					)
					(number "7"
						(effects
							(font
								(size 1.27 1.27)
							)
						)
					)
				)
				(pin no_connect line
					(at 2.54 -2.54 0)
					(length 2.54)
					(hide yes)
					(name "NC"
						(effects
							(font
								(size 1.27 1.27)
							)
						)
					)
					(number "6"
						(effects
							(font
								(size 1.27 1.27)
							)
						)
					)
				)
				(pin no_connect line
					(at 15.24 -15.24 180)
					(length 2.54)
					(hide yes)
					(name "NC"
						(effects
							(font
								(size 1.27 1.27)
							)
						)
					)
					(number "9"
						(effects
							(font
								(size 1.27 1.27)
							)
						)
					)
				)
				(pin power_in line
					(at 17.78 0 180)
					(length 2.54)
					(name "VCCB"
						(effects
							(font
								(size 1.27 1.27)
							)
						)
					)
					(number "14"
						(effects
							(font
								(size 1.27 1.27)
							)
						)
					)
				)
				(pin tri_state line
					(at 17.78 -2.54 180)
					(length 2.54)
					(name "OE"
						(effects
							(font
								(size 1.27 1.27)
							)
						)
					)
					(number "8"
						(effects
							(font
								(size 1.27 1.27)
							)
						)
					)
				)
				(pin output line
					(at 17.78 -5.08 180)
					(length 2.54)
					(name "B1Y"
						(effects
							(font
								(size 1.27 1.27)
							)
						)
					)
					(number "13"
						(effects
							(font
								(size 1.27 1.27)
							)
						)
					)
				)
				(pin output line
					(at 17.78 -7.62 180)
					(length 2.54)
					(name "B2Y"
						(effects
							(font
								(size 1.27 1.27)
							)
						)
					)
					(number "12"
						(effects
							(font
								(size 1.27 1.27)
							)
						)
					)
				)
				(pin output line
					(at 17.78 -10.16 180)
					(length 2.54)
					(name "B3Y"
						(effects
							(font
								(size 1.27 1.27)
							)
						)
					)
					(number "11"
						(effects
							(font
								(size 1.27 1.27)
							)
						)
					)
				)
				(pin input line
					(at 17.78 -12.7 180)
					(length 2.54)
					(name "B4"
						(effects
							(font
								(size 1.27 1.27)
							)
						)
					)
					(number "10"
						(effects
							(font
								(size 1.27 1.27)
							)
						)
					)
				)
			)
		)
	(symbol "antmicroMechanicalParts:Heatsink_960-27-12-D-AB-0"
			(pin_names
				(hide yes)
			)
			(exclude_from_sim no)
			(in_bom yes)
			(on_board yes)
			(property "Reference" "H"
				(at 17.78 -2.54 0)
				(effects
					(font
						(size 1.27 1.27)
						(thickness 0.15)
					)
					(justify left bottom)
				)
			)
			(property "Value" "Heatsink_960-27-12-D-AB-0"
				(at 17.78 -7.62 0)
				(effects
					(font
						(size 1.27 1.27)
						(thickness 0.15)
					)
					(justify left bottom)
					(hide yes)
				)
			)
			(property "Footprint" "antmicro-footprints:Heatsink_960-27-12-D-AB-0"
				(at 17.78 -10.16 0)
				(effects
					(font
						(size 1.27 1.27)
						(thickness 0.15)
					)
					(justify left bottom)
					(hide yes)
				)
			)
			(property "Datasheet" "https://media.digikey.com/pdf/Data%20Sheets/Wakefield%20Thermal%20PDFs/960_Series.pdf"
				(at 17.78 -12.7 0)
				(effects
					(font
						(size 1.27 1.27)
						(thickness 0.15)
					)
					(justify left bottom)
					(hide yes)
				)
			)
			(property "Description" "Heat Sink BGA Aluminum Top Mount"
				(at 0 0 0)
				(effects
					(font
						(size 1.27 1.27)
					)
					(hide yes)
				)
			)
			(property "MPN" "960-27-12-D-AB-0"
				(at 17.78 -5.08 0)
				(effects
					(font
						(size 1.27 1.27)
						(thickness 0.15)
					)
					(justify left bottom)
				)
			)
			(property "Manufacturer" "Wakefield-Vette"
				(at 17.78 -15.24 0)
				(effects
					(font
						(size 1.27 1.27)
						(thickness 0.15)
					)
					(justify left bottom)
					(hide yes)
				)
			)
			(property "Author" "Antmicro"
				(at 17.78 -17.78 0)
				(effects
					(font
						(size 1.27 1.27)
						(thickness 0.15)
					)
					(justify left bottom)
					(hide yes)
				)
			)
			(property "License" "Apache-2.0"
				(at 17.78 -20.32 0)
				(effects
					(font
						(size 1.27 1.27)
						(thickness 0.15)
					)
					(justify left bottom)
					(hide yes)
				)
			)
			(property "ki_keywords" "HEATSINK"
				(at 0 0 0)
				(effects
					(font
						(size 1.27 1.27)
					)
					(hide yes)
				)
			)
			(property "ki_fp_filters" "Heatsink_*"
				(at 0 0 0)
				(effects
					(font
						(size 1.27 1.27)
					)
					(hide yes)
				)
			)
			(symbol "Heatsink_960-27-12-D-AB-0_0_1"
				(polyline
					(pts
						(xy 0 0) (xy 0.635 0) (xy 0.635 -3.175) (xy 1.27 -3.175) (xy 1.27 0) (xy 1.905 0) (xy 1.905 -3.175)
						(xy 2.54 -3.175) (xy 2.54 0) (xy 3.175 0) (xy 3.175 -3.175) (xy 3.81 -3.175) (xy 3.81 0) (xy 4.445 0)
						(xy 4.445 -3.175) (xy 5.08 -3.175) (xy 5.08 0) (xy 5.715 0) (xy 5.715 -4.445) (xy 0 -4.445) (xy 0 0)
					)
					(stroke
						(width 0)
						(type default)
					)
					(fill
						(type background)
					)
				)
			)
		)
	(symbol "antmicroMechanicalParts:Lightpipe_Mentor_1296.2013"
			(exclude_from_sim no)
			(in_bom yes)
			(on_board yes)
			(property "Reference" "H"
				(at 20.32 -2.54 0)
				(effects
					(font
						(size 1.27 1.27)
						(thickness 0.15)
					)
					(justify left bottom)
				)
			)
			(property "Value" "Lightpipe_Mentor_1296.2013"
				(at 20.32 -5.08 0)
				(effects
					(font
						(size 1.27 1.27)
						(thickness 0.15)
					)
					(justify left bottom)
				)
			)
			(property "Footprint" "antmicro-footprints:Mech_Lightpipe_Mentor_1296.2013"
				(at 20.32 -7.62 0)
				(effects
					(font
						(size 1.27 1.27)
						(thickness 0.15)
					)
					(justify left bottom)
					(hide yes)
				)
			)
			(property "Datasheet" "https://docs.rs-online.com/e47b/0900766b813f6efb.pdf"
				(at 20.32 -10.16 0)
				(effects
					(font
						(size 1.27 1.27)
						(thickness 0.15)
					)
					(justify left bottom)
					(hide yes)
				)
			)
			(property "Description" "Light Pipe, Miniature Triple Line, 14.45 mm, 3 Pipes, Circular, PC Board, Transparent"
				(at 0 0 0)
				(effects
					(font
						(size 1.27 1.27)
					)
					(hide yes)
				)
			)
			(property "Manufacturer" "Mentor Worldwide"
				(at 20.32 -12.7 0)
				(effects
					(font
						(size 1.27 1.27)
						(thickness 0.15)
					)
					(justify left bottom)
					(hide yes)
				)
			)
			(property "MPN" "1296.2013"
				(at 20.32 -15.24 0)
				(effects
					(font
						(size 1.27 1.27)
						(thickness 0.15)
					)
					(justify left bottom)
					(hide yes)
				)
			)
			(property "Author" "Antmicro"
				(at 20.32 -17.78 0)
				(effects
					(font
						(size 1.27 1.27)
						(thickness 0.15)
					)
					(justify left bottom)
					(hide yes)
				)
			)
			(property "License" "Apache-2.0"
				(at 20.32 -20.32 0)
				(effects
					(font
						(size 1.27 1.27)
						(thickness 0.15)
					)
					(justify left bottom)
					(hide yes)
				)
			)
			(property "ki_keywords" "HORIZONTAL, THT, MECHANICAL, MODULE"
				(at 0 0 0)
				(effects
					(font
						(size 1.27 1.27)
					)
					(hide yes)
				)
			)
			(symbol "Lightpipe_Mentor_1296.2013_1_1"
				(rectangle
					(start 5.08 -2.54)
					(end -5.08 3.81)
					(stroke
						(width 0.254)
						(type default)
					)
					(fill
						(type background)
					)
				)
				(text "Horizontal"
					(at -5.08 1.524 0)
					(effects
						(font
							(size 1.27 1.27)
							(thickness 0.15)
						)
						(justify left bottom)
					)
				)
				(text "lightguide"
					(at -4.826 -0.508 0)
					(effects
						(font
							(size 1.27 1.27)
							(thickness 0.15)
						)
						(justify left bottom)
					)
				)
				(text "1x3"
					(at -1.905 -2.54 0)
					(effects
						(font
							(size 1.27 1.27)
							(thickness 0.15)
						)
						(justify left bottom)
					)
				)
			)
		)
	(symbol "antmicroMemory:AT24CS01_SOT23"
			(exclude_from_sim no)
			(in_bom yes)
			(on_board yes)
			(property "Reference" "U"
				(at 35.56 -2.54 0)
				(effects
					(font
						(size 1.27 1.27)
						(thickness 0.15)
					)
					(justify left bottom)
				)
			)
			(property "Value" "AT24CS01_SOT23"
				(at 35.56 -5.08 0)
				(effects
					(font
						(size 1.27 1.27)
						(thickness 0.15)
					)
					(justify left bottom)
					(hide yes)
				)
			)
			(property "Footprint" "antmicro-footprints:SOT-23-5"
				(at 35.56 -7.62 0)
				(effects
					(font
						(size 1.27 1.27)
						(thickness 0.15)
					)
					(justify left bottom)
					(hide yes)
				)
			)
			(property "Datasheet" "http://ww1.microchip.com/downloads/en/devicedoc/Atmel-8815-SEEPROM-AT24CS01-02-Datasheet.pdf"
				(at 35.56 -10.16 0)
				(effects
					(font
						(size 1.27 1.27)
						(thickness 0.15)
					)
					(justify left bottom)
					(hide yes)
				)
			)
			(property "Description" "EEPROM Memory IC 1Kbit I²C 1 MHz 550 ns SOT-23-5"
				(at 35.56 -22.86 0)
				(effects
					(font
						(size 1.27 1.27)
					)
					(justify left bottom)
					(hide yes)
				)
			)
			(property "Manufacturer" "Atmel"
				(at 35.56 -12.7 0)
				(effects
					(font
						(size 1.27 1.27)
						(thickness 0.15)
					)
					(justify left bottom)
					(hide yes)
				)
			)
			(property "MPN" "AT24CS01-ST"
				(at 35.56 -15.24 0)
				(effects
					(font
						(size 1.27 1.27)
						(thickness 0.15)
					)
					(justify left bottom)
				)
			)
			(property "Author" "Antmicro"
				(at 35.56 -17.78 0)
				(effects
					(font
						(size 1.27 1.27)
						(thickness 0.15)
					)
					(justify left bottom)
					(hide yes)
				)
			)
			(property "License" "Apache-2.0"
				(at 35.56 -20.32 0)
				(effects
					(font
						(size 1.27 1.27)
						(thickness 0.15)
					)
					(justify left bottom)
					(hide yes)
				)
			)
			(property "ki_keywords" "IC"
				(at 0 0 0)
				(effects
					(font
						(size 1.27 1.27)
					)
					(hide yes)
				)
			)
			(symbol "AT24CS01_SOT23_1_1"
				(rectangle
					(start 2.54 -7.62)
					(end 17.78 2.54)
					(stroke
						(width 0.254)
						(type default)
					)
					(fill
						(type background)
					)
				)
				(pin passive line
					(at 0 0 0)
					(length 2.54)
					(name "SDA"
						(effects
							(font
								(size 1.27 1.27)
							)
						)
					)
					(number "3"
						(effects
							(font
								(size 1.27 1.27)
							)
						)
					)
				)
				(pin passive line
					(at 0 -2.54 0)
					(length 2.54)
					(name "SCL"
						(effects
							(font
								(size 1.27 1.27)
							)
						)
					)
					(number "1"
						(effects
							(font
								(size 1.27 1.27)
							)
						)
					)
				)
				(pin passive line
					(at 0 -5.08 0)
					(length 2.54)
					(name "WP"
						(effects
							(font
								(size 1.27 1.27)
							)
						)
					)
					(number "5"
						(effects
							(font
								(size 1.27 1.27)
							)
						)
					)
				)
				(pin passive line
					(at 20.32 0 180)
					(length 2.54)
					(name "VCC"
						(effects
							(font
								(size 1.27 1.27)
							)
						)
					)
					(number "4"
						(effects
							(font
								(size 1.27 1.27)
							)
						)
					)
				)
				(pin passive line
					(at 20.32 -2.54 180)
					(length 2.54)
					(name "GND"
						(effects
							(font
								(size 1.27 1.27)
							)
						)
					)
					(number "2"
						(effects
							(font
								(size 1.27 1.27)
							)
						)
					)
				)
			)
		)
	(symbol "antmicroMemory:IS66WVH16M8DBLL-100B1LI"
			(exclude_from_sim no)
			(in_bom yes)
			(on_board yes)
			(property "Reference" "U"
				(at 45.72 -5.08 0)
				(effects
					(font
						(size 1.27 1.27)
						(thickness 0.15)
					)
					(justify left bottom)
				)
			)
			(property "Value" "IS66WVH16M8DBLL-100B1LI"
				(at 45.72 -10.16 0)
				(effects
					(font
						(size 1.27 1.27)
						(thickness 0.15)
					)
					(justify left bottom)
					(hide yes)
				)
			)
			(property "Footprint" "antmicro-footprints:FBGA-25-24_6x8mm_Layout5x5_P1mm"
				(at 45.72 -12.7 0)
				(effects
					(font
						(size 1.27 1.27)
						(thickness 0.15)
					)
					(justify left bottom)
					(hide yes)
				)
			)
			(property "Datasheet" "https://eu.mouser.com/datasheet/2/198/issi_s_a0011529618_1-2271553.pdf"
				(at 45.72 -15.24 0)
				(effects
					(font
						(size 1.27 1.27)
						(thickness 0.15)
					)
					(justify left bottom)
					(hide yes)
				)
			)
			(property "Description" "DRAM 128Mb, HyperRAM, 16Mbx8, 3.0V, 100MHz, 24-ball TFBGA, RoHS"
				(at 0 0 0)
				(effects
					(font
						(size 1.27 1.27)
					)
					(hide yes)
				)
			)
			(property "Manufacturer" "ISSI"
				(at 45.72 -17.78 0)
				(effects
					(font
						(size 1.27 1.27)
						(thickness 0.15)
					)
					(justify left bottom)
					(hide yes)
				)
			)
			(property "MPN" "IS66WVH16M8DBLL-100B1LI"
				(at 45.72 -7.62 0)
				(effects
					(font
						(size 1.27 1.27)
						(thickness 0.15)
					)
					(justify left bottom)
				)
			)
			(property "Author" "Antmicro"
				(at 45.72 -20.32 0)
				(effects
					(font
						(size 1.27 1.27)
						(thickness 0.15)
					)
					(justify left bottom)
					(hide yes)
				)
			)
			(property "License" "Apache-2.0"
				(at 45.72 -22.86 0)
				(effects
					(font
						(size 1.27 1.27)
						(thickness 0.15)
					)
					(justify left bottom)
					(hide yes)
				)
			)
			(property "ki_keywords" "SMT, MEMORY, IC, DRAM, HYPERBUS, HYPERRAM"
				(at 0 0 0)
				(effects
					(font
						(size 1.27 1.27)
					)
					(hide yes)
				)
			)
			(symbol "IS66WVH16M8DBLL-100B1LI_1_1"
				(rectangle
					(start 2.54 2.54)
					(end 27.94 -40.64)
					(stroke
						(width 0.254)
						(type default)
					)
					(fill
						(type background)
					)
				)
				(rectangle
					(start 7.62 -1.27)
					(end 7.62 -1.27)
					(stroke
						(width 0.254)
						(type default)
					)
					(fill
						(type background)
					)
				)
				(rectangle
					(start 11.43 -38.1)
					(end 11.43 -38.1)
					(stroke
						(width 0.254)
						(type default)
					)
					(fill
						(type background)
					)
				)
				(pin input line
					(at 0 0 0)
					(length 2.54)
					(name "~{RESET}"
						(effects
							(font
								(size 1.27 1.27)
							)
						)
					)
					(number "A4"
						(effects
							(font
								(size 1.27 1.27)
							)
						)
					)
				)
				(pin input line
					(at 0 -2.54 0)
					(length 2.54)
					(name "~{CS}"
						(effects
							(font
								(size 1.27 1.27)
							)
						)
					)
					(number "A3"
						(effects
							(font
								(size 1.27 1.27)
							)
						)
					)
				)
				(pin input line
					(at 0 -7.62 0)
					(length 2.54)
					(name "CK+"
						(effects
							(font
								(size 1.27 1.27)
							)
						)
					)
					(number "B2"
						(effects
							(font
								(size 1.27 1.27)
							)
						)
					)
				)
				(pin input line
					(at 0 -10.16 0)
					(length 2.54)
					(name "CK-"
						(effects
							(font
								(size 1.27 1.27)
							)
						)
					)
					(number "B1"
						(effects
							(font
								(size 1.27 1.27)
							)
						)
					)
				)
				(pin bidirectional line
					(at 0 -15.24 0)
					(length 2.54)
					(name "DQ0"
						(effects
							(font
								(size 1.27 1.27)
							)
						)
					)
					(number "D3"
						(effects
							(font
								(size 1.27 1.27)
							)
						)
					)
				)
				(pin bidirectional line
					(at 0 -17.78 0)
					(length 2.54)
					(name "DQ1"
						(effects
							(font
								(size 1.27 1.27)
							)
						)
					)
					(number "D2"
						(effects
							(font
								(size 1.27 1.27)
							)
						)
					)
				)
				(pin bidirectional line
					(at 0 -20.32 0)
					(length 2.54)
					(name "DQ2"
						(effects
							(font
								(size 1.27 1.27)
							)
						)
					)
					(number "C4"
						(effects
							(font
								(size 1.27 1.27)
							)
						)
					)
				)
				(pin bidirectional line
					(at 0 -22.86 0)
					(length 2.54)
					(name "DQ3"
						(effects
							(font
								(size 1.27 1.27)
							)
						)
					)
					(number "D4"
						(effects
							(font
								(size 1.27 1.27)
							)
						)
					)
				)
				(pin bidirectional line
					(at 0 -25.4 0)
					(length 2.54)
					(name "DQ4"
						(effects
							(font
								(size 1.27 1.27)
							)
						)
					)
					(number "D5"
						(effects
							(font
								(size 1.27 1.27)
							)
						)
					)
				)
				(pin bidirectional line
					(at 0 -27.94 0)
					(length 2.54)
					(name "DQ5"
						(effects
							(font
								(size 1.27 1.27)
							)
						)
					)
					(number "E3"
						(effects
							(font
								(size 1.27 1.27)
							)
						)
					)
				)
				(pin bidirectional line
					(at 0 -30.48 0)
					(length 2.54)
					(name "DQ6"
						(effects
							(font
								(size 1.27 1.27)
							)
						)
					)
					(number "E2"
						(effects
							(font
								(size 1.27 1.27)
							)
						)
					)
				)
				(pin bidirectional line
					(at 0 -33.02 0)
					(length 2.54)
					(name "DQ7"
						(effects
							(font
								(size 1.27 1.27)
							)
						)
					)
					(number "E1"
						(effects
							(font
								(size 1.27 1.27)
							)
						)
					)
				)
				(pin bidirectional line
					(at 0 -38.1 0)
					(length 2.54)
					(name "RWDS"
						(effects
							(font
								(size 1.27 1.27)
							)
						)
					)
					(number "C3"
						(effects
							(font
								(size 1.27 1.27)
							)
						)
					)
				)
				(pin no_connect line
					(at 27.94 -26.67 180)
					(length 2.54)
					(hide yes)
					(name "NC"
						(effects
							(font
								(size 1.27 1.27)
							)
						)
					)
					(number "B5"
						(effects
							(font
								(size 1.27 1.27)
							)
						)
					)
				)
				(pin no_connect line
					(at 27.94 -27.94 180)
					(length 2.54)
					(hide yes)
					(name "NC"
						(effects
							(font
								(size 1.27 1.27)
							)
						)
					)
					(number "A5"
						(effects
							(font
								(size 1.27 1.27)
							)
						)
					)
				)
				(pin no_connect line
					(at 27.94 -29.21 180)
					(length 2.54)
					(hide yes)
					(name "NC"
						(effects
							(font
								(size 1.27 1.27)
							)
						)
					)
					(number "A2"
						(effects
							(font
								(size 1.27 1.27)
							)
						)
					)
				)
				(pin no_connect line
					(at 27.94 -30.48 180)
					(length 2.54)
					(hide yes)
					(name "NC"
						(effects
							(font
								(size 1.27 1.27)
							)
						)
					)
					(number "C5"
						(effects
							(font
								(size 1.27 1.27)
							)
						)
					)
				)
				(pin no_connect line
					(at 27.94 -31.75 180)
					(length 2.54)
					(hide yes)
					(name "NC"
						(effects
							(font
								(size 1.27 1.27)
							)
						)
					)
					(number "C2"
						(effects
							(font
								(size 1.27 1.27)
							)
						)
					)
				)
				(pin power_in line
					(at 30.48 0 180)
					(length 2.54)
					(name "VCC"
						(effects
							(font
								(size 1.27 1.27)
							)
						)
					)
					(number "B4"
						(effects
							(font
								(size 1.27 1.27)
							)
						)
					)
				)
				(pin power_in line
					(at 30.48 -2.54 180)
					(length 2.54)
					(name "VCCQ"
						(effects
							(font
								(size 1.27 1.27)
							)
						)
					)
					(number "D1"
						(effects
							(font
								(size 1.27 1.27)
							)
						)
					)
				)
				(pin passive line
					(at 30.48 -2.54 180)
					(length 2.54)
					(hide yes)
					(name "VCCQ"
						(effects
							(font
								(size 1.27 1.27)
							)
						)
					)
					(number "E4"
						(effects
							(font
								(size 1.27 1.27)
							)
						)
					)
				)
				(pin power_in line
					(at 30.48 -35.56 180)
					(length 2.54)
					(name "VSSQ"
						(effects
							(font
								(size 1.27 1.27)
							)
						)
					)
					(number "C1"
						(effects
							(font
								(size 1.27 1.27)
							)
						)
					)
				)
				(pin passive line
					(at 30.48 -35.56 180)
					(length 2.54)
					(hide yes)
					(name "VSSQ"
						(effects
							(font
								(size 1.27 1.27)
							)
						)
					)
					(number "E5"
						(effects
							(font
								(size 1.27 1.27)
							)
						)
					)
				)
				(pin power_in line
					(at 30.48 -38.1 180)
					(length 2.54)
					(name "VSS"
						(effects
							(font
								(size 1.27 1.27)
							)
						)
					)
					(number "B3"
						(effects
							(font
								(size 1.27 1.27)
							)
						)
					)
				)
			)
		)
	(symbol "antmicroMemory:S25FL128SAGNFI000"
			(exclude_from_sim no)
			(in_bom yes)
			(on_board yes)
			(property "Reference" "U"
				(at 45.72 -2.54 0)
				(effects
					(font
						(size 1.27 1.27)
						(thickness 0.15)
					)
					(justify left bottom)
				)
			)
			(property "Value" "S25FL128SAGNFI000"
				(at 45.72 -5.08 0)
				(effects
					(font
						(size 1.27 1.27)
						(thickness 0.15)
					)
					(justify left bottom)
				)
			)
			(property "Footprint" "antmicro-footprints:WSON-8_6x8x0.5mm_P1.27mm"
				(at 45.72 -7.62 0)
				(effects
					(font
						(size 1.27 1.27)
						(thickness 0.15)
					)
					(justify left bottom)
					(hide yes)
				)
			)
			(property "Datasheet" "https://www.farnell.com/datasheets/2309615.pdf"
				(at 45.72 -10.16 0)
				(effects
					(font
						(size 1.27 1.27)
						(thickness 0.15)
					)
					(justify left bottom)
					(hide yes)
				)
			)
			(property "Description" "Flash Memory, MirrorBit Eclipse Architecture, Serial NOR, 128 Mbit, 16M x 8bit, SPI, WSON, 8 Pins"
				(at 0 0 0)
				(effects
					(font
						(size 1.27 1.27)
					)
					(hide yes)
				)
			)
			(property "MPN" "S25FL128SAGNFI000"
				(at 45.72 -15.24 0)
				(effects
					(font
						(size 1.27 1.27)
						(thickness 0.15)
					)
					(justify left bottom)
					(hide yes)
				)
			)
			(property "Manufacturer" "Cypress Semiconductor"
				(at 45.72 -12.7 0)
				(effects
					(font
						(size 1.27 1.27)
						(thickness 0.15)
					)
					(justify left bottom)
					(hide yes)
				)
			)
			(property "Author" "Antmicro"
				(at 45.72 -17.78 0)
				(effects
					(font
						(size 1.27 1.27)
						(thickness 0.15)
					)
					(justify left bottom)
					(hide yes)
				)
			)
			(property "License" "Apache-2.0"
				(at 45.72 -20.32 0)
				(effects
					(font
						(size 1.27 1.27)
						(thickness 0.15)
					)
					(justify left bottom)
					(hide yes)
				)
			)
			(property "ki_keywords" "SMT, MEMORY, IC, FLASH, SPI"
				(at 0 0 0)
				(effects
					(font
						(size 1.27 1.27)
					)
					(hide yes)
				)
			)
			(symbol "S25FL128SAGNFI000_1_1"
				(rectangle
					(start 2.54 0)
					(end 17.78 -17.78)
					(stroke
						(width 0.254)
						(type default)
					)
					(fill
						(type background)
					)
				)
				(pin bidirectional line
					(at 0 -2.54 0)
					(length 2.54)
					(name "SI/IO0"
						(effects
							(font
								(size 1.27 1.27)
							)
						)
					)
					(number "5"
						(effects
							(font
								(size 1.27 1.27)
							)
						)
					)
				)
				(pin bidirectional line
					(at 0 -5.08 0)
					(length 2.54)
					(name "SO/IO1"
						(effects
							(font
								(size 1.27 1.27)
							)
						)
					)
					(number "2"
						(effects
							(font
								(size 1.27 1.27)
							)
						)
					)
				)
				(pin bidirectional line
					(at 0 -7.62 0)
					(length 2.54)
					(name "~{WP}/IO2"
						(effects
							(font
								(size 1.27 1.27)
							)
						)
					)
					(number "3"
						(effects
							(font
								(size 1.27 1.27)
							)
						)
					)
				)
				(pin bidirectional line
					(at 0 -10.16 0)
					(length 2.54)
					(name "~{HOLD}/IO3"
						(effects
							(font
								(size 1.27 1.27)
							)
						)
					)
					(number "7"
						(effects
							(font
								(size 1.27 1.27)
							)
						)
					)
				)
				(pin input line
					(at 0 -12.7 0)
					(length 2.54)
					(name "SCK"
						(effects
							(font
								(size 1.27 1.27)
							)
						)
					)
					(number "6"
						(effects
							(font
								(size 1.27 1.27)
							)
						)
					)
				)
				(pin input line
					(at 0 -15.24 0)
					(length 2.54)
					(name "~{CS}"
						(effects
							(font
								(size 1.27 1.27)
							)
						)
					)
					(number "1"
						(effects
							(font
								(size 1.27 1.27)
							)
						)
					)
				)
				(pin no_connect line
					(at 17.78 -12.7 180)
					(length 2.54)
					(hide yes)
					(name "EP"
						(effects
							(font
								(size 1.27 1.27)
							)
						)
					)
					(number "9"
						(effects
							(font
								(size 1.27 1.27)
							)
						)
					)
				)
				(pin power_in line
					(at 20.32 -2.54 180)
					(length 2.54)
					(name "V_{CC}"
						(effects
							(font
								(size 1.27 1.27)
							)
						)
					)
					(number "8"
						(effects
							(font
								(size 1.27 1.27)
							)
						)
					)
				)
				(pin power_in line
					(at 20.32 -15.24 180)
					(length 2.54)
					(name "V_{SS}"
						(effects
							(font
								(size 1.27 1.27)
							)
						)
					)
					(number "4"
						(effects
							(font
								(size 1.27 1.27)
							)
						)
					)
				)
			)
		)
	(symbol "antmicroMemoryConnectorsPCCardSockets:Bus_DDR5_SODIMM_Amphenol_10161033-002RHLF_CUSTOM_2xDetectPin"
			(exclude_from_sim no)
			(in_bom yes)
			(on_board yes)
			(property "Reference" "J"
				(at 50.8 0 0)
				(effects
					(font
						(size 1.27 1.27)
						(thickness 0.15)
					)
					(justify left bottom)
				)
			)
			(property "Value" "Bus_DDR5_SODIMM_Amphenol_10161033-002RHLF_CUSTOM_2xDetectPin"
				(at 50.8 -7.62 0)
				(effects
					(font
						(size 1.27 1.27)
						(thickness 0.15)
					)
					(justify left bottom)
					(hide yes)
				)
			)
			(property "Footprint" "antmicro-footprints:Bus_DDR5_SODIMM_Amphenol_10161033-002RHLF"
				(at 50.8 -10.16 0)
				(effects
					(font
						(size 1.27 1.27)
						(thickness 0.15)
					)
					(justify left bottom)
					(hide yes)
				)
			)
			(property "Datasheet" "https://cdn.amphenol-cs.com/media/wysiwyg/files/documentation/datasheet/ssio/ssio_ddr5_sodimm.pdf"
				(at 50.8 -12.7 0)
				(effects
					(font
						(size 1.27 1.27)
						(thickness 0.15)
					)
					(justify left bottom)
					(hide yes)
				)
			)
			(property "Description" "DDR5 SODIMM connector, Right Angle, Surface Mount, 262 Position, 0.5mm Pitch, 5,2mm Height"
				(at 0 0 0)
				(effects
					(font
						(size 1.27 1.27)
					)
					(hide yes)
				)
			)
			(property "MPN" "10161033-002RHLF"
				(at 50.8 -2.54 0)
				(effects
					(font
						(size 1.27 1.27)
						(thickness 0.15)
					)
					(justify left bottom)
				)
			)
			(property "Manufacturer" "Amphenol"
				(at 50.8 -15.24 0)
				(effects
					(font
						(size 1.27 1.27)
						(thickness 0.15)
					)
					(justify left bottom)
					(hide yes)
				)
			)
			(property "Author" "Antmicro"
				(at 50.8 -17.78 0)
				(effects
					(font
						(size 1.27 1.27)
						(thickness 0.15)
					)
					(justify left bottom)
					(hide yes)
				)
			)
			(property "License" "Apache-2.0"
				(at 50.8 -20.32 0)
				(effects
					(font
						(size 1.27 1.27)
						(thickness 0.15)
					)
					(justify left bottom)
					(hide yes)
				)
			)
			(property "ki_locked" ""
				(at 0 0 0)
				(effects
					(font
						(size 1.27 1.27)
					)
				)
			)
			(property "ki_keywords" "SMT, CONNECTOR, DDR"
				(at 0 0 0)
				(effects
					(font
						(size 1.27 1.27)
					)
					(hide yes)
				)
			)
			(symbol "Bus_DDR5_SODIMM_Amphenol_10161033-002RHLF_CUSTOM_2xDetectPin_1_1"
				(rectangle
					(start 3.81 2.54)
					(end 31.75 -130.81)
					(stroke
						(width 0.254)
						(type default)
					)
					(fill
						(type background)
					)
				)
				(polyline
					(pts
						(xy 11.43 -57.15) (xy 15.24 -57.15) (xy 15.24 -77.47) (xy 11.43 -77.47)
					)
					(stroke
						(width 0.254)
						(type default)
					)
					(fill
						(type background)
					)
				)
				(polyline
					(pts
						(xy 20.32 1.27) (xy 20.32 -29.21)
					)
					(stroke
						(width 0.254)
						(type default)
					)
					(fill
						(type background)
					)
				)
				(polyline
					(pts
						(xy 20.32 -31.75) (xy 20.32 -62.23)
					)
					(stroke
						(width 0.254)
						(type default)
					)
					(fill
						(type background)
					)
				)
				(polyline
					(pts
						(xy 20.32 -64.77) (xy 20.32 -95.25)
					)
					(stroke
						(width 0.254)
						(type default)
					)
					(fill
						(type background)
					)
				)
				(polyline
					(pts
						(xy 20.32 -97.79) (xy 20.32 -128.27)
					)
					(stroke
						(width 0.254)
						(type default)
					)
					(fill
						(type background)
					)
				)
				(text "ECC"
					(at 17.78 -69.85 900)
					(effects
						(font
							(size 1.27 1.27)
							(thickness 0.15)
						)
						(justify left bottom)
					)
				)
				(pin passive line
					(at 0 0 0)
					(length 3.81)
					(name "CS0_A_n"
						(effects
							(font
								(size 1.27 1.27)
							)
						)
					)
					(number "106"
						(effects
							(font
								(size 1.27 1.27)
							)
						)
					)
				)
				(pin passive line
					(at 0 -2.54 0)
					(length 3.81)
					(name "CS1_A_n"
						(effects
							(font
								(size 1.27 1.27)
							)
						)
					)
					(number "110"
						(effects
							(font
								(size 1.27 1.27)
							)
						)
					)
				)
				(pin passive line
					(at 0 -6.35 0)
					(length 3.81)
					(name "CK0_A_t"
						(effects
							(font
								(size 1.27 1.27)
							)
						)
					)
					(number "131"
						(effects
							(font
								(size 1.27 1.27)
							)
						)
					)
				)
				(pin passive line
					(at 0 -8.89 0)
					(length 3.81)
					(name "CK0_A_c"
						(effects
							(font
								(size 1.27 1.27)
							)
						)
					)
					(number "133"
						(effects
							(font
								(size 1.27 1.27)
							)
						)
					)
				)
				(pin passive line
					(at 0 -13.97 0)
					(length 3.81)
					(name "CK1_A_t"
						(effects
							(font
								(size 1.27 1.27)
							)
						)
					)
					(number "132"
						(effects
							(font
								(size 1.27 1.27)
							)
						)
					)
				)
				(pin passive line
					(at 0 -16.51 0)
					(length 3.81)
					(name "CK1_A_c"
						(effects
							(font
								(size 1.27 1.27)
							)
						)
					)
					(number "134"
						(effects
							(font
								(size 1.27 1.27)
							)
						)
					)
				)
				(pin passive line
					(at 0 -21.59 0)
					(length 3.81)
					(name "CA0_A"
						(effects
							(font
								(size 1.27 1.27)
							)
						)
					)
					(number "107"
						(effects
							(font
								(size 1.27 1.27)
							)
						)
					)
				)
				(pin passive line
					(at 0 -24.13 0)
					(length 3.81)
					(name "CA1_A"
						(effects
							(font
								(size 1.27 1.27)
							)
						)
					)
					(number "109"
						(effects
							(font
								(size 1.27 1.27)
							)
						)
					)
				)
				(pin passive line
					(at 0 -26.67 0)
					(length 3.81)
					(name "CA2_A"
						(effects
							(font
								(size 1.27 1.27)
							)
						)
					)
					(number "113"
						(effects
							(font
								(size 1.27 1.27)
							)
						)
					)
				)
				(pin passive line
					(at 0 -29.21 0)
					(length 3.81)
					(name "CA3_A"
						(effects
							(font
								(size 1.27 1.27)
							)
						)
					)
					(number "114"
						(effects
							(font
								(size 1.27 1.27)
							)
						)
					)
				)
				(pin passive line
					(at 0 -31.75 0)
					(length 3.81)
					(name "CA4_A"
						(effects
							(font
								(size 1.27 1.27)
							)
						)
					)
					(number "115"
						(effects
							(font
								(size 1.27 1.27)
							)
						)
					)
				)
				(pin passive line
					(at 0 -34.29 0)
					(length 3.81)
					(name "CA5_A"
						(effects
							(font
								(size 1.27 1.27)
							)
						)
					)
					(number "116"
						(effects
							(font
								(size 1.27 1.27)
							)
						)
					)
				)
				(pin passive line
					(at 0 -36.83 0)
					(length 3.81)
					(name "CA6_A"
						(effects
							(font
								(size 1.27 1.27)
							)
						)
					)
					(number "119"
						(effects
							(font
								(size 1.27 1.27)
							)
						)
					)
				)
				(pin passive line
					(at 0 -39.37 0)
					(length 3.81)
					(name "CA7_A"
						(effects
							(font
								(size 1.27 1.27)
							)
						)
					)
					(number "120"
						(effects
							(font
								(size 1.27 1.27)
							)
						)
					)
				)
				(pin passive line
					(at 0 -41.91 0)
					(length 3.81)
					(name "CA8_A"
						(effects
							(font
								(size 1.27 1.27)
							)
						)
					)
					(number "121"
						(effects
							(font
								(size 1.27 1.27)
							)
						)
					)
				)
				(pin passive line
					(at 0 -44.45 0)
					(length 3.81)
					(name "CA9_A"
						(effects
							(font
								(size 1.27 1.27)
							)
						)
					)
					(number "122"
						(effects
							(font
								(size 1.27 1.27)
							)
						)
					)
				)
				(pin passive line
					(at 0 -46.99 0)
					(length 3.81)
					(name "CA10_A"
						(effects
							(font
								(size 1.27 1.27)
							)
						)
					)
					(number "125"
						(effects
							(font
								(size 1.27 1.27)
							)
						)
					)
				)
				(pin passive line
					(at 0 -49.53 0)
					(length 3.81)
					(name "CA11_A"
						(effects
							(font
								(size 1.27 1.27)
							)
						)
					)
					(number "126"
						(effects
							(font
								(size 1.27 1.27)
							)
						)
					)
				)
				(pin passive line
					(at 0 -52.07 0)
					(length 3.81)
					(name "CA12_A"
						(effects
							(font
								(size 1.27 1.27)
							)
						)
					)
					(number "127"
						(effects
							(font
								(size 1.27 1.27)
							)
						)
					)
				)
				(pin passive line
					(at 0 -59.69 0)
					(length 3.81)
					(name "DQS4_A_t"
						(effects
							(font
								(size 1.27 1.27)
							)
						)
					)
					(number "102"
						(effects
							(font
								(size 1.27 1.27)
							)
						)
					)
				)
				(pin passive line
					(at 0 -62.23 0)
					(length 3.81)
					(name "DQS4_A_c"
						(effects
							(font
								(size 1.27 1.27)
							)
						)
					)
					(number "100"
						(effects
							(font
								(size 1.27 1.27)
							)
						)
					)
				)
				(pin passive line
					(at 0 -67.31 0)
					(length 3.81)
					(name "CB0_A"
						(effects
							(font
								(size 1.27 1.27)
							)
						)
					)
					(number "95"
						(effects
							(font
								(size 1.27 1.27)
							)
						)
					)
				)
				(pin passive line
					(at 0 -69.85 0)
					(length 3.81)
					(name "CB1_A"
						(effects
							(font
								(size 1.27 1.27)
							)
						)
					)
					(number "96"
						(effects
							(font
								(size 1.27 1.27)
							)
						)
					)
				)
				(pin passive line
					(at 0 -72.39 0)
					(length 3.81)
					(name "CB2_A"
						(effects
							(font
								(size 1.27 1.27)
							)
						)
					)
					(number "99"
						(effects
							(font
								(size 1.27 1.27)
							)
						)
					)
				)
				(pin passive line
					(at 0 -74.93 0)
					(length 3.81)
					(name "CB3_A"
						(effects
							(font
								(size 1.27 1.27)
							)
						)
					)
					(number "103"
						(effects
							(font
								(size 1.27 1.27)
							)
						)
					)
				)
				(pin passive line
					(at 35.56 0 180)
					(length 3.81)
					(name "DQS0_A_t"
						(effects
							(font
								(size 1.27 1.27)
							)
						)
					)
					(number "22"
						(effects
							(font
								(size 1.27 1.27)
							)
						)
					)
				)
				(pin passive line
					(at 35.56 -2.54 180)
					(length 3.81)
					(name "DQS0_A_C"
						(effects
							(font
								(size 1.27 1.27)
							)
						)
					)
					(number "20"
						(effects
							(font
								(size 1.27 1.27)
							)
						)
					)
				)
				(pin passive line
					(at 35.56 -6.35 180)
					(length 3.81)
					(name "DQ0_A"
						(effects
							(font
								(size 1.27 1.27)
							)
						)
					)
					(number "11"
						(effects
							(font
								(size 1.27 1.27)
							)
						)
					)
				)
				(pin passive line
					(at 35.56 -8.89 180)
					(length 3.81)
					(name "DQ1_A"
						(effects
							(font
								(size 1.27 1.27)
							)
						)
					)
					(number "12"
						(effects
							(font
								(size 1.27 1.27)
							)
						)
					)
				)
				(pin passive line
					(at 35.56 -11.43 180)
					(length 3.81)
					(name "DQ2_A"
						(effects
							(font
								(size 1.27 1.27)
							)
						)
					)
					(number "15"
						(effects
							(font
								(size 1.27 1.27)
							)
						)
					)
				)
				(pin passive line
					(at 35.56 -13.97 180)
					(length 3.81)
					(name "DQ3_A"
						(effects
							(font
								(size 1.27 1.27)
							)
						)
					)
					(number "16"
						(effects
							(font
								(size 1.27 1.27)
							)
						)
					)
				)
				(pin passive line
					(at 35.56 -16.51 180)
					(length 3.81)
					(name "DQ4_A"
						(effects
							(font
								(size 1.27 1.27)
							)
						)
					)
					(number "23"
						(effects
							(font
								(size 1.27 1.27)
							)
						)
					)
				)
				(pin passive line
					(at 35.56 -19.05 180)
					(length 3.81)
					(name "DQ5_A"
						(effects
							(font
								(size 1.27 1.27)
							)
						)
					)
					(number "26"
						(effects
							(font
								(size 1.27 1.27)
							)
						)
					)
				)
				(pin passive line
					(at 35.56 -21.59 180)
					(length 3.81)
					(name "DQ6_A"
						(effects
							(font
								(size 1.27 1.27)
							)
						)
					)
					(number "27"
						(effects
							(font
								(size 1.27 1.27)
							)
						)
					)
				)
				(pin passive line
					(at 35.56 -24.13 180)
					(length 3.81)
					(name "DQ7_A"
						(effects
							(font
								(size 1.27 1.27)
							)
						)
					)
					(number "30"
						(effects
							(font
								(size 1.27 1.27)
							)
						)
					)
				)
				(pin passive line
					(at 35.56 -27.94 180)
					(length 3.81)
					(name "DM0_A_n"
						(effects
							(font
								(size 1.27 1.27)
							)
						)
					)
					(number "19"
						(effects
							(font
								(size 1.27 1.27)
							)
						)
					)
				)
				(pin passive line
					(at 35.56 -33.02 180)
					(length 3.81)
					(name "DQS1_A_t"
						(effects
							(font
								(size 1.27 1.27)
							)
						)
					)
					(number "41"
						(effects
							(font
								(size 1.27 1.27)
							)
						)
					)
				)
				(pin passive line
					(at 35.56 -35.56 180)
					(length 3.81)
					(name "DQS1_A_C"
						(effects
							(font
								(size 1.27 1.27)
							)
						)
					)
					(number "39"
						(effects
							(font
								(size 1.27 1.27)
							)
						)
					)
				)
				(pin passive line
					(at 35.56 -39.37 180)
					(length 3.81)
					(name "DQ8_A"
						(effects
							(font
								(size 1.27 1.27)
							)
						)
					)
					(number "31"
						(effects
							(font
								(size 1.27 1.27)
							)
						)
					)
				)
				(pin passive line
					(at 35.56 -41.91 180)
					(length 3.81)
					(name "DQ09_A"
						(effects
							(font
								(size 1.27 1.27)
							)
						)
					)
					(number "34"
						(effects
							(font
								(size 1.27 1.27)
							)
						)
					)
				)
				(pin passive line
					(at 35.56 -44.45 180)
					(length 3.81)
					(name "DQ10_A"
						(effects
							(font
								(size 1.27 1.27)
							)
						)
					)
					(number "35"
						(effects
							(font
								(size 1.27 1.27)
							)
						)
					)
				)
				(pin passive line
					(at 35.56 -46.99 180)
					(length 3.81)
					(name "DQ11_A"
						(effects
							(font
								(size 1.27 1.27)
							)
						)
					)
					(number "38"
						(effects
							(font
								(size 1.27 1.27)
							)
						)
					)
				)
				(pin passive line
					(at 35.56 -49.53 180)
					(length 3.81)
					(name "DQ12_A"
						(effects
							(font
								(size 1.27 1.27)
							)
						)
					)
					(number "45"
						(effects
							(font
								(size 1.27 1.27)
							)
						)
					)
				)
				(pin passive line
					(at 35.56 -52.07 180)
					(length 3.81)
					(name "DQ13_A"
						(effects
							(font
								(size 1.27 1.27)
							)
						)
					)
					(number "46"
						(effects
							(font
								(size 1.27 1.27)
							)
						)
					)
				)
				(pin passive line
					(at 35.56 -54.61 180)
					(length 3.81)
					(name "DQ14_A"
						(effects
							(font
								(size 1.27 1.27)
							)
						)
					)
					(number "49"
						(effects
							(font
								(size 1.27 1.27)
							)
						)
					)
				)
				(pin passive line
					(at 35.56 -57.15 180)
					(length 3.81)
					(name "DQ15_A"
						(effects
							(font
								(size 1.27 1.27)
							)
						)
					)
					(number "50"
						(effects
							(font
								(size 1.27 1.27)
							)
						)
					)
				)
				(pin passive line
					(at 35.56 -60.96 180)
					(length 3.81)
					(name "DM1_A_n"
						(effects
							(font
								(size 1.27 1.27)
							)
						)
					)
					(number "42"
						(effects
							(font
								(size 1.27 1.27)
							)
						)
					)
				)
				(pin passive line
					(at 35.56 -66.04 180)
					(length 3.81)
					(name "DQS2_A_t"
						(effects
							(font
								(size 1.27 1.27)
							)
						)
					)
					(number "64"
						(effects
							(font
								(size 1.27 1.27)
							)
						)
					)
				)
				(pin passive line
					(at 35.56 -68.58 180)
					(length 3.81)
					(name "DQS2_A_C"
						(effects
							(font
								(size 1.27 1.27)
							)
						)
					)
					(number "62"
						(effects
							(font
								(size 1.27 1.27)
							)
						)
					)
				)
				(pin passive line
					(at 35.56 -72.39 180)
					(length 3.81)
					(name "DQ16_A"
						(effects
							(font
								(size 1.27 1.27)
							)
						)
					)
					(number "53"
						(effects
							(font
								(size 1.27 1.27)
							)
						)
					)
				)
				(pin passive line
					(at 35.56 -74.93 180)
					(length 3.81)
					(name "DQ17_A"
						(effects
							(font
								(size 1.27 1.27)
							)
						)
					)
					(number "54"
						(effects
							(font
								(size 1.27 1.27)
							)
						)
					)
				)
				(pin passive line
					(at 35.56 -77.47 180)
					(length 3.81)
					(name "DQ18_A"
						(effects
							(font
								(size 1.27 1.27)
							)
						)
					)
					(number "57"
						(effects
							(font
								(size 1.27 1.27)
							)
						)
					)
				)
				(pin passive line
					(at 35.56 -80.01 180)
					(length 3.81)
					(name "DQ19_A"
						(effects
							(font
								(size 1.27 1.27)
							)
						)
					)
					(number "58"
						(effects
							(font
								(size 1.27 1.27)
							)
						)
					)
				)
				(pin passive line
					(at 35.56 -82.55 180)
					(length 3.81)
					(name "DQ20_A"
						(effects
							(font
								(size 1.27 1.27)
							)
						)
					)
					(number "65"
						(effects
							(font
								(size 1.27 1.27)
							)
						)
					)
				)
				(pin passive line
					(at 35.56 -85.09 180)
					(length 3.81)
					(name "DQ21_A"
						(effects
							(font
								(size 1.27 1.27)
							)
						)
					)
					(number "68"
						(effects
							(font
								(size 1.27 1.27)
							)
						)
					)
				)
				(pin passive line
					(at 35.56 -87.63 180)
					(length 3.81)
					(name "DQ22_A"
						(effects
							(font
								(size 1.27 1.27)
							)
						)
					)
					(number "69"
						(effects
							(font
								(size 1.27 1.27)
							)
						)
					)
				)
				(pin passive line
					(at 35.56 -90.17 180)
					(length 3.81)
					(name "DQ23_A"
						(effects
							(font
								(size 1.27 1.27)
							)
						)
					)
					(number "72"
						(effects
							(font
								(size 1.27 1.27)
							)
						)
					)
				)
				(pin passive line
					(at 35.56 -93.98 180)
					(length 3.81)
					(name "DM2_A_n"
						(effects
							(font
								(size 1.27 1.27)
							)
						)
					)
					(number "61"
						(effects
							(font
								(size 1.27 1.27)
							)
						)
					)
				)
				(pin passive line
					(at 35.56 -99.06 180)
					(length 3.81)
					(name "DQS3_A_t"
						(effects
							(font
								(size 1.27 1.27)
							)
						)
					)
					(number "83"
						(effects
							(font
								(size 1.27 1.27)
							)
						)
					)
				)
				(pin passive line
					(at 35.56 -101.6 180)
					(length 3.81)
					(name "DQS3_A_C"
						(effects
							(font
								(size 1.27 1.27)
							)
						)
					)
					(number "81"
						(effects
							(font
								(size 1.27 1.27)
							)
						)
					)
				)
				(pin passive line
					(at 35.56 -105.41 180)
					(length 3.81)
					(name "DQ24_A"
						(effects
							(font
								(size 1.27 1.27)
							)
						)
					)
					(number "73"
						(effects
							(font
								(size 1.27 1.27)
							)
						)
					)
				)
				(pin passive line
					(at 35.56 -107.95 180)
					(length 3.81)
					(name "DQ25_A"
						(effects
							(font
								(size 1.27 1.27)
							)
						)
					)
					(number "76"
						(effects
							(font
								(size 1.27 1.27)
							)
						)
					)
				)
				(pin passive line
					(at 35.56 -110.49 180)
					(length 3.81)
					(name "DQ26_A"
						(effects
							(font
								(size 1.27 1.27)
							)
						)
					)
					(number "77"
						(effects
							(font
								(size 1.27 1.27)
							)
						)
					)
				)
				(pin passive line
					(at 35.56 -113.03 180)
					(length 3.81)
					(name "DQ27_A"
						(effects
							(font
								(size 1.27 1.27)
							)
						)
					)
					(number "80"
						(effects
							(font
								(size 1.27 1.27)
							)
						)
					)
				)
				(pin passive line
					(at 35.56 -115.57 180)
					(length 3.81)
					(name "DQ28_A"
						(effects
							(font
								(size 1.27 1.27)
							)
						)
					)
					(number "87"
						(effects
							(font
								(size 1.27 1.27)
							)
						)
					)
				)
				(pin passive line
					(at 35.56 -118.11 180)
					(length 3.81)
					(name "DQ29_A"
						(effects
							(font
								(size 1.27 1.27)
							)
						)
					)
					(number "88"
						(effects
							(font
								(size 1.27 1.27)
							)
						)
					)
				)
				(pin passive line
					(at 35.56 -120.65 180)
					(length 3.81)
					(name "DQ30_A"
						(effects
							(font
								(size 1.27 1.27)
							)
						)
					)
					(number "91"
						(effects
							(font
								(size 1.27 1.27)
							)
						)
					)
				)
				(pin passive line
					(at 35.56 -123.19 180)
					(length 3.81)
					(name "DQ31_A"
						(effects
							(font
								(size 1.27 1.27)
							)
						)
					)
					(number "92"
						(effects
							(font
								(size 1.27 1.27)
							)
						)
					)
				)
				(pin passive line
					(at 35.56 -127 180)
					(length 3.81)
					(name "DM3_A_n"
						(effects
							(font
								(size 1.27 1.27)
							)
						)
					)
					(number "84"
						(effects
							(font
								(size 1.27 1.27)
							)
						)
					)
				)
			)
			(symbol "Bus_DDR5_SODIMM_Amphenol_10161033-002RHLF_CUSTOM_2xDetectPin_2_1"
				(rectangle
					(start 3.81 2.54)
					(end 31.75 -130.81)
					(stroke
						(width 0.254)
						(type default)
					)
					(fill
						(type background)
					)
				)
				(polyline
					(pts
						(xy 11.43 -57.15) (xy 15.24 -57.15) (xy 15.24 -77.47) (xy 11.43 -77.47)
					)
					(stroke
						(width 0.254)
						(type default)
					)
					(fill
						(type background)
					)
				)
				(polyline
					(pts
						(xy 20.32 1.27) (xy 20.32 -29.21)
					)
					(stroke
						(width 0.254)
						(type default)
					)
					(fill
						(type background)
					)
				)
				(polyline
					(pts
						(xy 20.32 -31.75) (xy 20.32 -62.23)
					)
					(stroke
						(width 0.254)
						(type default)
					)
					(fill
						(type background)
					)
				)
				(polyline
					(pts
						(xy 20.32 -64.77) (xy 20.32 -95.25)
					)
					(stroke
						(width 0.254)
						(type default)
					)
					(fill
						(type background)
					)
				)
				(polyline
					(pts
						(xy 20.32 -97.79) (xy 20.32 -128.27)
					)
					(stroke
						(width 0.254)
						(type default)
					)
					(fill
						(type background)
					)
				)
				(text "ECC"
					(at 17.78 -69.85 900)
					(effects
						(font
							(size 1.27 1.27)
							(thickness 0.15)
						)
						(justify left bottom)
					)
				)
				(pin passive line
					(at 0 0 0)
					(length 3.81)
					(name "CS0_B_n"
						(effects
							(font
								(size 1.27 1.27)
							)
						)
					)
					(number "161"
						(effects
							(font
								(size 1.27 1.27)
							)
						)
					)
				)
				(pin passive line
					(at 0 -2.54 0)
					(length 3.81)
					(name "CS1_B_N"
						(effects
							(font
								(size 1.27 1.27)
							)
						)
					)
					(number "165"
						(effects
							(font
								(size 1.27 1.27)
							)
						)
					)
				)
				(pin passive line
					(at 0 -6.35 0)
					(length 3.81)
					(name "CK0_B_t"
						(effects
							(font
								(size 1.27 1.27)
							)
						)
					)
					(number "137"
						(effects
							(font
								(size 1.27 1.27)
							)
						)
					)
				)
				(pin passive line
					(at 0 -8.89 0)
					(length 3.81)
					(name "CK0_B_c"
						(effects
							(font
								(size 1.27 1.27)
							)
						)
					)
					(number "139"
						(effects
							(font
								(size 1.27 1.27)
							)
						)
					)
				)
				(pin passive line
					(at 0 -13.97 0)
					(length 3.81)
					(name "CK1_B_t"
						(effects
							(font
								(size 1.27 1.27)
							)
						)
					)
					(number "138"
						(effects
							(font
								(size 1.27 1.27)
							)
						)
					)
				)
				(pin passive line
					(at 0 -16.51 0)
					(length 3.81)
					(name "CK1_B_C"
						(effects
							(font
								(size 1.27 1.27)
							)
						)
					)
					(number "140"
						(effects
							(font
								(size 1.27 1.27)
							)
						)
					)
				)
				(pin passive line
					(at 0 -21.59 0)
					(length 3.81)
					(name "CA0_B"
						(effects
							(font
								(size 1.27 1.27)
							)
						)
					)
					(number "164"
						(effects
							(font
								(size 1.27 1.27)
							)
						)
					)
				)
				(pin passive line
					(at 0 -24.13 0)
					(length 3.81)
					(name "CA1_B"
						(effects
							(font
								(size 1.27 1.27)
							)
						)
					)
					(number "162"
						(effects
							(font
								(size 1.27 1.27)
							)
						)
					)
				)
				(pin passive line
					(at 0 -26.67 0)
					(length 3.81)
					(name "CA2_B"
						(effects
							(font
								(size 1.27 1.27)
							)
						)
					)
					(number "158"
						(effects
							(font
								(size 1.27 1.27)
							)
						)
					)
				)
				(pin passive line
					(at 0 -29.21 0)
					(length 3.81)
					(name "CA3_B"
						(effects
							(font
								(size 1.27 1.27)
							)
						)
					)
					(number "157"
						(effects
							(font
								(size 1.27 1.27)
							)
						)
					)
				)
				(pin passive line
					(at 0 -31.75 0)
					(length 3.81)
					(name "CA4_B"
						(effects
							(font
								(size 1.27 1.27)
							)
						)
					)
					(number "156"
						(effects
							(font
								(size 1.27 1.27)
							)
						)
					)
				)
				(pin passive line
					(at 0 -34.29 0)
					(length 3.81)
					(name "CA5_B"
						(effects
							(font
								(size 1.27 1.27)
							)
						)
					)
					(number "155"
						(effects
							(font
								(size 1.27 1.27)
							)
						)
					)
				)
				(pin passive line
					(at 0 -36.83 0)
					(length 3.81)
					(name "CA6_B"
						(effects
							(font
								(size 1.27 1.27)
							)
						)
					)
					(number "152"
						(effects
							(font
								(size 1.27 1.27)
							)
						)
					)
				)
				(pin passive line
					(at 0 -39.37 0)
					(length 3.81)
					(name "CA7_B"
						(effects
							(font
								(size 1.27 1.27)
							)
						)
					)
					(number "151"
						(effects
							(font
								(size 1.27 1.27)
							)
						)
					)
				)
				(pin passive line
					(at 0 -41.91 0)
					(length 3.81)
					(name "CA8_B"
						(effects
							(font
								(size 1.27 1.27)
							)
						)
					)
					(number "150"
						(effects
							(font
								(size 1.27 1.27)
							)
						)
					)
				)
				(pin passive line
					(at 0 -44.45 0)
					(length 3.81)
					(name "CA9_B"
						(effects
							(font
								(size 1.27 1.27)
							)
						)
					)
					(number "149"
						(effects
							(font
								(size 1.27 1.27)
							)
						)
					)
				)
				(pin passive line
					(at 0 -46.99 0)
					(length 3.81)
					(name "CA10_B"
						(effects
							(font
								(size 1.27 1.27)
							)
						)
					)
					(number "146"
						(effects
							(font
								(size 1.27 1.27)
							)
						)
					)
				)
				(pin passive line
					(at 0 -49.53 0)
					(length 3.81)
					(name "CA11_B"
						(effects
							(font
								(size 1.27 1.27)
							)
						)
					)
					(number "145"
						(effects
							(font
								(size 1.27 1.27)
							)
						)
					)
				)
				(pin passive line
					(at 0 -52.07 0)
					(length 3.81)
					(name "CA12_B"
						(effects
							(font
								(size 1.27 1.27)
							)
						)
					)
					(number "144"
						(effects
							(font
								(size 1.27 1.27)
							)
						)
					)
				)
				(pin passive line
					(at 0 -59.69 0)
					(length 3.81)
					(name "DQS4_B_T"
						(effects
							(font
								(size 1.27 1.27)
							)
						)
					)
					(number "171"
						(effects
							(font
								(size 1.27 1.27)
							)
						)
					)
				)
				(pin passive line
					(at 0 -62.23 0)
					(length 3.81)
					(name "DQS4_B_c"
						(effects
							(font
								(size 1.27 1.27)
							)
						)
					)
					(number "169"
						(effects
							(font
								(size 1.27 1.27)
							)
						)
					)
				)
				(pin passive line
					(at 0 -67.31 0)
					(length 3.81)
					(name "CB0_B"
						(effects
							(font
								(size 1.27 1.27)
							)
						)
					)
					(number "168"
						(effects
							(font
								(size 1.27 1.27)
							)
						)
					)
				)
				(pin passive line
					(at 0 -69.85 0)
					(length 3.81)
					(name "CB1_B"
						(effects
							(font
								(size 1.27 1.27)
							)
						)
					)
					(number "172"
						(effects
							(font
								(size 1.27 1.27)
							)
						)
					)
				)
				(pin passive line
					(at 0 -72.39 0)
					(length 3.81)
					(name "CB2_B"
						(effects
							(font
								(size 1.27 1.27)
							)
						)
					)
					(number "176"
						(effects
							(font
								(size 1.27 1.27)
							)
						)
					)
				)
				(pin passive line
					(at 0 -74.93 0)
					(length 3.81)
					(name "CB3_B"
						(effects
							(font
								(size 1.27 1.27)
							)
						)
					)
					(number "175"
						(effects
							(font
								(size 1.27 1.27)
							)
						)
					)
				)
				(pin passive line
					(at 35.56 0 180)
					(length 3.81)
					(name "DQS0_B_t"
						(effects
							(font
								(size 1.27 1.27)
							)
						)
					)
					(number "190"
						(effects
							(font
								(size 1.27 1.27)
							)
						)
					)
				)
				(pin passive line
					(at 35.56 -2.54 180)
					(length 3.81)
					(name "DQS0_B_C"
						(effects
							(font
								(size 1.27 1.27)
							)
						)
					)
					(number "188"
						(effects
							(font
								(size 1.27 1.27)
							)
						)
					)
				)
				(pin passive line
					(at 35.56 -6.35 180)
					(length 3.81)
					(name "DQ0_B"
						(effects
							(font
								(size 1.27 1.27)
							)
						)
					)
					(number "179"
						(effects
							(font
								(size 1.27 1.27)
							)
						)
					)
				)
				(pin passive line
					(at 35.56 -8.89 180)
					(length 3.81)
					(name "DQ1_B"
						(effects
							(font
								(size 1.27 1.27)
							)
						)
					)
					(number "180"
						(effects
							(font
								(size 1.27 1.27)
							)
						)
					)
				)
				(pin passive line
					(at 35.56 -11.43 180)
					(length 3.81)
					(name "DQ2_B"
						(effects
							(font
								(size 1.27 1.27)
							)
						)
					)
					(number "183"
						(effects
							(font
								(size 1.27 1.27)
							)
						)
					)
				)
				(pin passive line
					(at 35.56 -13.97 180)
					(length 3.81)
					(name "DQ3_B"
						(effects
							(font
								(size 1.27 1.27)
							)
						)
					)
					(number "184"
						(effects
							(font
								(size 1.27 1.27)
							)
						)
					)
				)
				(pin passive line
					(at 35.56 -16.51 180)
					(length 3.81)
					(name "DQ4_B"
						(effects
							(font
								(size 1.27 1.27)
							)
						)
					)
					(number "191"
						(effects
							(font
								(size 1.27 1.27)
							)
						)
					)
				)
				(pin passive line
					(at 35.56 -19.05 180)
					(length 3.81)
					(name "DQ5_B"
						(effects
							(font
								(size 1.27 1.27)
							)
						)
					)
					(number "194"
						(effects
							(font
								(size 1.27 1.27)
							)
						)
					)
				)
				(pin passive line
					(at 35.56 -21.59 180)
					(length 3.81)
					(name "DQ6_B"
						(effects
							(font
								(size 1.27 1.27)
							)
						)
					)
					(number "195"
						(effects
							(font
								(size 1.27 1.27)
							)
						)
					)
				)
				(pin passive line
					(at 35.56 -24.13 180)
					(length 3.81)
					(name "DQ7_B"
						(effects
							(font
								(size 1.27 1.27)
							)
						)
					)
					(number "198"
						(effects
							(font
								(size 1.27 1.27)
							)
						)
					)
				)
				(pin passive line
					(at 35.56 -27.94 180)
					(length 3.81)
					(name "DM0_B_n"
						(effects
							(font
								(size 1.27 1.27)
							)
						)
					)
					(number "187"
						(effects
							(font
								(size 1.27 1.27)
							)
						)
					)
				)
				(pin passive line
					(at 35.56 -33.02 180)
					(length 3.81)
					(name "DQS1_B_t"
						(effects
							(font
								(size 1.27 1.27)
							)
						)
					)
					(number "209"
						(effects
							(font
								(size 1.27 1.27)
							)
						)
					)
				)
				(pin passive line
					(at 35.56 -35.56 180)
					(length 3.81)
					(name "DQS1_B_C"
						(effects
							(font
								(size 1.27 1.27)
							)
						)
					)
					(number "207"
						(effects
							(font
								(size 1.27 1.27)
							)
						)
					)
				)
				(pin passive line
					(at 35.56 -39.37 180)
					(length 3.81)
					(name "DQ8_B"
						(effects
							(font
								(size 1.27 1.27)
							)
						)
					)
					(number "199"
						(effects
							(font
								(size 1.27 1.27)
							)
						)
					)
				)
				(pin passive line
					(at 35.56 -41.91 180)
					(length 3.81)
					(name "DQ9_B"
						(effects
							(font
								(size 1.27 1.27)
							)
						)
					)
					(number "202"
						(effects
							(font
								(size 1.27 1.27)
							)
						)
					)
				)
				(pin passive line
					(at 35.56 -44.45 180)
					(length 3.81)
					(name "DQ10_B"
						(effects
							(font
								(size 1.27 1.27)
							)
						)
					)
					(number "203"
						(effects
							(font
								(size 1.27 1.27)
							)
						)
					)
				)
				(pin passive line
					(at 35.56 -46.99 180)
					(length 3.81)
					(name "DQ11_B"
						(effects
							(font
								(size 1.27 1.27)
							)
						)
					)
					(number "206"
						(effects
							(font
								(size 1.27 1.27)
							)
						)
					)
				)
				(pin passive line
					(at 35.56 -49.53 180)
					(length 3.81)
					(name "DQ12_B"
						(effects
							(font
								(size 1.27 1.27)
							)
						)
					)
					(number "213"
						(effects
							(font
								(size 1.27 1.27)
							)
						)
					)
				)
				(pin passive line
					(at 35.56 -52.07 180)
					(length 3.81)
					(name "DQ13_B"
						(effects
							(font
								(size 1.27 1.27)
							)
						)
					)
					(number "214"
						(effects
							(font
								(size 1.27 1.27)
							)
						)
					)
				)
				(pin passive line
					(at 35.56 -54.61 180)
					(length 3.81)
					(name "DQ14_B"
						(effects
							(font
								(size 1.27 1.27)
							)
						)
					)
					(number "217"
						(effects
							(font
								(size 1.27 1.27)
							)
						)
					)
				)
				(pin passive line
					(at 35.56 -57.15 180)
					(length 3.81)
					(name "DQ15_B"
						(effects
							(font
								(size 1.27 1.27)
							)
						)
					)
					(number "218"
						(effects
							(font
								(size 1.27 1.27)
							)
						)
					)
				)
				(pin passive line
					(at 35.56 -60.96 180)
					(length 3.81)
					(name "DM1_B_n"
						(effects
							(font
								(size 1.27 1.27)
							)
						)
					)
					(number "210"
						(effects
							(font
								(size 1.27 1.27)
							)
						)
					)
				)
				(pin passive line
					(at 35.56 -66.04 180)
					(length 3.81)
					(name "DQS2_B_t"
						(effects
							(font
								(size 1.27 1.27)
							)
						)
					)
					(number "232"
						(effects
							(font
								(size 1.27 1.27)
							)
						)
					)
				)
				(pin passive line
					(at 35.56 -68.58 180)
					(length 3.81)
					(name "DQS2_B_C"
						(effects
							(font
								(size 1.27 1.27)
							)
						)
					)
					(number "230"
						(effects
							(font
								(size 1.27 1.27)
							)
						)
					)
				)
				(pin passive line
					(at 35.56 -72.39 180)
					(length 3.81)
					(name "DQ16_B"
						(effects
							(font
								(size 1.27 1.27)
							)
						)
					)
					(number "221"
						(effects
							(font
								(size 1.27 1.27)
							)
						)
					)
				)
				(pin passive line
					(at 35.56 -74.93 180)
					(length 3.81)
					(name "DQ17_B"
						(effects
							(font
								(size 1.27 1.27)
							)
						)
					)
					(number "222"
						(effects
							(font
								(size 1.27 1.27)
							)
						)
					)
				)
				(pin passive line
					(at 35.56 -77.47 180)
					(length 3.81)
					(name "DQ18_B"
						(effects
							(font
								(size 1.27 1.27)
							)
						)
					)
					(number "225"
						(effects
							(font
								(size 1.27 1.27)
							)
						)
					)
				)
				(pin passive line
					(at 35.56 -80.01 180)
					(length 3.81)
					(name "DQ19_B"
						(effects
							(font
								(size 1.27 1.27)
							)
						)
					)
					(number "226"
						(effects
							(font
								(size 1.27 1.27)
							)
						)
					)
				)
				(pin passive line
					(at 35.56 -82.55 180)
					(length 3.81)
					(name "DQ20_B"
						(effects
							(font
								(size 1.27 1.27)
							)
						)
					)
					(number "233"
						(effects
							(font
								(size 1.27 1.27)
							)
						)
					)
				)
				(pin passive line
					(at 35.56 -85.09 180)
					(length 3.81)
					(name "DQ21_B"
						(effects
							(font
								(size 1.27 1.27)
							)
						)
					)
					(number "236"
						(effects
							(font
								(size 1.27 1.27)
							)
						)
					)
				)
				(pin passive line
					(at 35.56 -87.63 180)
					(length 3.81)
					(name "DQ22_B"
						(effects
							(font
								(size 1.27 1.27)
							)
						)
					)
					(number "237"
						(effects
							(font
								(size 1.27 1.27)
							)
						)
					)
				)
				(pin passive line
					(at 35.56 -90.17 180)
					(length 3.81)
					(name "DQ23_B"
						(effects
							(font
								(size 1.27 1.27)
							)
						)
					)
					(number "240"
						(effects
							(font
								(size 1.27 1.27)
							)
						)
					)
				)
				(pin passive line
					(at 35.56 -93.98 180)
					(length 3.81)
					(name "DM2_B_n"
						(effects
							(font
								(size 1.27 1.27)
							)
						)
					)
					(number "229"
						(effects
							(font
								(size 1.27 1.27)
							)
						)
					)
				)
				(pin passive line
					(at 35.56 -99.06 180)
					(length 3.81)
					(name "DQS3_B_t"
						(effects
							(font
								(size 1.27 1.27)
							)
						)
					)
					(number "251"
						(effects
							(font
								(size 1.27 1.27)
							)
						)
					)
				)
				(pin passive line
					(at 35.56 -101.6 180)
					(length 3.81)
					(name "DQS3_B_c"
						(effects
							(font
								(size 1.27 1.27)
							)
						)
					)
					(number "249"
						(effects
							(font
								(size 1.27 1.27)
							)
						)
					)
				)
				(pin passive line
					(at 35.56 -105.41 180)
					(length 3.81)
					(name "DQ24_B"
						(effects
							(font
								(size 1.27 1.27)
							)
						)
					)
					(number "241"
						(effects
							(font
								(size 1.27 1.27)
							)
						)
					)
				)
				(pin passive line
					(at 35.56 -107.95 180)
					(length 3.81)
					(name "DQ25_B"
						(effects
							(font
								(size 1.27 1.27)
							)
						)
					)
					(number "244"
						(effects
							(font
								(size 1.27 1.27)
							)
						)
					)
				)
				(pin passive line
					(at 35.56 -110.49 180)
					(length 3.81)
					(name "DQ26_B"
						(effects
							(font
								(size 1.27 1.27)
							)
						)
					)
					(number "245"
						(effects
							(font
								(size 1.27 1.27)
							)
						)
					)
				)
				(pin passive line
					(at 35.56 -113.03 180)
					(length 3.81)
					(name "DQ27_B"
						(effects
							(font
								(size 1.27 1.27)
							)
						)
					)
					(number "248"
						(effects
							(font
								(size 1.27 1.27)
							)
						)
					)
				)
				(pin passive line
					(at 35.56 -115.57 180)
					(length 3.81)
					(name "DQ28_B"
						(effects
							(font
								(size 1.27 1.27)
							)
						)
					)
					(number "255"
						(effects
							(font
								(size 1.27 1.27)
							)
						)
					)
				)
				(pin passive line
					(at 35.56 -118.11 180)
					(length 3.81)
					(name "DQ29_B"
						(effects
							(font
								(size 1.27 1.27)
							)
						)
					)
					(number "256"
						(effects
							(font
								(size 1.27 1.27)
							)
						)
					)
				)
				(pin passive line
					(at 35.56 -120.65 180)
					(length 3.81)
					(name "DQ30_B"
						(effects
							(font
								(size 1.27 1.27)
							)
						)
					)
					(number "259"
						(effects
							(font
								(size 1.27 1.27)
							)
						)
					)
				)
				(pin passive line
					(at 35.56 -123.19 180)
					(length 3.81)
					(name "DQ31_B"
						(effects
							(font
								(size 1.27 1.27)
							)
						)
					)
					(number "260"
						(effects
							(font
								(size 1.27 1.27)
							)
						)
					)
				)
				(pin passive line
					(at 35.56 -127 180)
					(length 3.81)
					(name "DM3_B_n"
						(effects
							(font
								(size 1.27 1.27)
							)
						)
					)
					(number "252"
						(effects
							(font
								(size 1.27 1.27)
							)
						)
					)
				)
			)
			(symbol "Bus_DDR5_SODIMM_Amphenol_10161033-002RHLF_CUSTOM_2xDetectPin_3_1"
				(rectangle
					(start 3.81 2.54)
					(end 24.13 -22.86)
					(stroke
						(width 0.254)
						(type default)
					)
					(fill
						(type background)
					)
				)
				(pin passive line
					(at 0 0 0)
					(length 3.81)
					(name "VIN_BULK"
						(effects
							(font
								(size 1.27 1.27)
							)
						)
					)
					(number "1"
						(effects
							(font
								(size 1.27 1.27)
							)
						)
					)
				)
				(pin passive line
					(at 0 0 0)
					(length 3.81)
					(hide yes)
					(name "VIN_BULK"
						(effects
							(font
								(size 1.27 1.27)
							)
						)
					)
					(number "3"
						(effects
							(font
								(size 1.27 1.27)
							)
						)
					)
				)
				(pin passive line
					(at 0 -3.81 0)
					(length 3.81)
					(name "RFU"
						(effects
							(font
								(size 1.27 1.27)
							)
						)
					)
					(number "5"
						(effects
							(font
								(size 1.27 1.27)
							)
						)
					)
				)
				(pin passive line
					(at 0 -6.35 0)
					(length 3.81)
					(name "RFU"
						(effects
							(font
								(size 1.27 1.27)
							)
						)
					)
					(number "128"
						(effects
							(font
								(size 1.27 1.27)
							)
						)
					)
				)
				(pin passive line
					(at 0 -8.89 0)
					(length 3.81)
					(name "RFU"
						(effects
							(font
								(size 1.27 1.27)
							)
						)
					)
					(number "143"
						(effects
							(font
								(size 1.27 1.27)
							)
						)
					)
				)
				(pin passive line
					(at 0 -12.7 0)
					(length 3.81)
					(name "SDM_DETECT"
						(effects
							(font
								(size 1.27 1.27)
							)
						)
					)
					(number "124"
						(effects
							(font
								(size 1.27 1.27)
							)
						)
					)
				)
				(pin passive line
					(at 0 -15.24 0)
					(length 3.81)
					(name "TB_DETECT"
						(effects
							(font
								(size 1.27 1.27)
							)
						)
					)
					(number "130"
						(effects
							(font
								(size 1.27 1.27)
							)
						)
					)
				)
				(pin passive line
					(at 0 -19.05 0)
					(length 3.81)
					(name "VSS"
						(effects
							(font
								(size 1.27 1.27)
							)
						)
					)
					(number "10"
						(effects
							(font
								(size 1.27 1.27)
							)
						)
					)
				)
				(pin passive line
					(at 0 -19.05 0)
					(length 3.81)
					(hide yes)
					(name "VSS"
						(effects
							(font
								(size 1.27 1.27)
							)
						)
					)
					(number "101"
						(effects
							(font
								(size 1.27 1.27)
							)
						)
					)
				)
				(pin passive line
					(at 0 -19.05 0)
					(length 3.81)
					(hide yes)
					(name "VSS"
						(effects
							(font
								(size 1.27 1.27)
							)
						)
					)
					(number "104"
						(effects
							(font
								(size 1.27 1.27)
							)
						)
					)
				)
				(pin passive line
					(at 0 -19.05 0)
					(length 3.81)
					(hide yes)
					(name "VSS"
						(effects
							(font
								(size 1.27 1.27)
							)
						)
					)
					(number "105"
						(effects
							(font
								(size 1.27 1.27)
							)
						)
					)
				)
				(pin passive line
					(at 0 -19.05 0)
					(length 3.81)
					(hide yes)
					(name "VSS"
						(effects
							(font
								(size 1.27 1.27)
							)
						)
					)
					(number "111"
						(effects
							(font
								(size 1.27 1.27)
							)
						)
					)
				)
				(pin passive line
					(at 0 -19.05 0)
					(length 3.81)
					(hide yes)
					(name "VSS"
						(effects
							(font
								(size 1.27 1.27)
							)
						)
					)
					(number "112"
						(effects
							(font
								(size 1.27 1.27)
							)
						)
					)
				)
				(pin passive line
					(at 0 -19.05 0)
					(length 3.81)
					(hide yes)
					(name "VSS"
						(effects
							(font
								(size 1.27 1.27)
							)
						)
					)
					(number "117"
						(effects
							(font
								(size 1.27 1.27)
							)
						)
					)
				)
				(pin passive line
					(at 0 -19.05 0)
					(length 3.81)
					(hide yes)
					(name "VSS"
						(effects
							(font
								(size 1.27 1.27)
							)
						)
					)
					(number "118"
						(effects
							(font
								(size 1.27 1.27)
							)
						)
					)
				)
				(pin passive line
					(at 0 -19.05 0)
					(length 3.81)
					(hide yes)
					(name "VSS"
						(effects
							(font
								(size 1.27 1.27)
							)
						)
					)
					(number "123"
						(effects
							(font
								(size 1.27 1.27)
							)
						)
					)
				)
				(pin passive line
					(at 0 -19.05 0)
					(length 3.81)
					(hide yes)
					(name "VSS"
						(effects
							(font
								(size 1.27 1.27)
							)
						)
					)
					(number "129"
						(effects
							(font
								(size 1.27 1.27)
							)
						)
					)
				)
				(pin passive line
					(at 0 -19.05 0)
					(length 3.81)
					(hide yes)
					(name "VSS"
						(effects
							(font
								(size 1.27 1.27)
							)
						)
					)
					(number "13"
						(effects
							(font
								(size 1.27 1.27)
							)
						)
					)
				)
				(pin passive line
					(at 0 -19.05 0)
					(length 3.81)
					(hide yes)
					(name "VSS"
						(effects
							(font
								(size 1.27 1.27)
							)
						)
					)
					(number "135"
						(effects
							(font
								(size 1.27 1.27)
							)
						)
					)
				)
				(pin passive line
					(at 0 -19.05 0)
					(length 3.81)
					(hide yes)
					(name "VSS"
						(effects
							(font
								(size 1.27 1.27)
							)
						)
					)
					(number "136"
						(effects
							(font
								(size 1.27 1.27)
							)
						)
					)
				)
				(pin passive line
					(at 0 -19.05 0)
					(length 3.81)
					(hide yes)
					(name "VSS"
						(effects
							(font
								(size 1.27 1.27)
							)
						)
					)
					(number "14"
						(effects
							(font
								(size 1.27 1.27)
							)
						)
					)
				)
				(pin passive line
					(at 0 -19.05 0)
					(length 3.81)
					(hide yes)
					(name "VSS"
						(effects
							(font
								(size 1.27 1.27)
							)
						)
					)
					(number "141"
						(effects
							(font
								(size 1.27 1.27)
							)
						)
					)
				)
				(pin passive line
					(at 0 -19.05 0)
					(length 3.81)
					(hide yes)
					(name "VSS"
						(effects
							(font
								(size 1.27 1.27)
							)
						)
					)
					(number "142"
						(effects
							(font
								(size 1.27 1.27)
							)
						)
					)
				)
				(pin passive line
					(at 0 -19.05 0)
					(length 3.81)
					(hide yes)
					(name "VSS"
						(effects
							(font
								(size 1.27 1.27)
							)
						)
					)
					(number "147"
						(effects
							(font
								(size 1.27 1.27)
							)
						)
					)
				)
				(pin passive line
					(at 0 -19.05 0)
					(length 3.81)
					(hide yes)
					(name "VSS"
						(effects
							(font
								(size 1.27 1.27)
							)
						)
					)
					(number "148"
						(effects
							(font
								(size 1.27 1.27)
							)
						)
					)
				)
				(pin passive line
					(at 0 -19.05 0)
					(length 3.81)
					(hide yes)
					(name "VSS"
						(effects
							(font
								(size 1.27 1.27)
							)
						)
					)
					(number "153"
						(effects
							(font
								(size 1.27 1.27)
							)
						)
					)
				)
				(pin passive line
					(at 0 -19.05 0)
					(length 3.81)
					(hide yes)
					(name "VSS"
						(effects
							(font
								(size 1.27 1.27)
							)
						)
					)
					(number "154"
						(effects
							(font
								(size 1.27 1.27)
							)
						)
					)
				)
				(pin passive line
					(at 0 -19.05 0)
					(length 3.81)
					(hide yes)
					(name "VSS"
						(effects
							(font
								(size 1.27 1.27)
							)
						)
					)
					(number "159"
						(effects
							(font
								(size 1.27 1.27)
							)
						)
					)
				)
				(pin passive line
					(at 0 -19.05 0)
					(length 3.81)
					(hide yes)
					(name "VSS"
						(effects
							(font
								(size 1.27 1.27)
							)
						)
					)
					(number "160"
						(effects
							(font
								(size 1.27 1.27)
							)
						)
					)
				)
				(pin passive line
					(at 0 -19.05 0)
					(length 3.81)
					(hide yes)
					(name "VSS"
						(effects
							(font
								(size 1.27 1.27)
							)
						)
					)
					(number "166"
						(effects
							(font
								(size 1.27 1.27)
							)
						)
					)
				)
				(pin passive line
					(at 0 -19.05 0)
					(length 3.81)
					(hide yes)
					(name "VSS"
						(effects
							(font
								(size 1.27 1.27)
							)
						)
					)
					(number "167"
						(effects
							(font
								(size 1.27 1.27)
							)
						)
					)
				)
				(pin passive line
					(at 0 -19.05 0)
					(length 3.81)
					(hide yes)
					(name "VSS"
						(effects
							(font
								(size 1.27 1.27)
							)
						)
					)
					(number "17"
						(effects
							(font
								(size 1.27 1.27)
							)
						)
					)
				)
				(pin passive line
					(at 0 -19.05 0)
					(length 3.81)
					(hide yes)
					(name "VSS"
						(effects
							(font
								(size 1.27 1.27)
							)
						)
					)
					(number "170"
						(effects
							(font
								(size 1.27 1.27)
							)
						)
					)
				)
				(pin passive line
					(at 0 -19.05 0)
					(length 3.81)
					(hide yes)
					(name "VSS"
						(effects
							(font
								(size 1.27 1.27)
							)
						)
					)
					(number "173"
						(effects
							(font
								(size 1.27 1.27)
							)
						)
					)
				)
				(pin passive line
					(at 0 -19.05 0)
					(length 3.81)
					(hide yes)
					(name "VSS"
						(effects
							(font
								(size 1.27 1.27)
							)
						)
					)
					(number "174"
						(effects
							(font
								(size 1.27 1.27)
							)
						)
					)
				)
				(pin passive line
					(at 0 -19.05 0)
					(length 3.81)
					(hide yes)
					(name "VSS"
						(effects
							(font
								(size 1.27 1.27)
							)
						)
					)
					(number "177"
						(effects
							(font
								(size 1.27 1.27)
							)
						)
					)
				)
				(pin passive line
					(at 0 -19.05 0)
					(length 3.81)
					(hide yes)
					(name "VSS"
						(effects
							(font
								(size 1.27 1.27)
							)
						)
					)
					(number "178"
						(effects
							(font
								(size 1.27 1.27)
							)
						)
					)
				)
				(pin passive line
					(at 0 -19.05 0)
					(length 3.81)
					(hide yes)
					(name "VSS"
						(effects
							(font
								(size 1.27 1.27)
							)
						)
					)
					(number "18"
						(effects
							(font
								(size 1.27 1.27)
							)
						)
					)
				)
				(pin passive line
					(at 0 -19.05 0)
					(length 3.81)
					(hide yes)
					(name "VSS"
						(effects
							(font
								(size 1.27 1.27)
							)
						)
					)
					(number "181"
						(effects
							(font
								(size 1.27 1.27)
							)
						)
					)
				)
				(pin passive line
					(at 0 -19.05 0)
					(length 3.81)
					(hide yes)
					(name "VSS"
						(effects
							(font
								(size 1.27 1.27)
							)
						)
					)
					(number "182"
						(effects
							(font
								(size 1.27 1.27)
							)
						)
					)
				)
				(pin passive line
					(at 0 -19.05 0)
					(length 3.81)
					(hide yes)
					(name "VSS"
						(effects
							(font
								(size 1.27 1.27)
							)
						)
					)
					(number "185"
						(effects
							(font
								(size 1.27 1.27)
							)
						)
					)
				)
				(pin passive line
					(at 0 -19.05 0)
					(length 3.81)
					(hide yes)
					(name "VSS"
						(effects
							(font
								(size 1.27 1.27)
							)
						)
					)
					(number "186"
						(effects
							(font
								(size 1.27 1.27)
							)
						)
					)
				)
				(pin passive line
					(at 0 -19.05 0)
					(length 3.81)
					(hide yes)
					(name "VSS"
						(effects
							(font
								(size 1.27 1.27)
							)
						)
					)
					(number "189"
						(effects
							(font
								(size 1.27 1.27)
							)
						)
					)
				)
				(pin passive line
					(at 0 -19.05 0)
					(length 3.81)
					(hide yes)
					(name "VSS"
						(effects
							(font
								(size 1.27 1.27)
							)
						)
					)
					(number "192"
						(effects
							(font
								(size 1.27 1.27)
							)
						)
					)
				)
				(pin passive line
					(at 0 -19.05 0)
					(length 3.81)
					(hide yes)
					(name "VSS"
						(effects
							(font
								(size 1.27 1.27)
							)
						)
					)
					(number "193"
						(effects
							(font
								(size 1.27 1.27)
							)
						)
					)
				)
				(pin passive line
					(at 0 -19.05 0)
					(length 3.81)
					(hide yes)
					(name "VSS"
						(effects
							(font
								(size 1.27 1.27)
							)
						)
					)
					(number "196"
						(effects
							(font
								(size 1.27 1.27)
							)
						)
					)
				)
				(pin passive line
					(at 0 -19.05 0)
					(length 3.81)
					(hide yes)
					(name "VSS"
						(effects
							(font
								(size 1.27 1.27)
							)
						)
					)
					(number "197"
						(effects
							(font
								(size 1.27 1.27)
							)
						)
					)
				)
				(pin passive line
					(at 0 -19.05 0)
					(length 3.81)
					(hide yes)
					(name "VSS"
						(effects
							(font
								(size 1.27 1.27)
							)
						)
					)
					(number "200"
						(effects
							(font
								(size 1.27 1.27)
							)
						)
					)
				)
				(pin passive line
					(at 0 -19.05 0)
					(length 3.81)
					(hide yes)
					(name "VSS"
						(effects
							(font
								(size 1.27 1.27)
							)
						)
					)
					(number "201"
						(effects
							(font
								(size 1.27 1.27)
							)
						)
					)
				)
				(pin passive line
					(at 0 -19.05 0)
					(length 3.81)
					(hide yes)
					(name "VSS"
						(effects
							(font
								(size 1.27 1.27)
							)
						)
					)
					(number "204"
						(effects
							(font
								(size 1.27 1.27)
							)
						)
					)
				)
				(pin passive line
					(at 0 -19.05 0)
					(length 3.81)
					(hide yes)
					(name "VSS"
						(effects
							(font
								(size 1.27 1.27)
							)
						)
					)
					(number "205"
						(effects
							(font
								(size 1.27 1.27)
							)
						)
					)
				)
				(pin passive line
					(at 0 -19.05 0)
					(length 3.81)
					(hide yes)
					(name "VSS"
						(effects
							(font
								(size 1.27 1.27)
							)
						)
					)
					(number "208"
						(effects
							(font
								(size 1.27 1.27)
							)
						)
					)
				)
				(pin passive line
					(at 0 -19.05 0)
					(length 3.81)
					(hide yes)
					(name "VSS"
						(effects
							(font
								(size 1.27 1.27)
							)
						)
					)
					(number "21"
						(effects
							(font
								(size 1.27 1.27)
							)
						)
					)
				)
				(pin passive line
					(at 0 -19.05 0)
					(length 3.81)
					(hide yes)
					(name "VSS"
						(effects
							(font
								(size 1.27 1.27)
							)
						)
					)
					(number "211"
						(effects
							(font
								(size 1.27 1.27)
							)
						)
					)
				)
				(pin passive line
					(at 0 -19.05 0)
					(length 3.81)
					(hide yes)
					(name "VSS"
						(effects
							(font
								(size 1.27 1.27)
							)
						)
					)
					(number "212"
						(effects
							(font
								(size 1.27 1.27)
							)
						)
					)
				)
				(pin passive line
					(at 0 -19.05 0)
					(length 3.81)
					(hide yes)
					(name "VSS"
						(effects
							(font
								(size 1.27 1.27)
							)
						)
					)
					(number "215"
						(effects
							(font
								(size 1.27 1.27)
							)
						)
					)
				)
				(pin passive line
					(at 0 -19.05 0)
					(length 3.81)
					(hide yes)
					(name "VSS"
						(effects
							(font
								(size 1.27 1.27)
							)
						)
					)
					(number "216"
						(effects
							(font
								(size 1.27 1.27)
							)
						)
					)
				)
				(pin passive line
					(at 0 -19.05 0)
					(length 3.81)
					(hide yes)
					(name "VSS"
						(effects
							(font
								(size 1.27 1.27)
							)
						)
					)
					(number "219"
						(effects
							(font
								(size 1.27 1.27)
							)
						)
					)
				)
				(pin passive line
					(at 0 -19.05 0)
					(length 3.81)
					(hide yes)
					(name "VSS"
						(effects
							(font
								(size 1.27 1.27)
							)
						)
					)
					(number "220"
						(effects
							(font
								(size 1.27 1.27)
							)
						)
					)
				)
				(pin passive line
					(at 0 -19.05 0)
					(length 3.81)
					(hide yes)
					(name "VSS"
						(effects
							(font
								(size 1.27 1.27)
							)
						)
					)
					(number "223"
						(effects
							(font
								(size 1.27 1.27)
							)
						)
					)
				)
				(pin passive line
					(at 0 -19.05 0)
					(length 3.81)
					(hide yes)
					(name "VSS"
						(effects
							(font
								(size 1.27 1.27)
							)
						)
					)
					(number "224"
						(effects
							(font
								(size 1.27 1.27)
							)
						)
					)
				)
				(pin passive line
					(at 0 -19.05 0)
					(length 3.81)
					(hide yes)
					(name "VSS"
						(effects
							(font
								(size 1.27 1.27)
							)
						)
					)
					(number "227"
						(effects
							(font
								(size 1.27 1.27)
							)
						)
					)
				)
				(pin passive line
					(at 0 -19.05 0)
					(length 3.81)
					(hide yes)
					(name "VSS"
						(effects
							(font
								(size 1.27 1.27)
							)
						)
					)
					(number "228"
						(effects
							(font
								(size 1.27 1.27)
							)
						)
					)
				)
				(pin passive line
					(at 0 -19.05 0)
					(length 3.81)
					(hide yes)
					(name "VSS"
						(effects
							(font
								(size 1.27 1.27)
							)
						)
					)
					(number "231"
						(effects
							(font
								(size 1.27 1.27)
							)
						)
					)
				)
				(pin passive line
					(at 0 -19.05 0)
					(length 3.81)
					(hide yes)
					(name "VSS"
						(effects
							(font
								(size 1.27 1.27)
							)
						)
					)
					(number "234"
						(effects
							(font
								(size 1.27 1.27)
							)
						)
					)
				)
				(pin passive line
					(at 0 -19.05 0)
					(length 3.81)
					(hide yes)
					(name "VSS"
						(effects
							(font
								(size 1.27 1.27)
							)
						)
					)
					(number "235"
						(effects
							(font
								(size 1.27 1.27)
							)
						)
					)
				)
				(pin passive line
					(at 0 -19.05 0)
					(length 3.81)
					(hide yes)
					(name "VSS"
						(effects
							(font
								(size 1.27 1.27)
							)
						)
					)
					(number "238"
						(effects
							(font
								(size 1.27 1.27)
							)
						)
					)
				)
				(pin passive line
					(at 0 -19.05 0)
					(length 3.81)
					(hide yes)
					(name "VSS"
						(effects
							(font
								(size 1.27 1.27)
							)
						)
					)
					(number "239"
						(effects
							(font
								(size 1.27 1.27)
							)
						)
					)
				)
				(pin passive line
					(at 0 -19.05 0)
					(length 3.81)
					(hide yes)
					(name "VSS"
						(effects
							(font
								(size 1.27 1.27)
							)
						)
					)
					(number "24"
						(effects
							(font
								(size 1.27 1.27)
							)
						)
					)
				)
				(pin passive line
					(at 0 -19.05 0)
					(length 3.81)
					(hide yes)
					(name "VSS"
						(effects
							(font
								(size 1.27 1.27)
							)
						)
					)
					(number "242"
						(effects
							(font
								(size 1.27 1.27)
							)
						)
					)
				)
				(pin passive line
					(at 0 -19.05 0)
					(length 3.81)
					(hide yes)
					(name "VSS"
						(effects
							(font
								(size 1.27 1.27)
							)
						)
					)
					(number "243"
						(effects
							(font
								(size 1.27 1.27)
							)
						)
					)
				)
				(pin passive line
					(at 0 -19.05 0)
					(length 3.81)
					(hide yes)
					(name "VSS"
						(effects
							(font
								(size 1.27 1.27)
							)
						)
					)
					(number "246"
						(effects
							(font
								(size 1.27 1.27)
							)
						)
					)
				)
				(pin passive line
					(at 0 -19.05 0)
					(length 3.81)
					(hide yes)
					(name "VSS"
						(effects
							(font
								(size 1.27 1.27)
							)
						)
					)
					(number "247"
						(effects
							(font
								(size 1.27 1.27)
							)
						)
					)
				)
				(pin passive line
					(at 0 -19.05 0)
					(length 3.81)
					(hide yes)
					(name "VSS"
						(effects
							(font
								(size 1.27 1.27)
							)
						)
					)
					(number "25"
						(effects
							(font
								(size 1.27 1.27)
							)
						)
					)
				)
				(pin passive line
					(at 0 -19.05 0)
					(length 3.81)
					(hide yes)
					(name "VSS"
						(effects
							(font
								(size 1.27 1.27)
							)
						)
					)
					(number "250"
						(effects
							(font
								(size 1.27 1.27)
							)
						)
					)
				)
				(pin passive line
					(at 0 -19.05 0)
					(length 3.81)
					(hide yes)
					(name "VSS"
						(effects
							(font
								(size 1.27 1.27)
							)
						)
					)
					(number "253"
						(effects
							(font
								(size 1.27 1.27)
							)
						)
					)
				)
				(pin passive line
					(at 0 -19.05 0)
					(length 3.81)
					(hide yes)
					(name "VSS"
						(effects
							(font
								(size 1.27 1.27)
							)
						)
					)
					(number "254"
						(effects
							(font
								(size 1.27 1.27)
							)
						)
					)
				)
				(pin passive line
					(at 0 -19.05 0)
					(length 3.81)
					(hide yes)
					(name "VSS"
						(effects
							(font
								(size 1.27 1.27)
							)
						)
					)
					(number "257"
						(effects
							(font
								(size 1.27 1.27)
							)
						)
					)
				)
				(pin passive line
					(at 0 -19.05 0)
					(length 3.81)
					(hide yes)
					(name "VSS"
						(effects
							(font
								(size 1.27 1.27)
							)
						)
					)
					(number "258"
						(effects
							(font
								(size 1.27 1.27)
							)
						)
					)
				)
				(pin passive line
					(at 0 -19.05 0)
					(length 3.81)
					(hide yes)
					(name "VSS"
						(effects
							(font
								(size 1.27 1.27)
							)
						)
					)
					(number "261"
						(effects
							(font
								(size 1.27 1.27)
							)
						)
					)
				)
				(pin passive line
					(at 0 -19.05 0)
					(length 3.81)
					(hide yes)
					(name "VSS"
						(effects
							(font
								(size 1.27 1.27)
							)
						)
					)
					(number "262"
						(effects
							(font
								(size 1.27 1.27)
							)
						)
					)
				)
				(pin passive line
					(at 0 -19.05 0)
					(length 3.81)
					(hide yes)
					(name "VSS"
						(effects
							(font
								(size 1.27 1.27)
							)
						)
					)
					(number "28"
						(effects
							(font
								(size 1.27 1.27)
							)
						)
					)
				)
				(pin passive line
					(at 0 -19.05 0)
					(length 3.81)
					(hide yes)
					(name "VSS"
						(effects
							(font
								(size 1.27 1.27)
							)
						)
					)
					(number "29"
						(effects
							(font
								(size 1.27 1.27)
							)
						)
					)
				)
				(pin passive line
					(at 0 -19.05 0)
					(length 3.81)
					(hide yes)
					(name "VSS"
						(effects
							(font
								(size 1.27 1.27)
							)
						)
					)
					(number "32"
						(effects
							(font
								(size 1.27 1.27)
							)
						)
					)
				)
				(pin passive line
					(at 0 -19.05 0)
					(length 3.81)
					(hide yes)
					(name "VSS"
						(effects
							(font
								(size 1.27 1.27)
							)
						)
					)
					(number "33"
						(effects
							(font
								(size 1.27 1.27)
							)
						)
					)
				)
				(pin passive line
					(at 0 -19.05 0)
					(length 3.81)
					(hide yes)
					(name "VSS"
						(effects
							(font
								(size 1.27 1.27)
							)
						)
					)
					(number "36"
						(effects
							(font
								(size 1.27 1.27)
							)
						)
					)
				)
				(pin passive line
					(at 0 -19.05 0)
					(length 3.81)
					(hide yes)
					(name "VSS"
						(effects
							(font
								(size 1.27 1.27)
							)
						)
					)
					(number "37"
						(effects
							(font
								(size 1.27 1.27)
							)
						)
					)
				)
				(pin passive line
					(at 0 -19.05 0)
					(length 3.81)
					(hide yes)
					(name "VSS"
						(effects
							(font
								(size 1.27 1.27)
							)
						)
					)
					(number "40"
						(effects
							(font
								(size 1.27 1.27)
							)
						)
					)
				)
				(pin passive line
					(at 0 -19.05 0)
					(length 3.81)
					(hide yes)
					(name "VSS"
						(effects
							(font
								(size 1.27 1.27)
							)
						)
					)
					(number "43"
						(effects
							(font
								(size 1.27 1.27)
							)
						)
					)
				)
				(pin passive line
					(at 0 -19.05 0)
					(length 3.81)
					(hide yes)
					(name "VSS"
						(effects
							(font
								(size 1.27 1.27)
							)
						)
					)
					(number "44"
						(effects
							(font
								(size 1.27 1.27)
							)
						)
					)
				)
				(pin passive line
					(at 0 -19.05 0)
					(length 3.81)
					(hide yes)
					(name "VSS"
						(effects
							(font
								(size 1.27 1.27)
							)
						)
					)
					(number "47"
						(effects
							(font
								(size 1.27 1.27)
							)
						)
					)
				)
				(pin passive line
					(at 0 -19.05 0)
					(length 3.81)
					(hide yes)
					(name "VSS"
						(effects
							(font
								(size 1.27 1.27)
							)
						)
					)
					(number "48"
						(effects
							(font
								(size 1.27 1.27)
							)
						)
					)
				)
				(pin passive line
					(at 0 -19.05 0)
					(length 3.81)
					(hide yes)
					(name "VSS"
						(effects
							(font
								(size 1.27 1.27)
							)
						)
					)
					(number "51"
						(effects
							(font
								(size 1.27 1.27)
							)
						)
					)
				)
				(pin passive line
					(at 0 -19.05 0)
					(length 3.81)
					(hide yes)
					(name "VSS"
						(effects
							(font
								(size 1.27 1.27)
							)
						)
					)
					(number "52"
						(effects
							(font
								(size 1.27 1.27)
							)
						)
					)
				)
				(pin passive line
					(at 0 -19.05 0)
					(length 3.81)
					(hide yes)
					(name "VSS"
						(effects
							(font
								(size 1.27 1.27)
							)
						)
					)
					(number "55"
						(effects
							(font
								(size 1.27 1.27)
							)
						)
					)
				)
				(pin passive line
					(at 0 -19.05 0)
					(length 3.81)
					(hide yes)
					(name "VSS"
						(effects
							(font
								(size 1.27 1.27)
							)
						)
					)
					(number "56"
						(effects
							(font
								(size 1.27 1.27)
							)
						)
					)
				)
				(pin passive line
					(at 0 -19.05 0)
					(length 3.81)
					(hide yes)
					(name "VSS"
						(effects
							(font
								(size 1.27 1.27)
							)
						)
					)
					(number "59"
						(effects
							(font
								(size 1.27 1.27)
							)
						)
					)
				)
				(pin passive line
					(at 0 -19.05 0)
					(length 3.81)
					(hide yes)
					(name "VSS"
						(effects
							(font
								(size 1.27 1.27)
							)
						)
					)
					(number "60"
						(effects
							(font
								(size 1.27 1.27)
							)
						)
					)
				)
				(pin passive line
					(at 0 -19.05 0)
					(length 3.81)
					(hide yes)
					(name "VSS"
						(effects
							(font
								(size 1.27 1.27)
							)
						)
					)
					(number "63"
						(effects
							(font
								(size 1.27 1.27)
							)
						)
					)
				)
				(pin passive line
					(at 0 -19.05 0)
					(length 3.81)
					(hide yes)
					(name "VSS"
						(effects
							(font
								(size 1.27 1.27)
							)
						)
					)
					(number "66"
						(effects
							(font
								(size 1.27 1.27)
							)
						)
					)
				)
				(pin passive line
					(at 0 -19.05 0)
					(length 3.81)
					(hide yes)
					(name "VSS"
						(effects
							(font
								(size 1.27 1.27)
							)
						)
					)
					(number "67"
						(effects
							(font
								(size 1.27 1.27)
							)
						)
					)
				)
				(pin passive line
					(at 0 -19.05 0)
					(length 3.81)
					(hide yes)
					(name "VSS"
						(effects
							(font
								(size 1.27 1.27)
							)
						)
					)
					(number "70"
						(effects
							(font
								(size 1.27 1.27)
							)
						)
					)
				)
				(pin passive line
					(at 0 -19.05 0)
					(length 3.81)
					(hide yes)
					(name "VSS"
						(effects
							(font
								(size 1.27 1.27)
							)
						)
					)
					(number "71"
						(effects
							(font
								(size 1.27 1.27)
							)
						)
					)
				)
				(pin passive line
					(at 0 -19.05 0)
					(length 3.81)
					(hide yes)
					(name "VSS"
						(effects
							(font
								(size 1.27 1.27)
							)
						)
					)
					(number "74"
						(effects
							(font
								(size 1.27 1.27)
							)
						)
					)
				)
				(pin passive line
					(at 0 -19.05 0)
					(length 3.81)
					(hide yes)
					(name "VSS"
						(effects
							(font
								(size 1.27 1.27)
							)
						)
					)
					(number "75"
						(effects
							(font
								(size 1.27 1.27)
							)
						)
					)
				)
				(pin passive line
					(at 0 -19.05 0)
					(length 3.81)
					(hide yes)
					(name "VSS"
						(effects
							(font
								(size 1.27 1.27)
							)
						)
					)
					(number "78"
						(effects
							(font
								(size 1.27 1.27)
							)
						)
					)
				)
				(pin passive line
					(at 0 -19.05 0)
					(length 3.81)
					(hide yes)
					(name "VSS"
						(effects
							(font
								(size 1.27 1.27)
							)
						)
					)
					(number "79"
						(effects
							(font
								(size 1.27 1.27)
							)
						)
					)
				)
				(pin passive line
					(at 0 -19.05 0)
					(length 3.81)
					(hide yes)
					(name "VSS"
						(effects
							(font
								(size 1.27 1.27)
							)
						)
					)
					(number "82"
						(effects
							(font
								(size 1.27 1.27)
							)
						)
					)
				)
				(pin passive line
					(at 0 -19.05 0)
					(length 3.81)
					(hide yes)
					(name "VSS"
						(effects
							(font
								(size 1.27 1.27)
							)
						)
					)
					(number "85"
						(effects
							(font
								(size 1.27 1.27)
							)
						)
					)
				)
				(pin passive line
					(at 0 -19.05 0)
					(length 3.81)
					(hide yes)
					(name "VSS"
						(effects
							(font
								(size 1.27 1.27)
							)
						)
					)
					(number "86"
						(effects
							(font
								(size 1.27 1.27)
							)
						)
					)
				)
				(pin passive line
					(at 0 -19.05 0)
					(length 3.81)
					(hide yes)
					(name "VSS"
						(effects
							(font
								(size 1.27 1.27)
							)
						)
					)
					(number "89"
						(effects
							(font
								(size 1.27 1.27)
							)
						)
					)
				)
				(pin passive line
					(at 0 -19.05 0)
					(length 3.81)
					(hide yes)
					(name "VSS"
						(effects
							(font
								(size 1.27 1.27)
							)
						)
					)
					(number "9"
						(effects
							(font
								(size 1.27 1.27)
							)
						)
					)
				)
				(pin passive line
					(at 0 -19.05 0)
					(length 3.81)
					(hide yes)
					(name "VSS"
						(effects
							(font
								(size 1.27 1.27)
							)
						)
					)
					(number "90"
						(effects
							(font
								(size 1.27 1.27)
							)
						)
					)
				)
				(pin passive line
					(at 0 -19.05 0)
					(length 3.81)
					(hide yes)
					(name "VSS"
						(effects
							(font
								(size 1.27 1.27)
							)
						)
					)
					(number "93"
						(effects
							(font
								(size 1.27 1.27)
							)
						)
					)
				)
				(pin passive line
					(at 0 -19.05 0)
					(length 3.81)
					(hide yes)
					(name "VSS"
						(effects
							(font
								(size 1.27 1.27)
							)
						)
					)
					(number "94"
						(effects
							(font
								(size 1.27 1.27)
							)
						)
					)
				)
				(pin passive line
					(at 0 -19.05 0)
					(length 3.81)
					(hide yes)
					(name "VSS"
						(effects
							(font
								(size 1.27 1.27)
							)
						)
					)
					(number "97"
						(effects
							(font
								(size 1.27 1.27)
							)
						)
					)
				)
				(pin passive line
					(at 0 -19.05 0)
					(length 3.81)
					(hide yes)
					(name "VSS"
						(effects
							(font
								(size 1.27 1.27)
							)
						)
					)
					(number "98"
						(effects
							(font
								(size 1.27 1.27)
							)
						)
					)
				)
				(pin passive line
					(at 0 -21.59 0)
					(length 3.81)
					(name "~"
						(effects
							(font
								(size 1.27 1.27)
							)
						)
					)
					(number "SH"
						(effects
							(font
								(size 1.27 1.27)
							)
						)
					)
				)
				(pin passive line
					(at 27.94 0 180)
					(length 3.81)
					(name "PWR_EN"
						(effects
							(font
								(size 1.27 1.27)
							)
						)
					)
					(number "8"
						(effects
							(font
								(size 1.27 1.27)
							)
						)
					)
				)
				(pin passive line
					(at 27.94 -2.54 180)
					(length 3.81)
					(name "RESET_n"
						(effects
							(font
								(size 1.27 1.27)
							)
						)
					)
					(number "163"
						(effects
							(font
								(size 1.27 1.27)
							)
						)
					)
				)
				(pin passive line
					(at 27.94 -5.08 180)
					(length 3.81)
					(name "PWR_GOOD"
						(effects
							(font
								(size 1.27 1.27)
							)
						)
					)
					(number "7"
						(effects
							(font
								(size 1.27 1.27)
							)
						)
					)
				)
				(pin passive line
					(at 27.94 -7.62 180)
					(length 3.81)
					(name "ALERT_n"
						(effects
							(font
								(size 1.27 1.27)
							)
						)
					)
					(number "108"
						(effects
							(font
								(size 1.27 1.27)
							)
						)
					)
				)
				(pin passive line
					(at 27.94 -11.43 180)
					(length 3.81)
					(name "HSA"
						(effects
							(font
								(size 1.27 1.27)
							)
						)
					)
					(number "2"
						(effects
							(font
								(size 1.27 1.27)
							)
						)
					)
				)
				(pin passive line
					(at 27.94 -13.97 180)
					(length 3.81)
					(name "HSCL"
						(effects
							(font
								(size 1.27 1.27)
							)
						)
					)
					(number "4"
						(effects
							(font
								(size 1.27 1.27)
							)
						)
					)
				)
				(pin passive line
					(at 27.94 -16.51 180)
					(length 3.81)
					(name "HSDA"
						(effects
							(font
								(size 1.27 1.27)
							)
						)
					)
					(number "6"
						(effects
							(font
								(size 1.27 1.27)
							)
						)
					)
				)
			)
		)
	(symbol "antmicroMemoryConnectorsPCCardSockets:MicroSD_693071020811"
			(exclude_from_sim no)
			(in_bom yes)
			(on_board yes)
			(property "Reference" "J"
				(at 55.88 -2.54 0)
				(effects
					(font
						(size 1.27 1.27)
						(thickness 0.15)
					)
					(justify left bottom)
				)
			)
			(property "Value" "MicroSD_693071020811"
				(at 55.88 -5.08 0)
				(effects
					(font
						(size 1.27 1.27)
						(thickness 0.15)
					)
					(justify left bottom)
				)
			)
			(property "Footprint" "antmicro-footprints:MicroSD_Wurth_693071020811"
				(at 55.88 -7.62 0)
				(effects
					(font
						(size 1.27 1.27)
						(thickness 0.15)
					)
					(justify left bottom)
					(hide yes)
				)
			)
			(property "Datasheet" "https://www.we-online.com/catalog/datasheet/693071020811.pdf"
				(at 55.88 -10.16 0)
				(effects
					(font
						(size 1.27 1.27)
						(thickness 0.15)
					)
					(justify left bottom)
					(hide yes)
				)
			)
			(property "Description" "Memory Card Connector, MicroSD, Push-Push, 8 Contacts, Copper Alloy, Gold Plated Contacts, WR-CRD"
				(at 0 0 0)
				(effects
					(font
						(size 1.27 1.27)
					)
					(hide yes)
				)
			)
			(property "Manufacturer" "Würth Elektronik"
				(at 55.88 -12.7 0)
				(effects
					(font
						(size 1.27 1.27)
						(thickness 0.15)
					)
					(justify left bottom)
					(hide yes)
				)
			)
			(property "MPN" "693071020811"
				(at 55.88 -15.24 0)
				(effects
					(font
						(size 1.27 1.27)
						(thickness 0.15)
					)
					(justify left bottom)
					(hide yes)
				)
			)
			(property "Author" "Antmicro"
				(at 55.88 -17.78 0)
				(effects
					(font
						(size 1.27 1.27)
						(thickness 0.15)
					)
					(justify left bottom)
					(hide yes)
				)
			)
			(property "License" "Apache-2.0"
				(at 55.88 -20.32 0)
				(effects
					(font
						(size 1.27 1.27)
						(thickness 0.15)
					)
					(justify left bottom)
					(hide yes)
				)
			)
			(property "ki_keywords" "HORIZONTAL, SMT, MEMORY, CONNECTOR"
				(at 0 0 0)
				(effects
					(font
						(size 1.27 1.27)
					)
					(hide yes)
				)
			)
			(symbol "MicroSD_693071020811_1_1"
				(polyline
					(pts
						(xy 12.7 -21.59) (xy 12.7 -1.27) (xy 20.32 -1.27) (xy 24.13 2.54) (xy 25.4 2.54) (xy 25.4 1.27)
						(xy 27.94 1.27) (xy 29.21 2.54) (xy 41.91 2.54) (xy 41.91 -21.59) (xy 12.7 -21.59)
					)
					(stroke
						(width 0.254)
						(type default)
					)
					(fill
						(type background)
					)
				)
				(rectangle
					(start 13.97 -1.905)
					(end 16.51 -3.175)
					(stroke
						(width 0.254)
						(type default)
					)
					(fill
						(type outline)
					)
				)
				(rectangle
					(start 13.97 -4.445)
					(end 16.51 -5.715)
					(stroke
						(width 0.254)
						(type default)
					)
					(fill
						(type outline)
					)
				)
				(rectangle
					(start 13.97 -6.985)
					(end 16.51 -8.255)
					(stroke
						(width 0.254)
						(type default)
					)
					(fill
						(type outline)
					)
				)
				(rectangle
					(start 13.97 -9.525)
					(end 16.51 -10.795)
					(stroke
						(width 0.254)
						(type default)
					)
					(fill
						(type outline)
					)
				)
				(rectangle
					(start 13.97 -12.065)
					(end 16.51 -13.335)
					(stroke
						(width 0.254)
						(type default)
					)
					(fill
						(type outline)
					)
				)
				(rectangle
					(start 13.97 -14.605)
					(end 16.51 -15.875)
					(stroke
						(width 0.254)
						(type default)
					)
					(fill
						(type outline)
					)
				)
				(rectangle
					(start 13.97 -17.145)
					(end 16.51 -18.415)
					(stroke
						(width 0.254)
						(type default)
					)
					(fill
						(type outline)
					)
				)
				(rectangle
					(start 13.97 -19.685)
					(end 16.51 -20.955)
					(stroke
						(width 0.254)
						(type default)
					)
					(fill
						(type outline)
					)
				)
				(polyline
					(pts
						(xy 38.1 2.54) (xy 38.1 3.81) (xy 2.54 3.81) (xy 2.54 -29.21) (xy 38.1 -29.21) (xy 38.1 -21.59)
					)
					(stroke
						(width 0.254)
						(type default)
					)
					(fill
						(type background)
					)
				)
				(pin power_in line
					(at 0 0 0)
					(length 2.54)
					(name "VDD"
						(effects
							(font
								(size 1.27 1.27)
							)
						)
					)
					(number "4"
						(effects
							(font
								(size 1.27 1.27)
							)
						)
					)
				)
				(pin bidirectional line
					(at 0 -5.08 0)
					(length 2.54)
					(name "DAT2"
						(effects
							(font
								(size 1.27 1.27)
							)
						)
					)
					(number "1"
						(effects
							(font
								(size 1.27 1.27)
							)
						)
					)
				)
				(pin bidirectional line
					(at 0 -7.62 0)
					(length 2.54)
					(name "DAT3/CD"
						(effects
							(font
								(size 1.27 1.27)
							)
						)
					)
					(number "2"
						(effects
							(font
								(size 1.27 1.27)
							)
						)
					)
				)
				(pin input line
					(at 0 -10.16 0)
					(length 2.54)
					(name "CMD"
						(effects
							(font
								(size 1.27 1.27)
							)
						)
					)
					(number "3"
						(effects
							(font
								(size 1.27 1.27)
							)
						)
					)
				)
				(pin input line
					(at 0 -12.7 0)
					(length 2.54)
					(name "CLK"
						(effects
							(font
								(size 1.27 1.27)
							)
						)
					)
					(number "5"
						(effects
							(font
								(size 1.27 1.27)
							)
						)
					)
				)
				(pin input line
					(at 0 -15.24 0)
					(length 2.54)
					(name "DAT0"
						(effects
							(font
								(size 1.27 1.27)
							)
						)
					)
					(number "7"
						(effects
							(font
								(size 1.27 1.27)
							)
						)
					)
				)
				(pin input line
					(at 0 -17.78 0)
					(length 2.54)
					(name "DAT1"
						(effects
							(font
								(size 1.27 1.27)
							)
						)
					)
					(number "8"
						(effects
							(font
								(size 1.27 1.27)
							)
						)
					)
				)
				(pin passive line
					(at 0 -20.32 0)
					(length 2.54)
					(name "CD_SW1"
						(effects
							(font
								(size 1.27 1.27)
							)
						)
					)
					(number "9"
						(effects
							(font
								(size 1.27 1.27)
							)
						)
					)
				)
				(pin passive line
					(at 0 -26.67 0)
					(length 2.54)
					(name "VSS"
						(effects
							(font
								(size 1.27 1.27)
							)
						)
					)
					(number "6"
						(effects
							(font
								(size 1.27 1.27)
							)
						)
					)
				)
				(pin passive line
					(at 40.64 -26.67 180)
					(length 2.54)
					(name "SH"
						(effects
							(font
								(size 1.27 1.27)
							)
						)
					)
					(number "SH"
						(effects
							(font
								(size 1.27 1.27)
							)
						)
					)
				)
			)
		)
	(symbol "antmicroModularConnectorsJacks:RJ45_Abracon_ARJM11B1-502-AB-EW2"
			(exclude_from_sim no)
			(in_bom yes)
			(on_board yes)
			(property "Reference" "J"
				(at 35.56 -2.54 0)
				(effects
					(font
						(size 1.27 1.27)
						(thickness 0.15)
					)
					(justify left bottom)
				)
			)
			(property "Value" "RJ45_Abracon_ARJM11B1-502-AB-EW2"
				(at 35.56 -7.62 0)
				(effects
					(font
						(size 1.27 1.27)
						(thickness 0.15)
					)
					(justify left bottom)
					(hide yes)
				)
			)
			(property "Footprint" "antmicro-footprints:RJ45_ARJM11B1-502-AB-EW2_Horizontal"
				(at 35.56 -10.16 0)
				(effects
					(font
						(size 1.27 1.27)
						(thickness 0.15)
					)
					(justify left bottom)
					(hide yes)
				)
			)
			(property "Datasheet" "https://www.mouser.com/datasheet/3/184/1/ARJM11.pdf"
				(at 35.56 -12.7 0)
				(effects
					(font
						(size 1.27 1.27)
						(thickness 0.15)
					)
					(justify left bottom)
					(hide yes)
				)
			)
			(property "Description" "Modular Connectors / Ethernet Connectors RJ45 JACK W/MAG 1X1 1000BASE-T"
				(at 35.56 -22.606 0)
				(effects
					(font
						(size 1.27 1.27)
					)
					(justify left bottom)
					(hide yes)
				)
			)
			(property "MPN" "ARJM11B1-502-AB-EW2"
				(at 35.56 -5.08 0)
				(effects
					(font
						(size 1.27 1.27)
						(thickness 0.15)
					)
					(justify left bottom)
				)
			)
			(property "Manufacturer" "Abracon"
				(at 35.56 -15.24 0)
				(effects
					(font
						(size 1.27 1.27)
						(thickness 0.15)
					)
					(justify left bottom)
					(hide yes)
				)
			)
			(property "Author" "Antmicro"
				(at 35.56 -17.526 0)
				(effects
					(font
						(size 1.27 1.27)
						(thickness 0.15)
					)
					(justify left bottom)
					(hide yes)
				)
			)
			(property "License" "Apache-2.0"
				(at 35.56 -20.066 0)
				(effects
					(font
						(size 1.27 1.27)
						(thickness 0.15)
					)
					(justify left bottom)
					(hide yes)
				)
			)
			(property "ki_keywords" "CONNECTOR, RJ45, THT, ETHERNET, HORIZONTAL"
				(at 0 0 0)
				(effects
					(font
						(size 1.27 1.27)
					)
					(hide yes)
				)
			)
			(symbol "RJ45_Abracon_ARJM11B1-502-AB-EW2_1_1"
				(rectangle
					(start 2.54 2.54)
					(end 20.32 -30.48)
					(stroke
						(width 0.254)
						(type default)
					)
					(fill
						(type background)
					)
				)
				(rectangle
					(start 6.35 -4.445)
					(end 17.78 -18.415)
					(stroke
						(width 0.254)
						(type default)
					)
					(fill
						(type background)
					)
				)
				(polyline
					(pts
						(xy 7.62 -5.715) (xy 13.97 -5.715)
					)
					(stroke
						(width 0.254)
						(type default)
					)
					(fill
						(type background)
					)
				)
				(polyline
					(pts
						(xy 7.62 -17.145) (xy 7.62 -5.715)
					)
					(stroke
						(width 0.254)
						(type default)
					)
					(fill
						(type background)
					)
				)
				(polyline
					(pts
						(xy 13.97 -5.715) (xy 13.97 -6.985)
					)
					(stroke
						(width 0.254)
						(type default)
					)
					(fill
						(type background)
					)
				)
				(polyline
					(pts
						(xy 13.97 -6.985) (xy 15.24 -6.985)
					)
					(stroke
						(width 0.254)
						(type default)
					)
					(fill
						(type background)
					)
				)
				(polyline
					(pts
						(xy 13.97 -15.875) (xy 15.24 -15.875)
					)
					(stroke
						(width 0.254)
						(type default)
					)
					(fill
						(type background)
					)
				)
				(polyline
					(pts
						(xy 13.97 -17.145) (xy 7.62 -17.145)
					)
					(stroke
						(width 0.254)
						(type default)
					)
					(fill
						(type background)
					)
				)
				(polyline
					(pts
						(xy 13.97 -17.145) (xy 13.97 -15.875)
					)
					(stroke
						(width 0.254)
						(type default)
					)
					(fill
						(type background)
					)
				)
				(polyline
					(pts
						(xy 15.24 -6.985) (xy 15.24 -8.255)
					)
					(stroke
						(width 0.254)
						(type default)
					)
					(fill
						(type background)
					)
				)
				(polyline
					(pts
						(xy 15.24 -8.255) (xy 16.51 -8.255)
					)
					(stroke
						(width 0.254)
						(type default)
					)
					(fill
						(type background)
					)
				)
				(polyline
					(pts
						(xy 15.24 -14.605) (xy 16.51 -14.605)
					)
					(stroke
						(width 0.254)
						(type default)
					)
					(fill
						(type background)
					)
				)
				(polyline
					(pts
						(xy 15.24 -15.875) (xy 15.24 -14.605)
					)
					(stroke
						(width 0.254)
						(type default)
					)
					(fill
						(type background)
					)
				)
				(polyline
					(pts
						(xy 16.51 -8.255) (xy 16.51 -14.605)
					)
					(stroke
						(width 0.254)
						(type default)
					)
					(fill
						(type background)
					)
				)
				(pin bidirectional line
					(at 0 0 0)
					(length 2.54)
					(name "1"
						(effects
							(font
								(size 1.27 1.27)
							)
						)
					)
					(number "1"
						(effects
							(font
								(size 1.27 1.27)
							)
						)
					)
				)
				(pin bidirectional line
					(at 0 -2.54 0)
					(length 2.54)
					(name "2"
						(effects
							(font
								(size 1.27 1.27)
							)
						)
					)
					(number "2"
						(effects
							(font
								(size 1.27 1.27)
							)
						)
					)
				)
				(pin bidirectional line
					(at 0 -5.08 0)
					(length 2.54)
					(name "3"
						(effects
							(font
								(size 1.27 1.27)
							)
						)
					)
					(number "3"
						(effects
							(font
								(size 1.27 1.27)
							)
						)
					)
				)
				(pin bidirectional line
					(at 0 -7.62 0)
					(length 2.54)
					(name "4"
						(effects
							(font
								(size 1.27 1.27)
							)
						)
					)
					(number "4"
						(effects
							(font
								(size 1.27 1.27)
							)
						)
					)
				)
				(pin bidirectional line
					(at 0 -10.16 0)
					(length 2.54)
					(name "7"
						(effects
							(font
								(size 1.27 1.27)
							)
						)
					)
					(number "7"
						(effects
							(font
								(size 1.27 1.27)
							)
						)
					)
				)
				(pin bidirectional line
					(at 0 -12.7 0)
					(length 2.54)
					(name "8"
						(effects
							(font
								(size 1.27 1.27)
							)
						)
					)
					(number "8"
						(effects
							(font
								(size 1.27 1.27)
							)
						)
					)
				)
				(pin bidirectional line
					(at 0 -15.24 0)
					(length 2.54)
					(name "9"
						(effects
							(font
								(size 1.27 1.27)
							)
						)
					)
					(number "9"
						(effects
							(font
								(size 1.27 1.27)
							)
						)
					)
				)
				(pin bidirectional line
					(at 0 -17.78 0)
					(length 2.54)
					(name "10"
						(effects
							(font
								(size 1.27 1.27)
							)
						)
					)
					(number "10"
						(effects
							(font
								(size 1.27 1.27)
							)
						)
					)
				)
				(pin passive line
					(at 0 -21.59 0)
					(length 2.54)
					(name "5"
						(effects
							(font
								(size 1.27 1.27)
							)
						)
					)
					(number "5"
						(effects
							(font
								(size 1.27 1.27)
							)
						)
					)
				)
				(pin passive line
					(at 0 -24.13 0)
					(length 2.54)
					(name "6"
						(effects
							(font
								(size 1.27 1.27)
							)
						)
					)
					(number "6"
						(effects
							(font
								(size 1.27 1.27)
							)
						)
					)
				)
				(pin passive line
					(at 0 -27.94 0)
					(length 2.54)
					(name "SH"
						(effects
							(font
								(size 1.27 1.27)
							)
						)
					)
					(number "SH"
						(effects
							(font
								(size 1.27 1.27)
							)
						)
					)
				)
				(pin passive line
					(at 22.86 0 180)
					(length 2.54)
					(name "LED_Y+"
						(effects
							(font
								(size 1.27 1.27)
							)
						)
					)
					(number "13"
						(effects
							(font
								(size 1.27 1.27)
							)
						)
					)
				)
				(pin passive line
					(at 22.86 -2.54 180)
					(length 2.54)
					(name "LED_Y-"
						(effects
							(font
								(size 1.27 1.27)
							)
						)
					)
					(number "14"
						(effects
							(font
								(size 1.27 1.27)
							)
						)
					)
				)
				(pin passive line
					(at 22.86 -25.4 180)
					(length 2.54)
					(name "LED_G+"
						(effects
							(font
								(size 1.27 1.27)
							)
						)
					)
					(number "11"
						(effects
							(font
								(size 1.27 1.27)
							)
						)
					)
				)
				(pin passive line
					(at 22.86 -27.94 180)
					(length 2.54)
					(name "LED_G-"
						(effects
							(font
								(size 1.27 1.27)
							)
						)
					)
					(number "12"
						(effects
							(font
								(size 1.27 1.27)
							)
						)
					)
				)
			)
		)
	(symbol "antmicroOscillators:Oscillator_100MHz_ASFL1"
			(exclude_from_sim no)
			(in_bom yes)
			(on_board yes)
			(property "Reference" "Y"
				(at 26.035 -1.905 0)
				(effects
					(font
						(size 1.27 1.27)
						(thickness 0.15)
					)
					(justify left bottom)
				)
			)
			(property "Value" "Oscillator_100MHz_ASFL1"
				(at 26.035 -12.065 0)
				(effects
					(font
						(size 1.27 1.27)
						(thickness 0.15)
					)
					(justify left bottom)
					(hide yes)
				)
			)
			(property "Footprint" "antmicro-footprints:Oscillator_SMD_Abracon_ASFL1-4Pin_5.0x3.2mm"
				(at 26.035 -14.605 0)
				(effects
					(font
						(size 1.27 1.27)
						(thickness 0.15)
					)
					(justify left bottom)
					(hide yes)
				)
			)
			(property "Datasheet" "https://abracon.com/Oscillators/ASFL1.pdf"
				(at 26.035 -17.145 0)
				(effects
					(font
						(size 1.27 1.27)
						(thickness 0.15)
					)
					(justify left bottom)
					(hide yes)
				)
			)
			(property "Description" "Oscillator, 100 MHz, 100 ppm, SMT, 5mm x 3.2mm, 3.3 V, ASFL1 Series"
				(at 0 0 0)
				(effects
					(font
						(size 1.27 1.27)
					)
					(hide yes)
				)
			)
			(property "MPN" "ASFL1-100.000MHZ-L-T"
				(at 26.035 -4.445 0)
				(effects
					(font
						(size 1.27 1.27)
						(thickness 0.15)
					)
					(justify left bottom)
				)
			)
			(property "Manufacturer" "Abracon"
				(at 26.035 -6.985 0)
				(effects
					(font
						(size 1.27 1.27)
						(thickness 0.15)
					)
					(justify left bottom)
					(hide yes)
				)
			)
			(property "Val" "100 MHz"
				(at 26.035 -9.525 0)
				(effects
					(font
						(size 1.27 1.27)
						(thickness 0.15)
					)
					(justify left bottom)
				)
			)
			(property "Author" "Antmicro"
				(at 26.035 -19.685 0)
				(effects
					(font
						(size 1.27 1.27)
						(thickness 0.15)
					)
					(justify left bottom)
					(hide yes)
				)
			)
			(property "License" "Apache-2.0"
				(at 26.035 -22.225 0)
				(effects
					(font
						(size 1.27 1.27)
						(thickness 0.15)
					)
					(justify left bottom)
					(hide yes)
				)
			)
			(property "ki_keywords" "OSCILLATOR"
				(at 0 0 0)
				(effects
					(font
						(size 1.27 1.27)
					)
					(hide yes)
				)
			)
			(symbol "Oscillator_100MHz_ASFL1_1_1"
				(rectangle
					(start 2.54 2.54)
					(end 16.51 -7.62)
					(stroke
						(width 0.254)
						(type default)
					)
					(fill
						(type background)
					)
				)
				(polyline
					(pts
						(xy 7.62 -1.27) (xy 8.255 -1.27) (xy 8.255 0) (xy 8.89 0) (xy 8.89 -1.27) (xy 9.525 -1.27) (xy 9.525 0)
						(xy 10.16 0) (xy 10.16 -1.27)
					)
					(stroke
						(width 0.254)
						(type default)
					)
					(fill
						(type background)
					)
				)
				(pin power_in line
					(at 0 0 0)
					(length 2.54)
					(name "VDD"
						(effects
							(font
								(size 1.27 1.27)
							)
						)
					)
					(number "4"
						(effects
							(font
								(size 1.27 1.27)
							)
						)
					)
				)
				(pin input line
					(at 0 -2.54 0)
					(length 2.54)
					(name "EN"
						(effects
							(font
								(size 1.27 1.27)
							)
						)
					)
					(number "1"
						(effects
							(font
								(size 1.27 1.27)
							)
						)
					)
				)
				(pin power_in line
					(at 0 -5.08 0)
					(length 2.54)
					(name "GND"
						(effects
							(font
								(size 1.27 1.27)
							)
						)
					)
					(number "2"
						(effects
							(font
								(size 1.27 1.27)
							)
						)
					)
				)
				(pin output line
					(at 19.05 0 180)
					(length 2.54)
					(name "OUT"
						(effects
							(font
								(size 1.27 1.27)
							)
						)
					)
					(number "3"
						(effects
							(font
								(size 1.27 1.27)
							)
						)
					)
				)
			)
		)
	(symbol "antmicroPMICORControllersIdealDiodes:LTC4412IS6"
			(exclude_from_sim no)
			(in_bom yes)
			(on_board yes)
			(property "Reference" "U"
				(at 31.75 -2.54 0)
				(effects
					(font
						(size 1.27 1.27)
						(thickness 0.15)
					)
					(justify left bottom)
				)
			)
			(property "Value" "LTC4412IS6"
				(at 31.75 -5.08 0)
				(effects
					(font
						(size 1.27 1.27)
						(thickness 0.15)
					)
					(justify left bottom)
				)
			)
			(property "Footprint" "antmicro-footprints:SOT-23-6"
				(at 31.75 -7.62 0)
				(effects
					(font
						(size 1.27 1.27)
						(thickness 0.15)
					)
					(justify left bottom)
					(hide yes)
				)
			)
			(property "Datasheet" "https://www.mouser.com/datasheet/2/308/NCV8187_D-1813214.pdf"
				(at 31.75 -10.16 0)
				(effects
					(font
						(size 1.27 1.27)
						(thickness 0.15)
					)
					(justify left bottom)
					(hide yes)
				)
			)
			(property "Description" "Ideal diode controller"
				(at 0 0 0)
				(effects
					(font
						(size 1.27 1.27)
					)
					(hide yes)
				)
			)
			(property "MPN" "LTC4412IS6#TRMPBF"
				(at 31.75 -12.7 0)
				(effects
					(font
						(size 1.27 1.27)
						(thickness 0.15)
					)
					(justify left bottom)
					(hide yes)
				)
			)
			(property "Manufacturer" "Analog Devices"
				(at 31.75 -15.24 0)
				(effects
					(font
						(size 1.27 1.27)
						(thickness 0.15)
					)
					(justify left bottom)
					(hide yes)
				)
			)
			(property "Author" "Antmicro"
				(at 31.75 -17.78 0)
				(effects
					(font
						(size 1.27 1.27)
						(thickness 0.15)
					)
					(justify left bottom)
					(hide yes)
				)
			)
			(property "License" "Apache-2.0"
				(at 31.75 -20.32 0)
				(effects
					(font
						(size 1.27 1.27)
						(thickness 0.15)
					)
					(justify left bottom)
					(hide yes)
				)
			)
			(property "ki_keywords" "SMT, CONTROLLER, IC, DIODE"
				(at 0 0 0)
				(effects
					(font
						(size 1.27 1.27)
					)
					(hide yes)
				)
			)
			(symbol "LTC4412IS6_1_1"
				(rectangle
					(start 2.54 2.54)
					(end 15.24 -7.62)
					(stroke
						(width 0.254)
						(type default)
					)
					(fill
						(type background)
					)
				)
				(pin power_in line
					(at 0 0 0)
					(length 2.54)
					(name "IN"
						(effects
							(font
								(size 1.27 1.27)
							)
						)
					)
					(number "1"
						(effects
							(font
								(size 1.27 1.27)
							)
						)
					)
				)
				(pin input line
					(at 0 -2.54 0)
					(length 2.54)
					(name "CTL"
						(effects
							(font
								(size 1.27 1.27)
							)
						)
					)
					(number "3"
						(effects
							(font
								(size 1.27 1.27)
							)
						)
					)
				)
				(pin power_in line
					(at 0 -5.08 0)
					(length 2.54)
					(name "GND"
						(effects
							(font
								(size 1.27 1.27)
							)
						)
					)
					(number "2"
						(effects
							(font
								(size 1.27 1.27)
							)
						)
					)
				)
				(pin input line
					(at 17.78 0 180)
					(length 2.54)
					(name "SENSE"
						(effects
							(font
								(size 1.27 1.27)
							)
						)
					)
					(number "6"
						(effects
							(font
								(size 1.27 1.27)
							)
						)
					)
				)
				(pin output line
					(at 17.78 -2.54 180)
					(length 2.54)
					(name "GATE"
						(effects
							(font
								(size 1.27 1.27)
							)
						)
					)
					(number "5"
						(effects
							(font
								(size 1.27 1.27)
							)
						)
					)
				)
				(pin output line
					(at 17.78 -5.08 180)
					(length 2.54)
					(name "STAT"
						(effects
							(font
								(size 1.27 1.27)
							)
						)
					)
					(number "4"
						(effects
							(font
								(size 1.27 1.27)
							)
						)
					)
				)
			)
		)
	(symbol "antmicroPMICPowerSequencers:LM3880"
			(exclude_from_sim no)
			(in_bom yes)
			(on_board yes)
			(property "Reference" "U"
				(at 25.4 -5.08 0)
				(effects
					(font
						(size 1.27 1.27)
						(thickness 0.15)
					)
					(justify left bottom)
				)
			)
			(property "Value" "LM3880"
				(at 25.4 -7.62 0)
				(effects
					(font
						(size 1.27 1.27)
						(thickness 0.15)
					)
					(justify left bottom)
				)
			)
			(property "Footprint" "antmicro-footprints:SOT-23-6"
				(at 25.4 -10.16 0)
				(effects
					(font
						(size 1.27 1.27)
						(thickness 0.15)
					)
					(justify left bottom)
					(hide yes)
				)
			)
			(property "Datasheet" "http://www.ti.com/lit/ds/symlink/lm3880.pdf"
				(at 25.4 -12.7 0)
				(effects
					(font
						(size 1.27 1.27)
						(thickness 0.15)
					)
					(justify left bottom)
					(hide yes)
				)
			)
			(property "Description" "Power sequencer"
				(at 0 0 0)
				(effects
					(font
						(size 1.27 1.27)
					)
					(hide yes)
				)
			)
			(property "Manufacturer" "Texas Instruments"
				(at 25.4 -15.24 0)
				(effects
					(font
						(size 1.27 1.27)
						(thickness 0.15)
					)
					(justify left bottom)
					(hide yes)
				)
			)
			(property "MPN" "LM3880MFX-1AA/NOPB"
				(at 25.4 -17.78 0)
				(effects
					(font
						(size 1.27 1.27)
						(thickness 0.15)
					)
					(justify left bottom)
					(hide yes)
				)
			)
			(property "Author" "Antmicro"
				(at 25.4 -20.32 0)
				(effects
					(font
						(size 1.27 1.27)
						(thickness 0.15)
					)
					(justify left bottom)
					(hide yes)
				)
			)
			(property "License" "Apache-2.0"
				(at 25.4 -22.86 0)
				(effects
					(font
						(size 1.27 1.27)
						(thickness 0.15)
					)
					(justify left bottom)
					(hide yes)
				)
			)
			(property "ki_keywords" "SMT, PMIC, IC, POWER, SEQUENCER"
				(at 0 0 0)
				(effects
					(font
						(size 1.27 1.27)
					)
					(hide yes)
				)
			)
			(property "ki_fp_filters" "SOT?23*"
				(at 0 0 0)
				(effects
					(font
						(size 1.27 1.27)
					)
					(hide yes)
				)
			)
			(symbol "LM3880_1_1"
				(rectangle
					(start -7.62 -2.54)
					(end 7.62 -12.7)
					(stroke
						(width 0.254)
						(type default)
					)
					(fill
						(type background)
					)
				)
				(pin input line
					(at -10.16 -7.62 0)
					(length 2.54)
					(name "EN"
						(effects
							(font
								(size 1.27 1.27)
							)
						)
					)
					(number "3"
						(effects
							(font
								(size 1.27 1.27)
							)
						)
					)
				)
				(pin power_in line
					(at 0 0 270)
					(length 2.54)
					(name "VCC"
						(effects
							(font
								(size 1.27 1.27)
							)
						)
					)
					(number "1"
						(effects
							(font
								(size 1.27 1.27)
							)
						)
					)
				)
				(pin power_in line
					(at 0 -15.24 90)
					(length 2.54)
					(name "GND"
						(effects
							(font
								(size 1.27 1.27)
							)
						)
					)
					(number "2"
						(effects
							(font
								(size 1.27 1.27)
							)
						)
					)
				)
				(pin open_collector line
					(at 10.16 -5.08 180)
					(length 2.54)
					(name "FLAG1"
						(effects
							(font
								(size 1.27 1.27)
							)
						)
					)
					(number "6"
						(effects
							(font
								(size 1.27 1.27)
							)
						)
					)
				)
				(pin open_collector line
					(at 10.16 -7.62 180)
					(length 2.54)
					(name "FLAG2"
						(effects
							(font
								(size 1.27 1.27)
							)
						)
					)
					(number "5"
						(effects
							(font
								(size 1.27 1.27)
							)
						)
					)
				)
				(pin open_collector line
					(at 10.16 -10.16 180)
					(length 2.54)
					(name "FLAG3"
						(effects
							(font
								(size 1.27 1.27)
							)
						)
					)
					(number "4"
						(effects
							(font
								(size 1.27 1.27)
							)
						)
					)
				)
			)
		)
	(symbol "antmicroPMICPowerSequencers:MAX16150A_SOT"
			(exclude_from_sim no)
			(in_bom yes)
			(on_board yes)
			(property "Reference" "U"
				(at 31.75 -3.81 0)
				(effects
					(font
						(size 1.27 1.27)
						(thickness 0.15)
					)
					(justify left bottom)
				)
			)
			(property "Value" "MAX16150A_SOT"
				(at 31.75 -6.35 0)
				(effects
					(font
						(size 1.27 1.27)
						(thickness 0.15)
					)
					(justify left bottom)
				)
			)
			(property "Footprint" "antmicro-footprints:SOT-23-6"
				(at 31.75 -8.89 0)
				(effects
					(font
						(size 1.27 1.27)
						(thickness 0.15)
					)
					(justify left bottom)
					(hide yes)
				)
			)
			(property "Datasheet" "https://datasheets.maximintegrated.com/en/ds/MAX16150.pdf"
				(at 31.75 -11.43 0)
				(effects
					(font
						(size 1.27 1.27)
						(thickness 0.15)
					)
					(justify left bottom)
					(hide yes)
				)
			)
			(property "Description" "Push Button On/Off Controller, Latched Output, 1.3 to 5.5 V Supply, 50 ms Debounce Time, SOT-23-6"
				(at 0 0 0)
				(effects
					(font
						(size 1.27 1.27)
					)
					(hide yes)
				)
			)
			(property "Manufacturer" "Maxim Integrated Products"
				(at 31.75 -13.97 0)
				(effects
					(font
						(size 1.27 1.27)
						(thickness 0.15)
					)
					(justify left bottom)
					(hide yes)
				)
			)
			(property "MPN" "MAX16150AUT+T"
				(at 31.75 -16.51 0)
				(effects
					(font
						(size 1.27 1.27)
						(thickness 0.15)
					)
					(justify left bottom)
					(hide yes)
				)
			)
			(property "License" "Apache-2.0"
				(at 31.75 -19.05 0)
				(effects
					(font
						(size 1.27 1.27)
						(thickness 0.15)
					)
					(justify left bottom)
					(hide yes)
				)
			)
			(property "Author" "Antmicro"
				(at 31.75 -21.59 0)
				(effects
					(font
						(size 1.27 1.27)
						(thickness 0.15)
					)
					(justify left bottom)
					(hide yes)
				)
			)
			(property "ki_keywords" "SMT, PMIC, IC, CONTROLLER, ESD"
				(at 0 0 0)
				(effects
					(font
						(size 1.27 1.27)
					)
					(hide yes)
				)
			)
			(symbol "MAX16150A_SOT_0_0"
				(text "CTRL"
					(at 8.89 -0.254 0)
					(effects
						(font
							(size 0.635 0.635)
						)
					)
				)
			)
			(symbol "MAX16150A_SOT_1_1"
				(rectangle
					(start 2.54 2.54)
					(end 15.24 -7.62)
					(stroke
						(width 0.254)
						(type default)
					)
					(fill
						(type background)
					)
				)
				(polyline
					(pts
						(xy 6.35 -3.429) (xy 7.112 -3.429)
					)
					(stroke
						(width 0.254)
						(type default)
					)
					(fill
						(type background)
					)
				)
				(polyline
					(pts
						(xy 7.112 -2.54) (xy 10.668 -2.54)
					)
					(stroke
						(width 0.254)
						(type default)
					)
					(fill
						(type background)
					)
				)
				(circle
					(center 7.366 -3.429)
					(radius 0.254)
					(stroke
						(width 0.254)
						(type default)
					)
					(fill
						(type outline)
					)
				)
				(polyline
					(pts
						(xy 7.874 -1.016) (xy 9.906 -1.016)
					)
					(stroke
						(width 0.254)
						(type default)
					)
					(fill
						(type background)
					)
				)
				(polyline
					(pts
						(xy 8.89 -2.54) (xy 8.89 -1.016)
					)
					(stroke
						(width 0.254)
						(type default)
					)
					(fill
						(type background)
					)
				)
				(circle
					(center 10.414 -3.429)
					(radius 0.254)
					(stroke
						(width 0.254)
						(type default)
					)
					(fill
						(type outline)
					)
				)
				(polyline
					(pts
						(xy 11.43 -3.429) (xy 10.668 -3.429)
					)
					(stroke
						(width 0.254)
						(type default)
					)
					(fill
						(type background)
					)
				)
				(pin power_in line
					(at 0 0 0)
					(length 2.54)
					(name "VCC"
						(effects
							(font
								(size 1.27 1.27)
							)
						)
					)
					(number "3"
						(effects
							(font
								(size 1.27 1.27)
							)
						)
					)
				)
				(pin input line
					(at 0 -2.54 0)
					(length 2.54)
					(name "~{CLR}"
						(effects
							(font
								(size 1.27 1.27)
							)
						)
					)
					(number "6"
						(effects
							(font
								(size 1.27 1.27)
							)
						)
					)
				)
				(pin input line
					(at 0 -5.08 0)
					(length 2.54)
					(name "~{PB_IN}"
						(effects
							(font
								(size 1.27 1.27)
							)
						)
					)
					(number "1"
						(effects
							(font
								(size 1.27 1.27)
							)
						)
					)
				)
				(pin output line
					(at 17.78 0 180)
					(length 2.54)
					(name "OUT"
						(effects
							(font
								(size 1.27 1.27)
							)
						)
					)
					(number "4"
						(effects
							(font
								(size 1.27 1.27)
							)
						)
					)
				)
				(pin output line
					(at 17.78 -2.54 180)
					(length 2.54)
					(name "~{INT}"
						(effects
							(font
								(size 1.27 1.27)
							)
						)
					)
					(number "5"
						(effects
							(font
								(size 1.27 1.27)
							)
						)
					)
				)
				(pin power_in line
					(at 17.78 -5.08 180)
					(length 2.54)
					(name "GND"
						(effects
							(font
								(size 1.27 1.27)
							)
						)
					)
					(number "2"
						(effects
							(font
								(size 1.27 1.27)
							)
						)
					)
				)
			)
		)
	(symbol "antmicroPMICPowerSequencers:MAX812REUS+T"
			(exclude_from_sim no)
			(in_bom yes)
			(on_board yes)
			(property "Reference" "U"
				(at 30.48 -2.54 0)
				(effects
					(font
						(size 1.27 1.27)
						(thickness 0.15)
					)
					(justify left bottom)
				)
			)
			(property "Value" "MAX812REUS+T"
				(at 30.48 -5.08 0)
				(effects
					(font
						(size 1.27 1.27)
						(thickness 0.15)
					)
					(justify left bottom)
				)
			)
			(property "Footprint" "antmicro-footprints:SOT-143-4"
				(at 30.48 -7.62 0)
				(effects
					(font
						(size 1.27 1.27)
						(thickness 0.15)
					)
					(justify left bottom)
					(hide yes)
				)
			)
			(property "Datasheet" "https://datasheets.maximintegrated.com/en/ds/MAX811-MAX812T.pdf"
				(at 30.48 -10.16 0)
				(effects
					(font
						(size 1.27 1.27)
						(thickness 0.15)
					)
					(justify left bottom)
					(hide yes)
				)
			)
			(property "Description" "Voltage monitor"
				(at 0 0 0)
				(effects
					(font
						(size 1.27 1.27)
					)
					(hide yes)
				)
			)
			(property "Manufacturer" "Maxim Integrated Products"
				(at 30.48 -12.7 0)
				(effects
					(font
						(size 1.27 1.27)
						(thickness 0.15)
					)
					(justify left bottom)
					(hide yes)
				)
			)
			(property "MPN" "MAX812REUS+T"
				(at 30.48 -15.24 0)
				(effects
					(font
						(size 1.27 1.27)
						(thickness 0.15)
					)
					(justify left bottom)
					(hide yes)
				)
			)
			(property "License" "Apache-2.0"
				(at 30.48 -17.78 0)
				(effects
					(font
						(size 1.27 1.27)
						(thickness 0.15)
					)
					(justify left bottom)
					(hide yes)
				)
			)
			(property "Author" "Antmicro"
				(at 30.48 -20.32 0)
				(effects
					(font
						(size 1.27 1.27)
						(thickness 0.15)
					)
					(justify left bottom)
					(hide yes)
				)
			)
			(property "ki_keywords" "SMT, PMIC, IC, VOLTAGE, MONITOR"
				(at 0 0 0)
				(effects
					(font
						(size 1.27 1.27)
					)
					(hide yes)
				)
			)
			(symbol "MAX812REUS+T_1_1"
				(rectangle
					(start 2.54 2.54)
					(end 12.7 -7.62)
					(stroke
						(width 0.254)
						(type default)
					)
					(fill
						(type background)
					)
				)
				(pin power_in line
					(at 0 0 0)
					(length 2.54)
					(name "VCC"
						(effects
							(font
								(size 1.27 1.27)
							)
						)
					)
					(number "4"
						(effects
							(font
								(size 1.27 1.27)
							)
						)
					)
				)
				(pin input line
					(at 0 -2.54 0)
					(length 2.54)
					(name "~{MR}"
						(effects
							(font
								(size 1.27 1.27)
							)
						)
					)
					(number "3"
						(effects
							(font
								(size 1.27 1.27)
							)
						)
					)
				)
				(pin power_in line
					(at 0 -5.08 0)
					(length 2.54)
					(name "GND"
						(effects
							(font
								(size 1.27 1.27)
							)
						)
					)
					(number "1"
						(effects
							(font
								(size 1.27 1.27)
							)
						)
					)
				)
				(pin output line
					(at 15.24 -2.54 180)
					(length 2.54)
					(name "~{RST}"
						(effects
							(font
								(size 1.27 1.27)
							)
						)
					)
					(number "2"
						(effects
							(font
								(size 1.27 1.27)
							)
						)
					)
				)
			)
		)
	(symbol "antmicroPMICVoltageRegulatorsDCDCSwitchingRegulators:MP8869S"
			(exclude_from_sim no)
			(in_bom yes)
			(on_board yes)
			(property "Reference" "U"
				(at 25.4 -6.35 0)
				(effects
					(font
						(size 1.27 1.27)
						(thickness 0.15)
					)
					(justify left bottom)
				)
			)
			(property "Value" "MP8869S"
				(at 25.4 -8.89 0)
				(effects
					(font
						(size 1.27 1.27)
						(thickness 0.15)
					)
					(justify left bottom)
				)
			)
			(property "Footprint" "antmicro-footprints:MPS_QFN-14_MP8869S"
				(at 25.4 -11.43 0)
				(effects
					(font
						(size 1.27 1.27)
						(thickness 0.15)
					)
					(justify left bottom)
					(hide yes)
				)
			)
			(property "Datasheet" "https://www.mouser.com/datasheet/2/277/MP8869S-2946178.pdf"
				(at 25.4 -13.97 0)
				(effects
					(font
						(size 1.27 1.27)
						(thickness 0.15)
					)
					(justify left bottom)
					(hide yes)
				)
			)
			(property "Description" "DC-DC Switching Synchronous Buck Regulator, 2.85V-18V in, 600mV to 5.5V out, 12A, 500kHz, QFN-14"
				(at 0 0 0)
				(effects
					(font
						(size 1.27 1.27)
					)
					(hide yes)
				)
			)
			(property "MPN" "MP8869SGL-P"
				(at 25.4 -16.51 0)
				(effects
					(font
						(size 1.27 1.27)
						(thickness 0.15)
					)
					(justify left bottom)
					(hide yes)
				)
			)
			(property "Manufacturer" "Monolithic Power Systems"
				(at 25.4 -19.05 0)
				(effects
					(font
						(size 1.27 1.27)
						(thickness 0.15)
					)
					(justify left bottom)
					(hide yes)
				)
			)
			(property "Author" "Antmicro"
				(at 25.4 -21.59 0)
				(effects
					(font
						(size 1.27 1.27)
						(thickness 0.15)
					)
					(justify left bottom)
					(hide yes)
				)
			)
			(property "License" "Apache-2.0"
				(at 25.4 -24.13 0)
				(effects
					(font
						(size 1.27 1.27)
						(thickness 0.15)
					)
					(justify left bottom)
					(hide yes)
				)
			)
			(property "ki_keywords" "SMT, PMIC, IC, VOLTAGE, REGULATOR, SWITCHING, DC-DC"
				(at 0 0 0)
				(effects
					(font
						(size 1.27 1.27)
					)
					(hide yes)
				)
			)
			(property "ki_fp_filters" "QFN-14_MP8869S_MNP"
				(at 0 0 0)
				(effects
					(font
						(size 1.27 1.27)
					)
					(hide yes)
				)
			)
			(symbol "MP8869S_1_1"
				(rectangle
					(start -7.62 -2.54)
					(end 7.62 -30.48)
					(stroke
						(width 0.254)
						(type default)
					)
					(fill
						(type background)
					)
				)
				(pin power_in line
					(at -10.16 -5.08 0)
					(length 2.54)
					(name "VIN"
						(effects
							(font
								(size 1.27 1.27)
							)
						)
					)
					(number "9"
						(effects
							(font
								(size 1.27 1.27)
							)
						)
					)
				)
				(pin unspecified line
					(at -10.16 -10.16 0)
					(length 2.54)
					(name "EN"
						(effects
							(font
								(size 1.27 1.27)
							)
						)
					)
					(number "5"
						(effects
							(font
								(size 1.27 1.27)
							)
						)
					)
				)
				(pin power_out line
					(at -10.16 -12.7 0)
					(length 2.54)
					(name "VCC"
						(effects
							(font
								(size 1.27 1.27)
							)
						)
					)
					(number "13"
						(effects
							(font
								(size 1.27 1.27)
							)
						)
					)
				)
				(pin unspecified line
					(at -10.16 -19.05 0)
					(length 2.54)
					(name "PG"
						(effects
							(font
								(size 1.27 1.27)
							)
						)
					)
					(number "7"
						(effects
							(font
								(size 1.27 1.27)
							)
						)
					)
				)
				(pin unspecified line
					(at -10.16 -22.86 0)
					(length 2.54)
					(name "SDA"
						(effects
							(font
								(size 1.27 1.27)
							)
						)
					)
					(number "4"
						(effects
							(font
								(size 1.27 1.27)
							)
						)
					)
				)
				(pin unspecified line
					(at -10.16 -25.4 0)
					(length 2.54)
					(name "SCL"
						(effects
							(font
								(size 1.27 1.27)
							)
						)
					)
					(number "3"
						(effects
							(font
								(size 1.27 1.27)
							)
						)
					)
				)
				(pin unspecified line
					(at -10.16 -27.94 0)
					(length 2.54)
					(name "A0"
						(effects
							(font
								(size 1.27 1.27)
							)
						)
					)
					(number "6"
						(effects
							(font
								(size 1.27 1.27)
							)
						)
					)
				)
				(pin power_in line
					(at -1.27 -33.02 90)
					(length 2.54)
					(name "AGND"
						(effects
							(font
								(size 1.27 1.27)
							)
						)
					)
					(number "14"
						(effects
							(font
								(size 1.27 1.27)
							)
						)
					)
				)
				(pin unspecified line
					(at 0 0 270)
					(length 2.54)
					(name "BST"
						(effects
							(font
								(size 1.27 1.27)
							)
						)
					)
					(number "1"
						(effects
							(font
								(size 1.27 1.27)
							)
						)
					)
				)
				(pin power_in line
					(at 1.27 -33.02 90)
					(length 2.54)
					(name "PGND"
						(effects
							(font
								(size 1.27 1.27)
							)
						)
					)
					(number "8"
						(effects
							(font
								(size 1.27 1.27)
							)
						)
					)
				)
				(pin output line
					(at 10.16 -5.08 180)
					(length 2.54)
					(name "SW"
						(effects
							(font
								(size 1.27 1.27)
							)
						)
					)
					(number "2"
						(effects
							(font
								(size 1.27 1.27)
							)
						)
					)
				)
				(pin unspecified line
					(at 10.16 -12.7 180)
					(length 2.54)
					(name "VOUT"
						(effects
							(font
								(size 1.27 1.27)
							)
						)
					)
					(number "10"
						(effects
							(font
								(size 1.27 1.27)
							)
						)
					)
				)
				(pin unspecified line
					(at 10.16 -20.32 180)
					(length 2.54)
					(name "FB"
						(effects
							(font
								(size 1.27 1.27)
							)
						)
					)
					(number "11"
						(effects
							(font
								(size 1.27 1.27)
							)
						)
					)
				)
				(pin unspecified line
					(at 10.16 -27.94 180)
					(length 2.54)
					(name "SS"
						(effects
							(font
								(size 1.27 1.27)
							)
						)
					)
					(number "12"
						(effects
							(font
								(size 1.27 1.27)
							)
						)
					)
				)
			)
		)
	(symbol "antmicroPMICVoltageRegulatorsDCDCSwitchingRegulators:MPM54304GMN"
			(exclude_from_sim no)
			(in_bom yes)
			(on_board yes)
			(property "Reference" "U"
				(at 46.99 -2.54 0)
				(effects
					(font
						(size 1.27 1.27)
						(thickness 0.15)
					)
					(justify left bottom)
				)
			)
			(property "Value" "MPM54304GMN"
				(at 46.99 -5.08 0)
				(effects
					(font
						(size 1.27 1.27)
						(thickness 0.15)
					)
					(justify left bottom)
				)
			)
			(property "Footprint" "antmicro-footprints:LGA-33_7x7mm_P0.65mm"
				(at 46.99 -7.62 0)
				(effects
					(font
						(size 1.27 1.27)
						(thickness 0.15)
					)
					(justify left bottom)
					(hide yes)
				)
			)
			(property "Datasheet" "https://www.monolithicpower.com/en/documentview/productdocument/index/version/2/document_type/Datasheet/lang/en/sku/MPM54304/document_id/4982/"
				(at 46.99 -10.16 0)
				(effects
					(font
						(size 1.27 1.27)
						(thickness 0.15)
					)
					(justify left bottom)
					(hide yes)
				)
			)
			(property "Description" "DC-DC Switching Synchronous Step-Down Regulator, Multi Output, 4-16V in, 1V/3.3V, 4.2/3A out, LGA33"
				(at 0 0 0)
				(effects
					(font
						(size 1.27 1.27)
					)
					(hide yes)
				)
			)
			(property "MPN" "MPM54304GMN-0000"
				(at 46.99 -12.7 0)
				(effects
					(font
						(size 1.27 1.27)
						(thickness 0.15)
					)
					(justify left bottom)
					(hide yes)
				)
			)
			(property "Manufacturer" "Monolithic Power Systems"
				(at 46.99 -15.24 0)
				(effects
					(font
						(size 1.27 1.27)
						(thickness 0.15)
					)
					(justify left bottom)
					(hide yes)
				)
			)
			(property "Author" "Antmicro"
				(at 46.99 -17.78 0)
				(effects
					(font
						(size 1.27 1.27)
						(thickness 0.15)
					)
					(justify left bottom)
					(hide yes)
				)
			)
			(property "License" "Apache-2.0"
				(at 46.99 -20.32 0)
				(effects
					(font
						(size 1.27 1.27)
						(thickness 0.15)
					)
					(justify left bottom)
					(hide yes)
				)
			)
			(property "ki_keywords" "SMT, PMIC, IC, VOLTAGE, REGULATOR, SWITCHING, DC-DC"
				(at 0 0 0)
				(effects
					(font
						(size 1.27 1.27)
					)
					(hide yes)
				)
			)
			(property "ki_fp_filters" "CP_48_13_ADI CP_48_13_ADI-M CP_48_13_ADI-L"
				(at 0 0 0)
				(effects
					(font
						(size 1.27 1.27)
					)
					(hide yes)
				)
			)
			(symbol "MPM54304GMN_1_1"
				(rectangle
					(start 2.54 3.81)
					(end 2.54 3.81)
					(stroke
						(width 0.254)
						(type default)
					)
					(fill
						(type background)
					)
				)
				(rectangle
					(start 2.54 2.54)
					(end 25.4 -38.1)
					(stroke
						(width 0.254)
						(type default)
					)
					(fill
						(type background)
					)
				)
				(polyline
					(pts
						(xy 25.4 1.27) (xy 17.78 1.27) (xy 17.78 -8.89) (xy 25.4 -8.89)
					)
					(stroke
						(width 0.254)
						(type default)
					)
					(fill
						(type background)
					)
				)
				(polyline
					(pts
						(xy 25.4 -11.43) (xy 17.78 -11.43) (xy 17.78 -19.05) (xy 25.4 -19.05)
					)
					(stroke
						(width 0.254)
						(type default)
					)
					(fill
						(type background)
					)
				)
				(polyline
					(pts
						(xy 25.4 -21.59) (xy 17.78 -21.59) (xy 17.78 -29.21) (xy 25.4 -29.21)
					)
					(stroke
						(width 0.254)
						(type default)
					)
					(fill
						(type background)
					)
				)
				(polyline
					(pts
						(xy 25.4 -31.75) (xy 17.78 -31.75) (xy 17.78 -36.83) (xy 25.4 -36.83)
					)
					(stroke
						(width 0.254)
						(type default)
					)
					(fill
						(type background)
					)
				)
				(pin input line
					(at 0 0 0)
					(length 2.54)
					(name "VIN"
						(effects
							(font
								(size 1.27 1.27)
							)
						)
					)
					(number "28"
						(effects
							(font
								(size 1.27 1.27)
							)
						)
					)
				)
				(pin passive line
					(at 0 0 0)
					(length 2.54)
					(hide yes)
					(name "VIN"
						(effects
							(font
								(size 1.27 1.27)
							)
						)
					)
					(number "29"
						(effects
							(font
								(size 1.27 1.27)
							)
						)
					)
				)
				(pin input line
					(at 0 -2.54 0)
					(length 2.54)
					(name "VCC"
						(effects
							(font
								(size 1.27 1.27)
							)
						)
					)
					(number "25"
						(effects
							(font
								(size 1.27 1.27)
							)
						)
					)
				)
				(pin input line
					(at 0 -10.16 0)
					(length 2.54)
					(name "EN/SYNCI"
						(effects
							(font
								(size 1.27 1.27)
							)
						)
					)
					(number "19"
						(effects
							(font
								(size 1.27 1.27)
							)
						)
					)
				)
				(pin bidirectional line
					(at 0 -19.05 0)
					(length 2.54)
					(name "SDA"
						(effects
							(font
								(size 1.27 1.27)
							)
						)
					)
					(number "3"
						(effects
							(font
								(size 1.27 1.27)
							)
						)
					)
				)
				(pin input line
					(at 0 -21.59 0)
					(length 2.54)
					(name "SCL"
						(effects
							(font
								(size 1.27 1.27)
							)
						)
					)
					(number "4"
						(effects
							(font
								(size 1.27 1.27)
							)
						)
					)
				)
				(pin input line
					(at 0 -30.48 0)
					(length 2.54)
					(name "GPIO"
						(effects
							(font
								(size 1.27 1.27)
							)
						)
					)
					(number "26"
						(effects
							(font
								(size 1.27 1.27)
							)
						)
					)
				)
				(pin passive line
					(at 0 -35.56 0)
					(length 2.54)
					(name "GND"
						(effects
							(font
								(size 1.27 1.27)
							)
						)
					)
					(number "10"
						(effects
							(font
								(size 1.27 1.27)
							)
						)
					)
				)
				(pin passive line
					(at 0 -35.56 0)
					(length 2.54)
					(hide yes)
					(name "GND"
						(effects
							(font
								(size 1.27 1.27)
							)
						)
					)
					(number "13"
						(effects
							(font
								(size 1.27 1.27)
							)
						)
					)
				)
				(pin passive line
					(at 0 -35.56 0)
					(length 2.54)
					(hide yes)
					(name "GND"
						(effects
							(font
								(size 1.27 1.27)
							)
						)
					)
					(number "16"
						(effects
							(font
								(size 1.27 1.27)
							)
						)
					)
				)
				(pin passive line
					(at 0 -35.56 0)
					(length 2.54)
					(hide yes)
					(name "GND"
						(effects
							(font
								(size 1.27 1.27)
							)
						)
					)
					(number "2"
						(effects
							(font
								(size 1.27 1.27)
							)
						)
					)
				)
				(pin passive line
					(at 0 -35.56 0)
					(length 2.54)
					(hide yes)
					(name "GND"
						(effects
							(font
								(size 1.27 1.27)
							)
						)
					)
					(number "20"
						(effects
							(font
								(size 1.27 1.27)
							)
						)
					)
				)
				(pin passive line
					(at 0 -35.56 0)
					(length 2.54)
					(hide yes)
					(name "GND"
						(effects
							(font
								(size 1.27 1.27)
							)
						)
					)
					(number "21"
						(effects
							(font
								(size 1.27 1.27)
							)
						)
					)
				)
				(pin passive line
					(at 0 -35.56 0)
					(length 2.54)
					(hide yes)
					(name "GND"
						(effects
							(font
								(size 1.27 1.27)
							)
						)
					)
					(number "27"
						(effects
							(font
								(size 1.27 1.27)
							)
						)
					)
				)
				(pin passive line
					(at 0 -35.56 0)
					(length 2.54)
					(hide yes)
					(name "GND"
						(effects
							(font
								(size 1.27 1.27)
							)
						)
					)
					(number "33"
						(effects
							(font
								(size 1.27 1.27)
							)
						)
					)
				)
				(pin passive line
					(at 0 -35.56 0)
					(length 2.54)
					(hide yes)
					(name "GND"
						(effects
							(font
								(size 1.27 1.27)
							)
						)
					)
					(number "5"
						(effects
							(font
								(size 1.27 1.27)
							)
						)
					)
				)
				(pin passive line
					(at 0 -35.56 0)
					(length 2.54)
					(hide yes)
					(name "GND"
						(effects
							(font
								(size 1.27 1.27)
							)
						)
					)
					(number "7"
						(effects
							(font
								(size 1.27 1.27)
							)
						)
					)
				)
				(pin power_out line
					(at 27.94 0 180)
					(length 2.54)
					(name "VOUT1"
						(effects
							(font
								(size 1.27 1.27)
							)
						)
					)
					(number "14"
						(effects
							(font
								(size 1.27 1.27)
							)
						)
					)
				)
				(pin passive line
					(at 27.94 0 180)
					(length 2.54)
					(hide yes)
					(name "VOUT1"
						(effects
							(font
								(size 1.27 1.27)
							)
						)
					)
					(number "15"
						(effects
							(font
								(size 1.27 1.27)
							)
						)
					)
				)
				(pin power_out line
					(at 27.94 -2.54 180)
					(length 2.54)
					(name "SW1"
						(effects
							(font
								(size 1.27 1.27)
							)
						)
					)
					(number "12"
						(effects
							(font
								(size 1.27 1.27)
							)
						)
					)
				)
				(pin input line
					(at 27.94 -5.08 180)
					(length 2.54)
					(name "FB1"
						(effects
							(font
								(size 1.27 1.27)
							)
						)
					)
					(number "18"
						(effects
							(font
								(size 1.27 1.27)
							)
						)
					)
				)
				(pin power_out line
					(at 27.94 -7.62 180)
					(length 2.54)
					(name "SGND1"
						(effects
							(font
								(size 1.27 1.27)
							)
						)
					)
					(number "17"
						(effects
							(font
								(size 1.27 1.27)
							)
						)
					)
				)
				(pin power_out line
					(at 27.94 -12.7 180)
					(length 2.54)
					(name "VOUT2"
						(effects
							(font
								(size 1.27 1.27)
							)
						)
					)
					(number "8"
						(effects
							(font
								(size 1.27 1.27)
							)
						)
					)
				)
				(pin passive line
					(at 27.94 -12.7 180)
					(length 2.54)
					(hide yes)
					(name "VOUT2"
						(effects
							(font
								(size 1.27 1.27)
							)
						)
					)
					(number "9"
						(effects
							(font
								(size 1.27 1.27)
							)
						)
					)
				)
				(pin power_out line
					(at 27.94 -15.24 180)
					(length 2.54)
					(name "SW2"
						(effects
							(font
								(size 1.27 1.27)
							)
						)
					)
					(number "11"
						(effects
							(font
								(size 1.27 1.27)
							)
						)
					)
				)
				(pin input line
					(at 27.94 -17.78 180)
					(length 2.54)
					(name "FB2"
						(effects
							(font
								(size 1.27 1.27)
							)
						)
					)
					(number "6"
						(effects
							(font
								(size 1.27 1.27)
							)
						)
					)
				)
				(pin power_out line
					(at 27.94 -22.86 180)
					(length 2.54)
					(name "VOUT3"
						(effects
							(font
								(size 1.27 1.27)
							)
						)
					)
					(number "1"
						(effects
							(font
								(size 1.27 1.27)
							)
						)
					)
				)
				(pin passive line
					(at 27.94 -22.86 180)
					(length 2.54)
					(hide yes)
					(name "VOUT3"
						(effects
							(font
								(size 1.27 1.27)
							)
						)
					)
					(number "32"
						(effects
							(font
								(size 1.27 1.27)
							)
						)
					)
				)
				(pin input line
					(at 27.94 -25.4 180)
					(length 2.54)
					(name "FB3"
						(effects
							(font
								(size 1.27 1.27)
							)
						)
					)
					(number "31"
						(effects
							(font
								(size 1.27 1.27)
							)
						)
					)
				)
				(pin power_out line
					(at 27.94 -27.94 180)
					(length 2.54)
					(name "SGND2"
						(effects
							(font
								(size 1.27 1.27)
							)
						)
					)
					(number "30"
						(effects
							(font
								(size 1.27 1.27)
							)
						)
					)
				)
				(pin power_out line
					(at 27.94 -33.02 180)
					(length 2.54)
					(name "VOUT4"
						(effects
							(font
								(size 1.27 1.27)
							)
						)
					)
					(number "22"
						(effects
							(font
								(size 1.27 1.27)
							)
						)
					)
				)
				(pin passive line
					(at 27.94 -33.02 180)
					(length 2.54)
					(hide yes)
					(name "VOUT4"
						(effects
							(font
								(size 1.27 1.27)
							)
						)
					)
					(number "23"
						(effects
							(font
								(size 1.27 1.27)
							)
						)
					)
				)
				(pin input line
					(at 27.94 -35.56 180)
					(length 2.54)
					(name "FB4"
						(effects
							(font
								(size 1.27 1.27)
							)
						)
					)
					(number "24"
						(effects
							(font
								(size 1.27 1.27)
							)
						)
					)
				)
			)
		)
	(symbol "antmicroPMICVoltageRegulatorsLinear:NCP718BSN330T1G"
			(exclude_from_sim no)
			(in_bom yes)
			(on_board yes)
			(property "Reference" "U"
				(at 35.56 -3.81 0)
				(effects
					(font
						(size 1.27 1.27)
						(thickness 0.15)
					)
					(justify left bottom)
				)
			)
			(property "Value" "NCP718BSN330T1G"
				(at 35.56 -6.35 0)
				(effects
					(font
						(size 1.27 1.27)
						(thickness 0.15)
					)
					(justify left bottom)
				)
			)
			(property "Footprint" "antmicro-footprints:SOT-23-5"
				(at 35.56 -8.89 0)
				(effects
					(font
						(size 1.27 1.27)
						(thickness 0.15)
					)
					(justify left bottom)
					(hide yes)
				)
			)
			(property "Datasheet" "https://www.mouser.com/datasheet/2/308/NCP718_D-1224359.pdf"
				(at 35.56 -11.43 0)
				(effects
					(font
						(size 1.27 1.27)
						(thickness 0.15)
					)
					(justify left bottom)
					(hide yes)
				)
			)
			(property "Description" "Linear Voltage Regulator IC Positive Fixed 1 Output 300mA TSOT-23-5"
				(at 0 0 0)
				(effects
					(font
						(size 1.27 1.27)
					)
					(hide yes)
				)
			)
			(property "MPN" "NCP718BSN330T1G"
				(at 35.56 -13.97 0)
				(effects
					(font
						(size 1.27 1.27)
						(thickness 0.15)
					)
					(justify left bottom)
					(hide yes)
				)
			)
			(property "Manufacturer" "ON Semiconductor"
				(at 35.56 -16.51 0)
				(effects
					(font
						(size 1.27 1.27)
						(thickness 0.15)
					)
					(justify left bottom)
					(hide yes)
				)
			)
			(property "Author" "Antmicro"
				(at 35.56 -19.05 0)
				(effects
					(font
						(size 1.27 1.27)
						(thickness 0.15)
					)
					(justify left bottom)
					(hide yes)
				)
			)
			(property "License" "Apache-2.0"
				(at 35.56 -21.59 0)
				(effects
					(font
						(size 1.27 1.27)
						(thickness 0.15)
					)
					(justify left bottom)
					(hide yes)
				)
			)
			(property "ki_keywords" "SMT, PMIC, IC, LDO, VOLTAGE, REGULATOR"
				(at 0 0 0)
				(effects
					(font
						(size 1.27 1.27)
					)
					(hide yes)
				)
			)
			(symbol "NCP718BSN330T1G_1_1"
				(rectangle
					(start 2.54 2.54)
					(end 17.78 -5.08)
					(stroke
						(width 0.254)
						(type default)
					)
					(fill
						(type background)
					)
				)
				(pin passive line
					(at 0 0 0)
					(length 2.54)
					(name "VIN"
						(effects
							(font
								(size 1.27 1.27)
							)
						)
					)
					(number "1"
						(effects
							(font
								(size 1.27 1.27)
							)
						)
					)
				)
				(pin passive line
					(at 0 -2.54 0)
					(length 2.54)
					(name "EN"
						(effects
							(font
								(size 1.27 1.27)
							)
						)
					)
					(number "3"
						(effects
							(font
								(size 1.27 1.27)
							)
						)
					)
				)
				(pin no_connect line
					(at 10.16 -5.08 90)
					(length 2.54)
					(hide yes)
					(name "NC"
						(effects
							(font
								(size 1.27 1.27)
							)
						)
					)
					(number "4"
						(effects
							(font
								(size 1.27 1.27)
							)
						)
					)
				)
				(pin passive line
					(at 20.32 0 180)
					(length 2.54)
					(name "VOUT"
						(effects
							(font
								(size 1.27 1.27)
							)
						)
					)
					(number "5"
						(effects
							(font
								(size 1.27 1.27)
							)
						)
					)
				)
				(pin passive line
					(at 20.32 -2.54 180)
					(length 2.54)
					(name "GND"
						(effects
							(font
								(size 1.27 1.27)
							)
						)
					)
					(number "2"
						(effects
							(font
								(size 1.27 1.27)
							)
						)
					)
				)
			)
		)
	(symbol "antmicroPMICVoltageRegulatorsLinear:XC6230H001ER-G"
			(exclude_from_sim no)
			(in_bom yes)
			(on_board yes)
			(property "Reference" "U"
				(at 30.48 -2.54 0)
				(effects
					(font
						(size 1.27 1.27)
						(thickness 0.15)
					)
					(justify left bottom)
				)
			)
			(property "Value" "XC6230H001ER-G"
				(at 30.48 -5.08 0)
				(effects
					(font
						(size 1.27 1.27)
						(thickness 0.15)
					)
					(justify left bottom)
				)
			)
			(property "Footprint" "antmicro-footprints:Torex_USP-6C"
				(at 30.48 -7.62 0)
				(effects
					(font
						(size 1.27 1.27)
						(thickness 0.15)
					)
					(justify left bottom)
					(hide yes)
				)
			)
			(property "Datasheet" "https://www.torexsemi.com/file/xc6230/XC6230.pdf"
				(at 30.48 -10.16 0)
				(effects
					(font
						(size 1.27 1.27)
						(thickness 0.15)
					)
					(justify left bottom)
					(hide yes)
				)
			)
			(property "Description" "LDO Voltage Regulator, Adjustable, 1.7 V to 6 V in, 350 mV Drop, 1.188-1.212 V/2 A out, USP-6C-6"
				(at 0 0 0)
				(effects
					(font
						(size 1.27 1.27)
					)
					(hide yes)
				)
			)
			(property "MPN" "XC6230H001ER-G"
				(at 30.48 -12.7 0)
				(effects
					(font
						(size 1.27 1.27)
						(thickness 0.15)
					)
					(justify left bottom)
					(hide yes)
				)
			)
			(property "Manufacturer" "Torex Semiconductor"
				(at 30.48 -15.24 0)
				(effects
					(font
						(size 1.27 1.27)
						(thickness 0.15)
					)
					(justify left bottom)
					(hide yes)
				)
			)
			(property "Author" "Antmicro"
				(at 30.48 -17.78 0)
				(effects
					(font
						(size 1.27 1.27)
						(thickness 0.15)
					)
					(justify left bottom)
					(hide yes)
				)
			)
			(property "License" "Apache-2.0"
				(at 30.48 -20.32 0)
				(effects
					(font
						(size 1.27 1.27)
						(thickness 0.15)
					)
					(justify left bottom)
					(hide yes)
				)
			)
			(property "ki_keywords" "SMT, PMIC, IC, LDO, LINEAR, VOLTAGE, REGULATOR"
				(at 0 0 0)
				(effects
					(font
						(size 1.27 1.27)
					)
					(hide yes)
				)
			)
			(symbol "XC6230H001ER-G_1_1"
				(rectangle
					(start 2.54 2.54)
					(end 12.7 -7.62)
					(stroke
						(width 0.254)
						(type default)
					)
					(fill
						(type background)
					)
				)
				(pin power_out line
					(at 0 0 0)
					(length 2.54)
					(name "IN"
						(effects
							(font
								(size 1.27 1.27)
							)
						)
					)
					(number "6"
						(effects
							(font
								(size 1.27 1.27)
							)
						)
					)
				)
				(pin input line
					(at 0 -2.54 0)
					(length 2.54)
					(name "EN"
						(effects
							(font
								(size 1.27 1.27)
							)
						)
					)
					(number "4"
						(effects
							(font
								(size 1.27 1.27)
							)
						)
					)
				)
				(pin output line
					(at 0 -5.08 0)
					(length 2.54)
					(name "ILIM"
						(effects
							(font
								(size 1.27 1.27)
							)
						)
					)
					(number "2"
						(effects
							(font
								(size 1.27 1.27)
							)
						)
					)
				)
				(pin power_out line
					(at 15.24 0 180)
					(length 2.54)
					(name "OUT"
						(effects
							(font
								(size 1.27 1.27)
							)
						)
					)
					(number "1"
						(effects
							(font
								(size 1.27 1.27)
							)
						)
					)
				)
				(pin open_collector line
					(at 15.24 -2.54 180)
					(length 2.54)
					(name "FB"
						(effects
							(font
								(size 1.27 1.27)
							)
						)
					)
					(number "3"
						(effects
							(font
								(size 1.27 1.27)
							)
						)
					)
				)
				(pin power_in line
					(at 15.24 -5.08 180)
					(length 2.54)
					(name "GND"
						(effects
							(font
								(size 1.27 1.27)
							)
						)
					)
					(number "5"
						(effects
							(font
								(size 1.27 1.27)
							)
						)
					)
				)
				(pin passive line
					(at 15.24 -5.08 180)
					(length 2.54)
					(hide yes)
					(name "EP"
						(effects
							(font
								(size 1.27 1.27)
							)
						)
					)
					(number "7"
						(effects
							(font
								(size 1.27 1.27)
							)
						)
					)
				)
			)
		)
	(symbol "antmicroPciConnectors:Edge_Conn_Bus_PCIe_x4"
			(exclude_from_sim no)
			(in_bom no)
			(on_board yes)
			(property "Reference" "J"
				(at 48.26 -5.08 0)
				(effects
					(font
						(size 1.27 1.27)
						(thickness 0.15)
					)
					(justify left bottom)
				)
			)
			(property "Value" "Edge_Conn_Bus_PCIe_x4"
				(at 48.26 -7.62 0)
				(effects
					(font
						(size 1.27 1.27)
						(thickness 0.15)
					)
					(justify left bottom)
					(hide yes)
				)
			)
			(property "Footprint" "antmicro-footprints:Edge_Conn_Bus_PCIexpress_x4"
				(at 48.26 -10.16 0)
				(effects
					(font
						(size 1.27 1.27)
						(thickness 0.15)
					)
					(justify left bottom)
					(hide yes)
				)
			)
			(property "Datasheet" ""
				(at 48.26 -12.7 0)
				(effects
					(font
						(size 1.27 1.27)
						(thickness 0.15)
					)
					(justify left bottom)
					(hide yes)
				)
			)
			(property "Description" "PCIe x4 edge connector"
				(at 0 0 0)
				(effects
					(font
						(size 1.27 1.27)
					)
					(hide yes)
				)
			)
			(property "MPN" ""
				(at 48.26 -10.16 0)
				(effects
					(font
						(size 1.27 1.27)
						(thickness 0.15)
					)
					(justify left bottom)
				)
			)
			(property "Manufacturer" ""
				(at 48.26 -15.24 0)
				(effects
					(font
						(size 1.27 1.27)
						(thickness 0.15)
					)
					(justify left bottom)
					(hide yes)
				)
			)
			(property "Author" "Antmicro"
				(at 48.26 -12.7 0)
				(effects
					(font
						(size 1.27 1.27)
						(thickness 0.15)
					)
					(justify left bottom)
					(hide yes)
				)
			)
			(property "License" "Apache-2.0"
				(at 48.26 -15.24 0)
				(effects
					(font
						(size 1.27 1.27)
						(thickness 0.15)
					)
					(justify left bottom)
					(hide yes)
				)
			)
			(property "ki_keywords" "PCIE, CONNECTOR, EDGE"
				(at 0 0 0)
				(effects
					(font
						(size 1.27 1.27)
					)
					(hide yes)
				)
			)
			(symbol "Edge_Conn_Bus_PCIe_x4_1_1"
				(rectangle
					(start 3.81 2.54)
					(end 29.21 -64.77)
					(stroke
						(width 0.254)
						(type default)
					)
					(fill
						(type background)
					)
				)
				(polyline
					(pts
						(xy 29.21 -25.4) (xy 3.81 -25.4)
					)
					(stroke
						(width 0.254)
						(type default)
					)
					(fill
						(type background)
					)
				)
				(polyline
					(pts
						(xy 29.21 -41.91) (xy 3.81 -41.91)
					)
					(stroke
						(width 0.254)
						(type default)
					)
					(fill
						(type background)
					)
				)
				(text "PCIe_x1"
					(at 12.7 -41.91 0)
					(effects
						(font
							(size 1.27 1.27)
							(thickness 0.15)
						)
						(justify left bottom)
					)
				)
				(text "PCIe_x4"
					(at 12.7 -64.77 0)
					(effects
						(font
							(size 1.27 1.27)
							(thickness 0.15)
						)
						(justify left bottom)
					)
				)
				(pin power_out line
					(at 0 0 0)
					(length 3.81)
					(name "12V"
						(effects
							(font
								(size 1.27 1.27)
							)
						)
					)
					(number "A2"
						(effects
							(font
								(size 1.27 1.27)
							)
						)
					)
				)
				(pin passive line
					(at 0 0 0)
					(length 3.81)
					(hide yes)
					(name "12V"
						(effects
							(font
								(size 1.27 1.27)
							)
						)
					)
					(number "A3"
						(effects
							(font
								(size 1.27 1.27)
							)
						)
					)
				)
				(pin passive line
					(at 0 0 0)
					(length 3.81)
					(hide yes)
					(name "12V"
						(effects
							(font
								(size 1.27 1.27)
							)
						)
					)
					(number "B1"
						(effects
							(font
								(size 1.27 1.27)
							)
						)
					)
				)
				(pin passive line
					(at 0 0 0)
					(length 3.81)
					(hide yes)
					(name "12V"
						(effects
							(font
								(size 1.27 1.27)
							)
						)
					)
					(number "B2"
						(effects
							(font
								(size 1.27 1.27)
							)
						)
					)
				)
				(pin passive line
					(at 0 0 0)
					(length 3.81)
					(hide yes)
					(name "12V"
						(effects
							(font
								(size 1.27 1.27)
							)
						)
					)
					(number "B3"
						(effects
							(font
								(size 1.27 1.27)
							)
						)
					)
				)
				(pin power_out line
					(at 0 -2.54 0)
					(length 3.81)
					(name "3V3"
						(effects
							(font
								(size 1.27 1.27)
							)
						)
					)
					(number "A10"
						(effects
							(font
								(size 1.27 1.27)
							)
						)
					)
				)
				(pin passive line
					(at 0 -2.54 0)
					(length 3.81)
					(hide yes)
					(name "3V3"
						(effects
							(font
								(size 1.27 1.27)
							)
						)
					)
					(number "A9"
						(effects
							(font
								(size 1.27 1.27)
							)
						)
					)
				)
				(pin passive line
					(at 0 -2.54 0)
					(length 3.81)
					(hide yes)
					(name "3V3"
						(effects
							(font
								(size 1.27 1.27)
							)
						)
					)
					(number "B8"
						(effects
							(font
								(size 1.27 1.27)
							)
						)
					)
				)
				(pin power_out line
					(at 0 -5.08 0)
					(length 3.81)
					(name "3V3AUX"
						(effects
							(font
								(size 1.27 1.27)
							)
						)
					)
					(number "B10"
						(effects
							(font
								(size 1.27 1.27)
							)
						)
					)
				)
				(pin input line
					(at 0 -10.16 0)
					(length 3.81)
					(name "TCK"
						(effects
							(font
								(size 1.27 1.27)
							)
						)
					)
					(number "A5"
						(effects
							(font
								(size 1.27 1.27)
							)
						)
					)
				)
				(pin input line
					(at 0 -12.7 0)
					(length 3.81)
					(name "TDI"
						(effects
							(font
								(size 1.27 1.27)
							)
						)
					)
					(number "A6"
						(effects
							(font
								(size 1.27 1.27)
							)
						)
					)
				)
				(pin output line
					(at 0 -15.24 0)
					(length 3.81)
					(name "TDO"
						(effects
							(font
								(size 1.27 1.27)
							)
						)
					)
					(number "A7"
						(effects
							(font
								(size 1.27 1.27)
							)
						)
					)
				)
				(pin input line
					(at 0 -17.78 0)
					(length 3.81)
					(name "TMS"
						(effects
							(font
								(size 1.27 1.27)
							)
						)
					)
					(number "A8"
						(effects
							(font
								(size 1.27 1.27)
							)
						)
					)
				)
				(pin passive line
					(at 0 -22.86 0)
					(length 3.81)
					(name "GND"
						(effects
							(font
								(size 1.27 1.27)
							)
						)
					)
					(number "A12"
						(effects
							(font
								(size 1.27 1.27)
							)
						)
					)
				)
				(pin passive line
					(at 0 -22.86 0)
					(length 3.81)
					(hide yes)
					(name "GND"
						(effects
							(font
								(size 1.27 1.27)
							)
						)
					)
					(number "A15"
						(effects
							(font
								(size 1.27 1.27)
							)
						)
					)
				)
				(pin passive line
					(at 0 -22.86 0)
					(length 3.81)
					(hide yes)
					(name "GND"
						(effects
							(font
								(size 1.27 1.27)
							)
						)
					)
					(number "A18"
						(effects
							(font
								(size 1.27 1.27)
							)
						)
					)
				)
				(pin passive line
					(at 0 -22.86 0)
					(length 3.81)
					(hide yes)
					(name "GND"
						(effects
							(font
								(size 1.27 1.27)
							)
						)
					)
					(number "A20"
						(effects
							(font
								(size 1.27 1.27)
							)
						)
					)
				)
				(pin passive line
					(at 0 -22.86 0)
					(length 3.81)
					(hide yes)
					(name "GND"
						(effects
							(font
								(size 1.27 1.27)
							)
						)
					)
					(number "A23"
						(effects
							(font
								(size 1.27 1.27)
							)
						)
					)
				)
				(pin passive line
					(at 0 -22.86 0)
					(length 3.81)
					(hide yes)
					(name "GND"
						(effects
							(font
								(size 1.27 1.27)
							)
						)
					)
					(number "A24"
						(effects
							(font
								(size 1.27 1.27)
							)
						)
					)
				)
				(pin passive line
					(at 0 -22.86 0)
					(length 3.81)
					(hide yes)
					(name "GND"
						(effects
							(font
								(size 1.27 1.27)
							)
						)
					)
					(number "A27"
						(effects
							(font
								(size 1.27 1.27)
							)
						)
					)
				)
				(pin passive line
					(at 0 -22.86 0)
					(length 3.81)
					(hide yes)
					(name "GND"
						(effects
							(font
								(size 1.27 1.27)
							)
						)
					)
					(number "A28"
						(effects
							(font
								(size 1.27 1.27)
							)
						)
					)
				)
				(pin passive line
					(at 0 -22.86 0)
					(length 3.81)
					(hide yes)
					(name "GND"
						(effects
							(font
								(size 1.27 1.27)
							)
						)
					)
					(number "A31"
						(effects
							(font
								(size 1.27 1.27)
							)
						)
					)
				)
				(pin passive line
					(at 0 -22.86 0)
					(length 3.81)
					(hide yes)
					(name "GND"
						(effects
							(font
								(size 1.27 1.27)
							)
						)
					)
					(number "A4"
						(effects
							(font
								(size 1.27 1.27)
							)
						)
					)
				)
				(pin passive line
					(at 0 -22.86 0)
					(length 3.81)
					(hide yes)
					(name "GND"
						(effects
							(font
								(size 1.27 1.27)
							)
						)
					)
					(number "B13"
						(effects
							(font
								(size 1.27 1.27)
							)
						)
					)
				)
				(pin passive line
					(at 0 -22.86 0)
					(length 3.81)
					(hide yes)
					(name "GND"
						(effects
							(font
								(size 1.27 1.27)
							)
						)
					)
					(number "B16"
						(effects
							(font
								(size 1.27 1.27)
							)
						)
					)
				)
				(pin passive line
					(at 0 -22.86 0)
					(length 3.81)
					(hide yes)
					(name "GND"
						(effects
							(font
								(size 1.27 1.27)
							)
						)
					)
					(number "B18"
						(effects
							(font
								(size 1.27 1.27)
							)
						)
					)
				)
				(pin passive line
					(at 0 -22.86 0)
					(length 3.81)
					(hide yes)
					(name "GND"
						(effects
							(font
								(size 1.27 1.27)
							)
						)
					)
					(number "B21"
						(effects
							(font
								(size 1.27 1.27)
							)
						)
					)
				)
				(pin passive line
					(at 0 -22.86 0)
					(length 3.81)
					(hide yes)
					(name "GND"
						(effects
							(font
								(size 1.27 1.27)
							)
						)
					)
					(number "B22"
						(effects
							(font
								(size 1.27 1.27)
							)
						)
					)
				)
				(pin passive line
					(at 0 -22.86 0)
					(length 3.81)
					(hide yes)
					(name "GND"
						(effects
							(font
								(size 1.27 1.27)
							)
						)
					)
					(number "B25"
						(effects
							(font
								(size 1.27 1.27)
							)
						)
					)
				)
				(pin passive line
					(at 0 -22.86 0)
					(length 3.81)
					(hide yes)
					(name "GND"
						(effects
							(font
								(size 1.27 1.27)
							)
						)
					)
					(number "B26"
						(effects
							(font
								(size 1.27 1.27)
							)
						)
					)
				)
				(pin passive line
					(at 0 -22.86 0)
					(length 3.81)
					(hide yes)
					(name "GND"
						(effects
							(font
								(size 1.27 1.27)
							)
						)
					)
					(number "B29"
						(effects
							(font
								(size 1.27 1.27)
							)
						)
					)
				)
				(pin passive line
					(at 0 -22.86 0)
					(length 3.81)
					(hide yes)
					(name "GND"
						(effects
							(font
								(size 1.27 1.27)
							)
						)
					)
					(number "B32"
						(effects
							(font
								(size 1.27 1.27)
							)
						)
					)
				)
				(pin passive line
					(at 0 -22.86 0)
					(length 3.81)
					(hide yes)
					(name "GND"
						(effects
							(font
								(size 1.27 1.27)
							)
						)
					)
					(number "B4"
						(effects
							(font
								(size 1.27 1.27)
							)
						)
					)
				)
				(pin passive line
					(at 0 -22.86 0)
					(length 3.81)
					(hide yes)
					(name "GND"
						(effects
							(font
								(size 1.27 1.27)
							)
						)
					)
					(number "B7"
						(effects
							(font
								(size 1.27 1.27)
							)
						)
					)
				)
				(pin input line
					(at 0 -29.21 0)
					(length 3.81)
					(name "REFCLK_p"
						(effects
							(font
								(size 1.27 1.27)
							)
						)
					)
					(number "A13"
						(effects
							(font
								(size 1.27 1.27)
							)
						)
					)
				)
				(pin input line
					(at 0 -31.75 0)
					(length 3.81)
					(name "REFCLK_n"
						(effects
							(font
								(size 1.27 1.27)
							)
						)
					)
					(number "A14"
						(effects
							(font
								(size 1.27 1.27)
							)
						)
					)
				)
				(pin input line
					(at 0 -36.83 0)
					(length 3.81)
					(name "HSO0_p"
						(effects
							(font
								(size 1.27 1.27)
							)
						)
					)
					(number "B14"
						(effects
							(font
								(size 1.27 1.27)
							)
						)
					)
				)
				(pin input line
					(at 0 -39.37 0)
					(length 3.81)
					(name "HSO0_n"
						(effects
							(font
								(size 1.27 1.27)
							)
						)
					)
					(number "B15"
						(effects
							(font
								(size 1.27 1.27)
							)
						)
					)
				)
				(pin input line
					(at 0 -44.45 0)
					(length 3.81)
					(name "HSO1_p"
						(effects
							(font
								(size 1.27 1.27)
							)
						)
					)
					(number "B19"
						(effects
							(font
								(size 1.27 1.27)
							)
						)
					)
				)
				(pin input line
					(at 0 -46.99 0)
					(length 3.81)
					(name "HSO1_n"
						(effects
							(font
								(size 1.27 1.27)
							)
						)
					)
					(number "B20"
						(effects
							(font
								(size 1.27 1.27)
							)
						)
					)
				)
				(pin input line
					(at 0 -52.07 0)
					(length 3.81)
					(name "HSO2_p"
						(effects
							(font
								(size 1.27 1.27)
							)
						)
					)
					(number "B23"
						(effects
							(font
								(size 1.27 1.27)
							)
						)
					)
				)
				(pin input line
					(at 0 -54.61 0)
					(length 3.81)
					(name "HSO2_n"
						(effects
							(font
								(size 1.27 1.27)
							)
						)
					)
					(number "B24"
						(effects
							(font
								(size 1.27 1.27)
							)
						)
					)
				)
				(pin input line
					(at 0 -59.69 0)
					(length 3.81)
					(name "HSO3_p"
						(effects
							(font
								(size 1.27 1.27)
							)
						)
					)
					(number "B27"
						(effects
							(font
								(size 1.27 1.27)
							)
						)
					)
				)
				(pin input line
					(at 0 -62.23 0)
					(length 3.81)
					(name "HSO3_n"
						(effects
							(font
								(size 1.27 1.27)
							)
						)
					)
					(number "B28"
						(effects
							(font
								(size 1.27 1.27)
							)
						)
					)
				)
				(pin no_connect line
					(at 3.81 -7.62 0)
					(length 3.81)
					(hide yes)
					(name "NC"
						(effects
							(font
								(size 1.27 1.27)
							)
						)
					)
					(number "A32"
						(effects
							(font
								(size 1.27 1.27)
							)
						)
					)
				)
				(pin no_connect line
					(at 29.21 -7.62 180)
					(length 3.81)
					(hide yes)
					(name "NC"
						(effects
							(font
								(size 1.27 1.27)
							)
						)
					)
					(number "A19"
						(effects
							(font
								(size 1.27 1.27)
							)
						)
					)
				)
				(pin passive line
					(at 33.02 0 180)
					(length 3.81)
					(name "~{PRSNT1}"
						(effects
							(font
								(size 1.27 1.27)
							)
						)
					)
					(number "A1"
						(effects
							(font
								(size 1.27 1.27)
							)
						)
					)
				)
				(pin passive line
					(at 33.02 -2.54 180)
					(length 3.81)
					(name "~{PRSNT2_x1}"
						(effects
							(font
								(size 1.27 1.27)
							)
						)
					)
					(number "B17"
						(effects
							(font
								(size 1.27 1.27)
							)
						)
					)
				)
				(pin passive line
					(at 33.02 -5.08 180)
					(length 3.81)
					(name "~{PRSNT2_x4}"
						(effects
							(font
								(size 1.27 1.27)
							)
						)
					)
					(number "B31"
						(effects
							(font
								(size 1.27 1.27)
							)
						)
					)
				)
				(pin input line
					(at 33.02 -10.16 180)
					(length 3.81)
					(name "~{TRST}"
						(effects
							(font
								(size 1.27 1.27)
							)
						)
					)
					(number "B9"
						(effects
							(font
								(size 1.27 1.27)
							)
						)
					)
				)
				(pin open_collector line
					(at 33.02 -12.7 180)
					(length 3.81)
					(name "~{WAKE}"
						(effects
							(font
								(size 1.27 1.27)
							)
						)
					)
					(number "B11"
						(effects
							(font
								(size 1.27 1.27)
							)
						)
					)
				)
				(pin open_collector line
					(at 33.02 -15.24 180)
					(length 3.81)
					(name "~{CLKREQ}"
						(effects
							(font
								(size 1.27 1.27)
							)
						)
					)
					(number "B12"
						(effects
							(font
								(size 1.27 1.27)
							)
						)
					)
				)
				(pin open_collector line
					(at 33.02 -17.78 180)
					(length 3.81)
					(name "~{PERST}"
						(effects
							(font
								(size 1.27 1.27)
							)
						)
					)
					(number "A11"
						(effects
							(font
								(size 1.27 1.27)
							)
						)
					)
				)
				(pin open_collector line
					(at 33.02 -20.32 180)
					(length 3.81)
					(name "~{PWRBRK}"
						(effects
							(font
								(size 1.27 1.27)
							)
						)
					)
					(number "B30"
						(effects
							(font
								(size 1.27 1.27)
							)
						)
					)
				)
				(pin open_collector line
					(at 33.02 -29.21 180)
					(length 3.81)
					(name "SMCLK"
						(effects
							(font
								(size 1.27 1.27)
							)
						)
					)
					(number "B5"
						(effects
							(font
								(size 1.27 1.27)
							)
						)
					)
				)
				(pin open_collector line
					(at 33.02 -31.75 180)
					(length 3.81)
					(name "SMDAT"
						(effects
							(font
								(size 1.27 1.27)
							)
						)
					)
					(number "B6"
						(effects
							(font
								(size 1.27 1.27)
							)
						)
					)
				)
				(pin output line
					(at 33.02 -36.83 180)
					(length 3.81)
					(name "HSI0_p"
						(effects
							(font
								(size 1.27 1.27)
							)
						)
					)
					(number "A16"
						(effects
							(font
								(size 1.27 1.27)
							)
						)
					)
				)
				(pin output line
					(at 33.02 -39.37 180)
					(length 3.81)
					(name "HSI0_n"
						(effects
							(font
								(size 1.27 1.27)
							)
						)
					)
					(number "A17"
						(effects
							(font
								(size 1.27 1.27)
							)
						)
					)
				)
				(pin output line
					(at 33.02 -44.45 180)
					(length 3.81)
					(name "HSI1_p"
						(effects
							(font
								(size 1.27 1.27)
							)
						)
					)
					(number "A21"
						(effects
							(font
								(size 1.27 1.27)
							)
						)
					)
				)
				(pin output line
					(at 33.02 -46.99 180)
					(length 3.81)
					(name "HSI1_n"
						(effects
							(font
								(size 1.27 1.27)
							)
						)
					)
					(number "A22"
						(effects
							(font
								(size 1.27 1.27)
							)
						)
					)
				)
				(pin output line
					(at 33.02 -52.07 180)
					(length 3.81)
					(name "HSI2_p"
						(effects
							(font
								(size 1.27 1.27)
							)
						)
					)
					(number "A25"
						(effects
							(font
								(size 1.27 1.27)
							)
						)
					)
				)
				(pin output line
					(at 33.02 -54.61 180)
					(length 3.81)
					(name "HSI2_n"
						(effects
							(font
								(size 1.27 1.27)
							)
						)
					)
					(number "A26"
						(effects
							(font
								(size 1.27 1.27)
							)
						)
					)
				)
				(pin output line
					(at 33.02 -59.69 180)
					(length 3.81)
					(name "HSI3_p"
						(effects
							(font
								(size 1.27 1.27)
							)
						)
					)
					(number "A29"
						(effects
							(font
								(size 1.27 1.27)
							)
						)
					)
				)
				(pin output line
					(at 33.02 -62.23 180)
					(length 3.81)
					(name "HSI3_n"
						(effects
							(font
								(size 1.27 1.27)
							)
						)
					)
					(number "A30"
						(effects
							(font
								(size 1.27 1.27)
							)
						)
					)
				)
			)
		)
	(symbol "antmicroPowerMeasurement:PAC1954T-E_VQFN"
			(exclude_from_sim no)
			(in_bom yes)
			(on_board yes)
			(property "Reference" "U"
				(at 38.1 -2.54 0)
				(effects
					(font
						(size 1.27 1.27)
						(thickness 0.15)
					)
					(justify left bottom)
				)
			)
			(property "Value" "PAC1954T-E_VQFN"
				(at 38.1 -5.08 0)
				(effects
					(font
						(size 1.27 1.27)
						(thickness 0.15)
					)
					(justify left bottom)
				)
			)
			(property "Footprint" "antmicro-footprints:VQFN-16-1EP_3x3mm_P0.5mm_EP1.1x1.1mm"
				(at 38.1 -7.62 0)
				(effects
					(font
						(size 1.27 1.27)
						(thickness 0.15)
					)
					(justify left bottom)
					(hide yes)
				)
			)
			(property "Datasheet" "https://ww1.microchip.com/downloads/aemDocuments/documents/MSLD/ProductDocuments/DataSheets/PAC195X-Family-Data-Sheet-DS20006539.pdf"
				(at 38.1 -10.16 0)
				(effects
					(font
						(size 1.27 1.27)
						(thickness 0.15)
					)
					(justify left bottom)
					(hide yes)
				)
			)
			(property "Description" "Current/Voltage Monitor Regulator High-Side 16-VQFN (3x3)"
				(at 0 0 0)
				(effects
					(font
						(size 1.27 1.27)
					)
					(hide yes)
				)
			)
			(property "MPN" "PAC1954T-E/4MX"
				(at 38.1 -12.7 0)
				(effects
					(font
						(size 1.27 1.27)
						(thickness 0.15)
					)
					(justify left bottom)
					(hide yes)
				)
			)
			(property "Manufacturer" "Microchip Technology"
				(at 38.1 -15.24 0)
				(effects
					(font
						(size 1.27 1.27)
						(thickness 0.15)
					)
					(justify left bottom)
					(hide yes)
				)
			)
			(property "Author" "Antmicro"
				(at 38.1 -17.78 0)
				(effects
					(font
						(size 1.27 1.27)
						(thickness 0.15)
					)
					(justify left bottom)
					(hide yes)
				)
			)
			(property "License" "Apache-2.0"
				(at 38.1 -20.32 0)
				(effects
					(font
						(size 1.27 1.27)
						(thickness 0.15)
					)
					(justify left bottom)
					(hide yes)
				)
			)
			(property "ki_keywords" "MONITOR, VOLTAGE"
				(at 0 0 0)
				(effects
					(font
						(size 1.27 1.27)
					)
					(hide yes)
				)
			)
			(property "ki_fp_filters" "UQFN*1EP*4x4mm*P0.65mm*"
				(at 0 0 0)
				(effects
					(font
						(size 1.27 1.27)
					)
					(hide yes)
				)
			)
			(symbol "PAC1954T-E_VQFN_1_1"
				(rectangle
					(start 2.54 2.54)
					(end 22.86 -27.94)
					(stroke
						(width 0.254)
						(type default)
					)
					(fill
						(type background)
					)
				)
				(pin power_in line
					(at 0 0 0)
					(length 2.54)
					(name "VDD"
						(effects
							(font
								(size 1.27 1.27)
							)
						)
					)
					(number "2"
						(effects
							(font
								(size 1.27 1.27)
							)
						)
					)
				)
				(pin input line
					(at 0 -2.54 0)
					(length 2.54)
					(name "~{PWRDN}"
						(effects
							(font
								(size 1.27 1.27)
							)
						)
					)
					(number "16"
						(effects
							(font
								(size 1.27 1.27)
							)
						)
					)
				)
				(pin bidirectional line
					(at 0 -7.62 0)
					(length 2.54)
					(name "SDA"
						(effects
							(font
								(size 1.27 1.27)
							)
						)
					)
					(number "5"
						(effects
							(font
								(size 1.27 1.27)
							)
						)
					)
				)
				(pin input line
					(at 0 -10.16 0)
					(length 2.54)
					(name "SCL"
						(effects
							(font
								(size 1.27 1.27)
							)
						)
					)
					(number "4"
						(effects
							(font
								(size 1.27 1.27)
							)
						)
					)
				)
				(pin bidirectional line
					(at 0 -15.24 0)
					(length 2.54)
					(name "SLOW/~{ALERT1}"
						(effects
							(font
								(size 1.27 1.27)
							)
						)
					)
					(number "1"
						(effects
							(font
								(size 1.27 1.27)
							)
						)
					)
				)
				(pin bidirectional line
					(at 0 -17.78 0)
					(length 2.54)
					(name "GPIO/~{ALERT2}"
						(effects
							(font
								(size 1.27 1.27)
							)
						)
					)
					(number "15"
						(effects
							(font
								(size 1.27 1.27)
							)
						)
					)
				)
				(pin bidirectional line
					(at 0 -20.32 0)
					(length 2.54)
					(name "ADDRSEL"
						(effects
							(font
								(size 1.27 1.27)
							)
						)
					)
					(number "6"
						(effects
							(font
								(size 1.27 1.27)
							)
						)
					)
				)
				(pin power_in line
					(at 0 -25.4 0)
					(length 2.54)
					(name "GND"
						(effects
							(font
								(size 1.27 1.27)
							)
						)
					)
					(number "3"
						(effects
							(font
								(size 1.27 1.27)
							)
						)
					)
				)
				(pin no_connect line
					(at 2.54 -22.86 0)
					(length 2.54)
					(hide yes)
					(name "EP"
						(effects
							(font
								(size 1.27 1.27)
							)
						)
					)
					(number "17"
						(effects
							(font
								(size 1.27 1.27)
							)
						)
					)
				)
				(pin input line
					(at 25.4 0 180)
					(length 2.54)
					(name "IN1+"
						(effects
							(font
								(size 1.27 1.27)
							)
						)
					)
					(number "11"
						(effects
							(font
								(size 1.27 1.27)
							)
						)
					)
				)
				(pin input line
					(at 25.4 -2.54 180)
					(length 2.54)
					(name "IN1-"
						(effects
							(font
								(size 1.27 1.27)
							)
						)
					)
					(number "12"
						(effects
							(font
								(size 1.27 1.27)
							)
						)
					)
				)
				(pin input line
					(at 25.4 -7.62 180)
					(length 2.54)
					(name "IN2+"
						(effects
							(font
								(size 1.27 1.27)
							)
						)
					)
					(number "13"
						(effects
							(font
								(size 1.27 1.27)
							)
						)
					)
				)
				(pin input line
					(at 25.4 -10.16 180)
					(length 2.54)
					(name "IN2-"
						(effects
							(font
								(size 1.27 1.27)
							)
						)
					)
					(number "14"
						(effects
							(font
								(size 1.27 1.27)
							)
						)
					)
				)
				(pin input line
					(at 25.4 -15.24 180)
					(length 2.54)
					(name "IN3+"
						(effects
							(font
								(size 1.27 1.27)
							)
						)
					)
					(number "8"
						(effects
							(font
								(size 1.27 1.27)
							)
						)
					)
				)
				(pin input line
					(at 25.4 -17.78 180)
					(length 2.54)
					(name "IN3-"
						(effects
							(font
								(size 1.27 1.27)
							)
						)
					)
					(number "7"
						(effects
							(font
								(size 1.27 1.27)
							)
						)
					)
				)
				(pin input line
					(at 25.4 -22.86 180)
					(length 2.54)
					(name "IN4+"
						(effects
							(font
								(size 1.27 1.27)
							)
						)
					)
					(number "10"
						(effects
							(font
								(size 1.27 1.27)
							)
						)
					)
				)
				(pin input line
					(at 25.4 -25.4 180)
					(length 2.54)
					(name "IN4-"
						(effects
							(font
								(size 1.27 1.27)
							)
						)
					)
					(number "9"
						(effects
							(font
								(size 1.27 1.27)
							)
						)
					)
				)
			)
		)
	(symbol "antmicroPushbuttonSwitches:SW_KMR211NGLFS_SMD"
			(pin_names
				(hide yes)
			)
			(exclude_from_sim no)
			(in_bom yes)
			(on_board yes)
			(property "Reference" "SW"
				(at 25.4 -2.54 0)
				(effects
					(font
						(size 1.27 1.27)
						(thickness 0.15)
					)
					(justify left bottom)
				)
			)
			(property "Value" "SW_KMR211NGLFS_SMD"
				(at 25.4 -7.62 0)
				(effects
					(font
						(size 1.27 1.27)
						(thickness 0.15)
					)
					(justify left bottom)
					(hide yes)
				)
			)
			(property "Footprint" "antmicro-footprints:SW_KMR211NGLFS_SMD"
				(at 25.4 -10.16 0)
				(effects
					(font
						(size 1.27 1.27)
						(thickness 0.15)
					)
					(justify left bottom)
					(hide yes)
				)
			)
			(property "Datasheet" "http://www.farnell.com/datasheets/2631211.pdf"
				(at 25.4 -12.7 0)
				(effects
					(font
						(size 1.27 1.27)
						(thickness 0.15)
					)
					(justify left bottom)
					(hide yes)
				)
			)
			(property "Description" "Tactile Switch, KMR 2 Series, Top Actuated, Surface Mount, Oval Button, 120 gf, 50mA at 32VDC"
				(at 0 0 0)
				(effects
					(font
						(size 1.27 1.27)
					)
					(hide yes)
				)
			)
			(property "MPN" "KMR211NGLFS"
				(at 25.4 -5.08 0)
				(effects
					(font
						(size 1.27 1.27)
						(thickness 0.15)
					)
					(justify left bottom)
				)
			)
			(property "Manufacturer" "C&K"
				(at 25.4 -15.24 0)
				(effects
					(font
						(size 1.27 1.27)
						(thickness 0.15)
					)
					(justify left bottom)
					(hide yes)
				)
			)
			(property "Author" "Antmicro"
				(at 25.4 -17.78 0)
				(effects
					(font
						(size 1.27 1.27)
						(thickness 0.15)
					)
					(justify left bottom)
					(hide yes)
				)
			)
			(property "License" "Apache-2.0"
				(at 25.4 -20.32 0)
				(effects
					(font
						(size 1.27 1.27)
						(thickness 0.15)
					)
					(justify left bottom)
					(hide yes)
				)
			)
			(property "ki_keywords" "VERTICAL, SMT, SWITCH, MECHANICAL, TACTILE"
				(at 0 0 0)
				(effects
					(font
						(size 1.27 1.27)
					)
					(hide yes)
				)
			)
			(symbol "SW_KMR211NGLFS_SMD_1_1"
				(polyline
					(pts
						(xy 2.54 0) (xy 3.302 0)
					)
					(stroke
						(width 0.254)
						(type default)
					)
					(fill
						(type none)
					)
				)
				(polyline
					(pts
						(xy 2.54 -2.54) (xy 3.302 -2.54)
					)
					(stroke
						(width 0.254)
						(type default)
					)
					(fill
						(type none)
					)
				)
				(polyline
					(pts
						(xy 3.302 1.27) (xy 6.858 1.27)
					)
					(stroke
						(width 0.254)
						(type default)
					)
					(fill
						(type none)
					)
				)
				(circle
					(center 3.556 0)
					(radius 0.254)
					(stroke
						(width 0.254)
						(type default)
					)
					(fill
						(type none)
					)
				)
				(polyline
					(pts
						(xy 3.556 -0.3048) (xy 3.556 -2.1844)
					)
					(stroke
						(width 0.254)
						(type default)
					)
					(fill
						(type none)
					)
				)
				(circle
					(center 3.556 -2.54)
					(radius 0.254)
					(stroke
						(width 0.254)
						(type default)
					)
					(fill
						(type none)
					)
				)
				(polyline
					(pts
						(xy 4.064 2.794) (xy 6.096 2.794)
					)
					(stroke
						(width 0.254)
						(type default)
					)
					(fill
						(type none)
					)
				)
				(polyline
					(pts
						(xy 5.08 1.27) (xy 5.08 2.794)
					)
					(stroke
						(width 0.254)
						(type default)
					)
					(fill
						(type none)
					)
				)
				(circle
					(center 6.604 0)
					(radius 0.254)
					(stroke
						(width 0.254)
						(type default)
					)
					(fill
						(type none)
					)
				)
				(polyline
					(pts
						(xy 6.604 -0.254) (xy 6.604 -2.1844)
					)
					(stroke
						(width 0.254)
						(type default)
					)
					(fill
						(type none)
					)
				)
				(circle
					(center 6.604 -2.54)
					(radius 0.254)
					(stroke
						(width 0.254)
						(type default)
					)
					(fill
						(type none)
					)
				)
				(polyline
					(pts
						(xy 7.62 0) (xy 6.858 0)
					)
					(stroke
						(width 0.254)
						(type default)
					)
					(fill
						(type none)
					)
				)
				(polyline
					(pts
						(xy 7.62 -2.54) (xy 6.858 -2.54)
					)
					(stroke
						(width 0.254)
						(type default)
					)
					(fill
						(type none)
					)
				)
				(pin passive line
					(at 0 0 0)
					(length 2.54)
					(name "1"
						(effects
							(font
								(size 1.27 1.27)
							)
						)
					)
					(number "1"
						(effects
							(font
								(size 1.27 1.27)
							)
						)
					)
				)
				(pin passive line
					(at 0 -2.54 0)
					(length 2.54)
					(name "2"
						(effects
							(font
								(size 1.27 1.27)
							)
						)
					)
					(number "2"
						(effects
							(font
								(size 1.27 1.27)
							)
						)
					)
				)
				(pin passive line
					(at 10.16 0 180)
					(length 2.54)
					(name "3"
						(effects
							(font
								(size 1.27 1.27)
							)
						)
					)
					(number "3"
						(effects
							(font
								(size 1.27 1.27)
							)
						)
					)
				)
				(pin passive line
					(at 10.16 -2.54 180)
					(length 2.54)
					(name "4"
						(effects
							(font
								(size 1.27 1.27)
							)
						)
					)
					(number "4"
						(effects
							(font
								(size 1.27 1.27)
							)
						)
					)
				)
			)
		)
	(symbol "antmicroResistors0402:R_0R_0402"
			(pin_numbers
				(hide yes)
			)
			(pin_names
				(hide yes)
			)
			(exclude_from_sim no)
			(in_bom yes)
			(on_board yes)
			(property "Reference" "R"
				(at 20.32 -5.08 0)
				(effects
					(font
						(size 1.27 1.27)
						(thickness 0.15)
					)
					(justify left bottom)
				)
			)
			(property "Value" "R_0R_0402"
				(at 20.32 -12.7 0)
				(effects
					(font
						(size 1.27 1.27)
						(thickness 0.15)
					)
					(justify left bottom)
					(hide yes)
				)
			)
			(property "Footprint" "antmicro-footprints:R_0402_1005Metric"
				(at 20.32 -15.24 0)
				(effects
					(font
						(size 1.27 1.27)
						(thickness 0.15)
					)
					(justify left bottom)
					(hide yes)
				)
			)
			(property "Datasheet" "https://industrial.panasonic.com/cdbs/www-data/pdf/RDA0000/AOA0000C301.pdf"
				(at 20.32 -17.78 0)
				(effects
					(font
						(size 1.27 1.27)
						(thickness 0.15)
					)
					(justify left bottom)
					(hide yes)
				)
			)
			(property "Description" "SMD Chip Resistor, Jumper, 0 ohm, 100 mW, 0402 [1005 Metric], Thick Film, General Purpose"
				(at 0 0 0)
				(effects
					(font
						(size 1.27 1.27)
					)
					(hide yes)
				)
			)
			(property "MPN" "ERJ2GE0R00X"
				(at 20.32 -20.32 0)
				(effects
					(font
						(size 1.27 1.27)
						(thickness 0.15)
					)
					(justify left bottom)
					(hide yes)
				)
			)
			(property "Manufacturer" "Panasonic"
				(at 20.32 -22.86 0)
				(effects
					(font
						(size 1.27 1.27)
						(thickness 0.15)
					)
					(justify left bottom)
					(hide yes)
				)
			)
			(property "License" "Apache-2.0"
				(at 20.32 -25.4 0)
				(effects
					(font
						(size 1.27 1.27)
						(thickness 0.15)
					)
					(justify left bottom)
					(hide yes)
				)
			)
			(property "Author" "Antmicro"
				(at 20.32 -27.94 0)
				(effects
					(font
						(size 1.27 1.27)
						(thickness 0.15)
					)
					(justify left bottom)
					(hide yes)
				)
			)
			(property "Val" "0R"
				(at 20.32 -7.62 0)
				(effects
					(font
						(size 1.27 1.27)
						(thickness 0.15)
					)
					(justify left bottom)
				)
			)
			(property "Tolerance" "~"
				(at 20.32 -10.16 0)
				(effects
					(font
						(size 1.27 1.27)
					)
					(justify left bottom)
					(hide yes)
				)
			)
			(property "Current" "1A"
				(at 20.32 -30.48 0)
				(effects
					(font
						(size 1.27 1.27)
						(thickness 0.15)
					)
					(justify left bottom)
					(hide yes)
				)
			)
			(property "ki_keywords" "0402, SMT, RESISTOR, PASSIVE"
				(at 0 0 0)
				(effects
					(font
						(size 1.27 1.27)
					)
					(hide yes)
				)
			)
			(symbol "R_0R_0402_0_1"
				(rectangle
					(start 0.635 0.889)
					(end 4.445 -0.889)
					(stroke
						(width 0.254)
						(type default)
					)
					(fill
						(type none)
					)
				)
			)
			(symbol "R_0R_0402_1_1"
				(pin passive line
					(at 0 0 0)
					(length 0.635)
					(name "~"
						(effects
							(font
								(size 1.27 1.27)
							)
						)
					)
					(number "1"
						(effects
							(font
								(size 1.27 1.27)
							)
						)
					)
				)
				(pin passive line
					(at 5.08 0 180)
					(length 0.635)
					(name "~"
						(effects
							(font
								(size 1.27 1.27)
							)
						)
					)
					(number "2"
						(effects
							(font
								(size 1.27 1.27)
							)
						)
					)
				)
			)
		)
	(symbol "antmicroResistors0402:R_100R_0402"
			(pin_numbers
				(hide yes)
			)
			(pin_names
				(hide yes)
			)
			(exclude_from_sim no)
			(in_bom yes)
			(on_board yes)
			(property "Reference" "R"
				(at 20.32 -5.08 0)
				(effects
					(font
						(size 1.27 1.27)
						(thickness 0.15)
					)
					(justify left bottom)
				)
			)
			(property "Value" "R_100R_0402"
				(at 20.32 -12.7 0)
				(effects
					(font
						(size 1.27 1.27)
						(thickness 0.15)
					)
					(justify left bottom)
					(hide yes)
				)
			)
			(property "Footprint" "antmicro-footprints:R_0402_1005Metric"
				(at 20.32 -15.24 0)
				(effects
					(font
						(size 1.27 1.27)
						(thickness 0.15)
					)
					(justify left bottom)
					(hide yes)
				)
			)
			(property "Datasheet" "https://www.bourns.com/docs/product-datasheets/cr.pdf"
				(at 20.32 -17.78 0)
				(effects
					(font
						(size 1.27 1.27)
						(thickness 0.15)
					)
					(justify left bottom)
					(hide yes)
				)
			)
			(property "Description" "SMD Chip Resistor, 100 ohm, ± 1%, 62.5 mW, 0402 [1005 Metric], Thick Film, General Purpose"
				(at 0 0 0)
				(effects
					(font
						(size 1.27 1.27)
					)
					(hide yes)
				)
			)
			(property "MPN" "CR0402-FX-1000GLF"
				(at 20.32 -20.32 0)
				(effects
					(font
						(size 1.27 1.27)
						(thickness 0.15)
					)
					(justify left bottom)
					(hide yes)
				)
			)
			(property "Manufacturer" "Bourns"
				(at 20.32 -22.86 0)
				(effects
					(font
						(size 1.27 1.27)
						(thickness 0.15)
					)
					(justify left bottom)
					(hide yes)
				)
			)
			(property "License" "Apache-2.0"
				(at 20.32 -25.4 0)
				(effects
					(font
						(size 1.27 1.27)
						(thickness 0.15)
					)
					(justify left bottom)
					(hide yes)
				)
			)
			(property "Author" "Antmicro"
				(at 20.32 -27.94 0)
				(effects
					(font
						(size 1.27 1.27)
						(thickness 0.15)
					)
					(justify left bottom)
					(hide yes)
				)
			)
			(property "Val" "100R"
				(at 20.32 -7.62 0)
				(effects
					(font
						(size 1.27 1.27)
						(thickness 0.15)
					)
					(justify left bottom)
				)
			)
			(property "Tolerance" "1%"
				(at 20.32 -10.16 0)
				(effects
					(font
						(size 1.27 1.27)
					)
					(justify left bottom)
					(hide yes)
				)
			)
			(property "ki_keywords" "0402, SMT, RESISTOR, PASSIVE"
				(at 0 0 0)
				(effects
					(font
						(size 1.27 1.27)
					)
					(hide yes)
				)
			)
			(symbol "R_100R_0402_0_1"
				(rectangle
					(start 0.635 0.889)
					(end 4.445 -0.889)
					(stroke
						(width 0.254)
						(type default)
					)
					(fill
						(type none)
					)
				)
			)
			(symbol "R_100R_0402_1_1"
				(pin passive line
					(at 0 0 0)
					(length 0.635)
					(name "~"
						(effects
							(font
								(size 1.27 1.27)
							)
						)
					)
					(number "1"
						(effects
							(font
								(size 1.27 1.27)
							)
						)
					)
				)
				(pin passive line
					(at 5.08 0 180)
					(length 0.635)
					(name "~"
						(effects
							(font
								(size 1.27 1.27)
							)
						)
					)
					(number "2"
						(effects
							(font
								(size 1.27 1.27)
							)
						)
					)
				)
			)
		)
	(symbol "antmicroResistors0402:R_10k_0402"
			(pin_numbers
				(hide yes)
			)
			(pin_names
				(hide yes)
			)
			(exclude_from_sim no)
			(in_bom yes)
			(on_board yes)
			(property "Reference" "R"
				(at 20.32 -5.08 0)
				(effects
					(font
						(size 1.27 1.27)
						(thickness 0.15)
					)
					(justify left bottom)
				)
			)
			(property "Value" "R_10k_0402"
				(at 20.32 -12.7 0)
				(effects
					(font
						(size 1.27 1.27)
						(thickness 0.15)
					)
					(justify left bottom)
					(hide yes)
				)
			)
			(property "Footprint" "antmicro-footprints:R_0402_1005Metric"
				(at 20.32 -15.24 0)
				(effects
					(font
						(size 1.27 1.27)
						(thickness 0.15)
					)
					(justify left bottom)
					(hide yes)
				)
			)
			(property "Datasheet" "https://www.bourns.com/docs/product-datasheets/cr.pdf"
				(at 20.32 -17.78 0)
				(effects
					(font
						(size 1.27 1.27)
						(thickness 0.15)
					)
					(justify left bottom)
					(hide yes)
				)
			)
			(property "Description" "SMD Chip Resistor, 10 kohm, ± 1%, 62.5 mW, 0402 [1005 Metric], Thick Film, General Purpose"
				(at 0 0 0)
				(effects
					(font
						(size 1.27 1.27)
					)
					(hide yes)
				)
			)
			(property "MPN" "CR0402-FX-1002GLF"
				(at 20.32 -20.32 0)
				(effects
					(font
						(size 1.27 1.27)
						(thickness 0.15)
					)
					(justify left bottom)
					(hide yes)
				)
			)
			(property "Manufacturer" "Bourns"
				(at 20.32 -22.86 0)
				(effects
					(font
						(size 1.27 1.27)
						(thickness 0.15)
					)
					(justify left bottom)
					(hide yes)
				)
			)
			(property "License" "Apache-2.0"
				(at 20.32 -25.4 0)
				(effects
					(font
						(size 1.27 1.27)
						(thickness 0.15)
					)
					(justify left bottom)
					(hide yes)
				)
			)
			(property "Author" "Antmicro"
				(at 20.32 -27.94 0)
				(effects
					(font
						(size 1.27 1.27)
						(thickness 0.15)
					)
					(justify left bottom)
					(hide yes)
				)
			)
			(property "Val" "10k"
				(at 20.32 -7.62 0)
				(effects
					(font
						(size 1.27 1.27)
						(thickness 0.15)
					)
					(justify left bottom)
				)
			)
			(property "Tolerance" "1%"
				(at 20.32 -10.16 0)
				(effects
					(font
						(size 1.27 1.27)
					)
					(justify left bottom)
					(hide yes)
				)
			)
			(property "ki_keywords" "0402, SMT, RESISTOR, PASSIVE"
				(at 0 0 0)
				(effects
					(font
						(size 1.27 1.27)
					)
					(hide yes)
				)
			)
			(symbol "R_10k_0402_0_1"
				(rectangle
					(start 0.635 0.889)
					(end 4.445 -0.889)
					(stroke
						(width 0.254)
						(type default)
					)
					(fill
						(type none)
					)
				)
			)
			(symbol "R_10k_0402_1_1"
				(pin passive line
					(at 0 0 0)
					(length 0.635)
					(name "~"
						(effects
							(font
								(size 1.27 1.27)
							)
						)
					)
					(number "1"
						(effects
							(font
								(size 1.27 1.27)
							)
						)
					)
				)
				(pin passive line
					(at 5.08 0 180)
					(length 0.635)
					(name "~"
						(effects
							(font
								(size 1.27 1.27)
							)
						)
					)
					(number "2"
						(effects
							(font
								(size 1.27 1.27)
							)
						)
					)
				)
			)
		)
	(symbol "antmicroResistors0402:R_12k1_0402"
			(pin_numbers
				(hide yes)
			)
			(pin_names
				(hide yes)
			)
			(exclude_from_sim no)
			(in_bom yes)
			(on_board yes)
			(property "Reference" "R"
				(at 20.32 -5.08 0)
				(effects
					(font
						(size 1.27 1.27)
						(thickness 0.15)
					)
					(justify left bottom)
				)
			)
			(property "Value" "R_12k1_0402"
				(at 20.32 -12.7 0)
				(effects
					(font
						(size 1.27 1.27)
						(thickness 0.15)
					)
					(justify left bottom)
					(hide yes)
				)
			)
			(property "Footprint" "antmicro-footprints:R_0402_1005Metric"
				(at 20.32 -15.24 0)
				(effects
					(font
						(size 1.27 1.27)
						(thickness 0.15)
					)
					(justify left bottom)
					(hide yes)
				)
			)
			(property "Datasheet" "https://www.bourns.com/docs/product-datasheets/cr.pdf"
				(at 20.32 -17.78 0)
				(effects
					(font
						(size 1.27 1.27)
						(thickness 0.15)
					)
					(justify left bottom)
					(hide yes)
				)
			)
			(property "Description" "SMD Chip Resistor, 12.1 kohm, ± 1%, 62.5 mW, 0402 [1005 Metric], Thick Film, General Purpose"
				(at 0 0 0)
				(effects
					(font
						(size 1.27 1.27)
					)
					(hide yes)
				)
			)
			(property "MPN" "CR0402-FX-1212GLF"
				(at 20.32 -20.32 0)
				(effects
					(font
						(size 1.27 1.27)
						(thickness 0.15)
					)
					(justify left bottom)
					(hide yes)
				)
			)
			(property "Manufacturer" "Bourns"
				(at 20.32 -22.86 0)
				(effects
					(font
						(size 1.27 1.27)
						(thickness 0.15)
					)
					(justify left bottom)
					(hide yes)
				)
			)
			(property "License" "Apache-2.0"
				(at 20.32 -25.4 0)
				(effects
					(font
						(size 1.27 1.27)
						(thickness 0.15)
					)
					(justify left bottom)
					(hide yes)
				)
			)
			(property "Author" "Antmicro"
				(at 20.32 -27.94 0)
				(effects
					(font
						(size 1.27 1.27)
						(thickness 0.15)
					)
					(justify left bottom)
					(hide yes)
				)
			)
			(property "Val" "12k1"
				(at 20.32 -7.62 0)
				(effects
					(font
						(size 1.27 1.27)
						(thickness 0.15)
					)
					(justify left bottom)
				)
			)
			(property "Tolerance" "1%"
				(at 20.32 -10.16 0)
				(effects
					(font
						(size 1.27 1.27)
					)
					(justify left bottom)
					(hide yes)
				)
			)
			(property "ki_keywords" "0402, SMT, RESISTOR, PASSIVE"
				(at 0 0 0)
				(effects
					(font
						(size 1.27 1.27)
					)
					(hide yes)
				)
			)
			(symbol "R_12k1_0402_0_1"
				(rectangle
					(start 0.635 0.889)
					(end 4.445 -0.889)
					(stroke
						(width 0.254)
						(type default)
					)
					(fill
						(type none)
					)
				)
			)
			(symbol "R_12k1_0402_1_1"
				(pin passive line
					(at 0 0 0)
					(length 0.635)
					(name "~"
						(effects
							(font
								(size 1.27 1.27)
							)
						)
					)
					(number "1"
						(effects
							(font
								(size 1.27 1.27)
							)
						)
					)
				)
				(pin passive line
					(at 5.08 0 180)
					(length 0.635)
					(name "~"
						(effects
							(font
								(size 1.27 1.27)
							)
						)
					)
					(number "2"
						(effects
							(font
								(size 1.27 1.27)
							)
						)
					)
				)
			)
		)
	(symbol "antmicroResistors0402:R_12k_0402"
			(pin_numbers
				(hide yes)
			)
			(pin_names
				(hide yes)
			)
			(exclude_from_sim no)
			(in_bom yes)
			(on_board yes)
			(property "Reference" "R"
				(at 20.32 -5.08 0)
				(effects
					(font
						(size 1.27 1.27)
						(thickness 0.15)
					)
					(justify left bottom)
				)
			)
			(property "Value" "R_12k_0402"
				(at 20.32 -12.7 0)
				(effects
					(font
						(size 1.27 1.27)
						(thickness 0.15)
					)
					(justify left bottom)
					(hide yes)
				)
			)
			(property "Footprint" "antmicro-footprints:R_0402_1005Metric"
				(at 20.32 -15.24 0)
				(effects
					(font
						(size 1.27 1.27)
						(thickness 0.15)
					)
					(justify left bottom)
					(hide yes)
				)
			)
			(property "Datasheet" "https://www.bourns.com/docs/product-datasheets/cr.pdf"
				(at 20.32 -17.78 0)
				(effects
					(font
						(size 1.27 1.27)
						(thickness 0.15)
					)
					(justify left bottom)
					(hide yes)
				)
			)
			(property "Description" "SMD Chip Resistor, 12 kohm, ± 1%, 62.5 mW, 0402 [1005 Metric], Thick Film, General Purpose"
				(at 0 0 0)
				(effects
					(font
						(size 1.27 1.27)
					)
					(hide yes)
				)
			)
			(property "MPN" "CR0402-FX-1202GLF"
				(at 20.32 -20.32 0)
				(effects
					(font
						(size 1.27 1.27)
						(thickness 0.15)
					)
					(justify left bottom)
					(hide yes)
				)
			)
			(property "Manufacturer" "Bourns"
				(at 20.32 -22.86 0)
				(effects
					(font
						(size 1.27 1.27)
						(thickness 0.15)
					)
					(justify left bottom)
					(hide yes)
				)
			)
			(property "License" "Apache-2.0"
				(at 20.32 -25.4 0)
				(effects
					(font
						(size 1.27 1.27)
						(thickness 0.15)
					)
					(justify left bottom)
					(hide yes)
				)
			)
			(property "Author" "Antmicro"
				(at 20.32 -27.94 0)
				(effects
					(font
						(size 1.27 1.27)
						(thickness 0.15)
					)
					(justify left bottom)
					(hide yes)
				)
			)
			(property "Val" "12k"
				(at 20.32 -7.62 0)
				(effects
					(font
						(size 1.27 1.27)
						(thickness 0.15)
					)
					(justify left bottom)
				)
			)
			(property "Tolerance" "1%"
				(at 20.32 -10.16 0)
				(effects
					(font
						(size 1.27 1.27)
					)
					(justify left bottom)
					(hide yes)
				)
			)
			(property "ki_keywords" "0402, SMT, RESISTOR, PASSIVE"
				(at 0 0 0)
				(effects
					(font
						(size 1.27 1.27)
					)
					(hide yes)
				)
			)
			(symbol "R_12k_0402_0_1"
				(rectangle
					(start 0.635 0.889)
					(end 4.445 -0.889)
					(stroke
						(width 0.254)
						(type default)
					)
					(fill
						(type none)
					)
				)
			)
			(symbol "R_12k_0402_1_1"
				(pin passive line
					(at 0 0 0)
					(length 0.635)
					(name "~"
						(effects
							(font
								(size 1.27 1.27)
							)
						)
					)
					(number "1"
						(effects
							(font
								(size 1.27 1.27)
							)
						)
					)
				)
				(pin passive line
					(at 5.08 0 180)
					(length 0.635)
					(name "~"
						(effects
							(font
								(size 1.27 1.27)
							)
						)
					)
					(number "2"
						(effects
							(font
								(size 1.27 1.27)
							)
						)
					)
				)
			)
		)
	(symbol "antmicroResistors0402:R_1k_0402"
			(pin_numbers
				(hide yes)
			)
			(pin_names
				(hide yes)
			)
			(exclude_from_sim no)
			(in_bom yes)
			(on_board yes)
			(property "Reference" "R"
				(at 20.32 -5.08 0)
				(effects
					(font
						(size 1.27 1.27)
						(thickness 0.15)
					)
					(justify left bottom)
				)
			)
			(property "Value" "R_1k_0402"
				(at 20.32 -12.7 0)
				(effects
					(font
						(size 1.27 1.27)
						(thickness 0.15)
					)
					(justify left bottom)
					(hide yes)
				)
			)
			(property "Footprint" "antmicro-footprints:R_0402_1005Metric"
				(at 20.32 -15.24 0)
				(effects
					(font
						(size 1.27 1.27)
						(thickness 0.15)
					)
					(justify left bottom)
					(hide yes)
				)
			)
			(property "Datasheet" "https://www.bourns.com/docs/product-datasheets/cr.pdf"
				(at 20.32 -17.78 0)
				(effects
					(font
						(size 1.27 1.27)
						(thickness 0.15)
					)
					(justify left bottom)
					(hide yes)
				)
			)
			(property "Description" "SMD Chip Resistor, 1 kohm, ± 1%, 63 mW, 0402 [1005 Metric], Thick Film, General Purpose"
				(at 0 0 0)
				(effects
					(font
						(size 1.27 1.27)
					)
					(hide yes)
				)
			)
			(property "MPN" "CR0402-FX-1001GLF"
				(at 20.32 -20.32 0)
				(effects
					(font
						(size 1.27 1.27)
						(thickness 0.15)
					)
					(justify left bottom)
					(hide yes)
				)
			)
			(property "Manufacturer" "Bourns"
				(at 20.32 -22.86 0)
				(effects
					(font
						(size 1.27 1.27)
						(thickness 0.15)
					)
					(justify left bottom)
					(hide yes)
				)
			)
			(property "License" "Apache-2.0"
				(at 20.32 -25.4 0)
				(effects
					(font
						(size 1.27 1.27)
						(thickness 0.15)
					)
					(justify left bottom)
					(hide yes)
				)
			)
			(property "Author" "Antmicro"
				(at 20.32 -27.94 0)
				(effects
					(font
						(size 1.27 1.27)
						(thickness 0.15)
					)
					(justify left bottom)
					(hide yes)
				)
			)
			(property "Val" "1k"
				(at 20.32 -7.62 0)
				(effects
					(font
						(size 1.27 1.27)
						(thickness 0.15)
					)
					(justify left bottom)
				)
			)
			(property "Tolerance" "1%"
				(at 20.32 -10.16 0)
				(effects
					(font
						(size 1.27 1.27)
					)
					(justify left bottom)
					(hide yes)
				)
			)
			(property "ki_keywords" "0402, SMT, RESISTOR, PASSIVE"
				(at 0 0 0)
				(effects
					(font
						(size 1.27 1.27)
					)
					(hide yes)
				)
			)
			(symbol "R_1k_0402_0_1"
				(rectangle
					(start 0.635 0.889)
					(end 4.445 -0.889)
					(stroke
						(width 0.254)
						(type default)
					)
					(fill
						(type none)
					)
				)
			)
			(symbol "R_1k_0402_1_1"
				(pin passive line
					(at 0 0 0)
					(length 0.635)
					(name "~"
						(effects
							(font
								(size 1.27 1.27)
							)
						)
					)
					(number "1"
						(effects
							(font
								(size 1.27 1.27)
							)
						)
					)
				)
				(pin passive line
					(at 5.08 0 180)
					(length 0.635)
					(name "~"
						(effects
							(font
								(size 1.27 1.27)
							)
						)
					)
					(number "2"
						(effects
							(font
								(size 1.27 1.27)
							)
						)
					)
				)
			)
		)
	(symbol "antmicroResistors0402:R_205k_0402"
			(pin_numbers
				(hide yes)
			)
			(pin_names
				(hide yes)
			)
			(exclude_from_sim no)
			(in_bom yes)
			(on_board yes)
			(property "Reference" "R"
				(at 20.32 -5.08 0)
				(effects
					(font
						(size 1.27 1.27)
						(thickness 0.15)
					)
					(justify left bottom)
				)
			)
			(property "Value" "R_205k_0402"
				(at 20.32 -12.7 0)
				(effects
					(font
						(size 1.27 1.27)
						(thickness 0.15)
					)
					(justify left bottom)
					(hide yes)
				)
			)
			(property "Footprint" "antmicro-footprints:R_0402_1005Metric"
				(at 20.32 -15.24 0)
				(effects
					(font
						(size 1.27 1.27)
						(thickness 0.15)
					)
					(justify left bottom)
					(hide yes)
				)
			)
			(property "Datasheet" "https://www.bourns.com/docs/product-datasheets/cr.pdf"
				(at 20.32 -17.78 0)
				(effects
					(font
						(size 1.27 1.27)
						(thickness 0.15)
					)
					(justify left bottom)
					(hide yes)
				)
			)
			(property "Description" "SMD Chip Resistor"
				(at 0 0 0)
				(effects
					(font
						(size 1.27 1.27)
					)
					(hide yes)
				)
			)
			(property "MPN" "CR0402-FX-2053GLF"
				(at 20.32 -20.32 0)
				(effects
					(font
						(size 1.27 1.27)
						(thickness 0.15)
					)
					(justify left bottom)
					(hide yes)
				)
			)
			(property "Manufacturer" "Bourns"
				(at 20.32 -22.86 0)
				(effects
					(font
						(size 1.27 1.27)
						(thickness 0.15)
					)
					(justify left bottom)
					(hide yes)
				)
			)
			(property "License" "Apache-2.0"
				(at 20.32 -25.4 0)
				(effects
					(font
						(size 1.27 1.27)
						(thickness 0.15)
					)
					(justify left bottom)
					(hide yes)
				)
			)
			(property "Author" "Antmicro"
				(at 20.32 -27.94 0)
				(effects
					(font
						(size 1.27 1.27)
						(thickness 0.15)
					)
					(justify left bottom)
					(hide yes)
				)
			)
			(property "Val" "205k"
				(at 20.32 -7.62 0)
				(effects
					(font
						(size 1.27 1.27)
						(thickness 0.15)
					)
					(justify left bottom)
				)
			)
			(property "Tolerance" "1%"
				(at 20.32 -10.16 0)
				(effects
					(font
						(size 1.27 1.27)
					)
					(justify left bottom)
					(hide yes)
				)
			)
			(property "ki_keywords" "0402, SMT, RESISTOR, PASSIVE"
				(at 0 0 0)
				(effects
					(font
						(size 1.27 1.27)
					)
					(hide yes)
				)
			)
			(symbol "R_205k_0402_0_1"
				(rectangle
					(start 0.635 0.889)
					(end 4.445 -0.889)
					(stroke
						(width 0.254)
						(type default)
					)
					(fill
						(type none)
					)
				)
			)
			(symbol "R_205k_0402_1_1"
				(pin passive line
					(at 0 0 0)
					(length 0.635)
					(name "~"
						(effects
							(font
								(size 1.27 1.27)
							)
						)
					)
					(number "1"
						(effects
							(font
								(size 1.27 1.27)
							)
						)
					)
				)
				(pin passive line
					(at 5.08 0 180)
					(length 0.635)
					(name "~"
						(effects
							(font
								(size 1.27 1.27)
							)
						)
					)
					(number "2"
						(effects
							(font
								(size 1.27 1.27)
							)
						)
					)
				)
			)
		)
	(symbol "antmicroResistors0402:R_20k_0402"
			(pin_numbers
				(hide yes)
			)
			(pin_names
				(hide yes)
			)
			(exclude_from_sim no)
			(in_bom yes)
			(on_board yes)
			(property "Reference" "R"
				(at 20.32 -5.08 0)
				(effects
					(font
						(size 1.27 1.27)
						(thickness 0.15)
					)
					(justify left bottom)
				)
			)
			(property "Value" "R_20k_0402"
				(at 20.32 -12.7 0)
				(effects
					(font
						(size 1.27 1.27)
						(thickness 0.15)
					)
					(justify left bottom)
					(hide yes)
				)
			)
			(property "Footprint" "antmicro-footprints:R_0402_1005Metric"
				(at 20.32 -15.24 0)
				(effects
					(font
						(size 1.27 1.27)
						(thickness 0.15)
					)
					(justify left bottom)
					(hide yes)
				)
			)
			(property "Datasheet" "https://www.bourns.com/docs/product-datasheets/cr.pdf"
				(at 20.32 -17.78 0)
				(effects
					(font
						(size 1.27 1.27)
						(thickness 0.15)
					)
					(justify left bottom)
					(hide yes)
				)
			)
			(property "Description" "SMD Chip Resistor, 20 kohm, ± 1%, 62.5 mW, 0402 [1005 Metric], Thick Film, General Purpose"
				(at 0 0 0)
				(effects
					(font
						(size 1.27 1.27)
					)
					(hide yes)
				)
			)
			(property "MPN" "CR0402-FX-2002GLF"
				(at 20.32 -20.32 0)
				(effects
					(font
						(size 1.27 1.27)
						(thickness 0.15)
					)
					(justify left bottom)
					(hide yes)
				)
			)
			(property "Manufacturer" "Bourns"
				(at 20.32 -22.86 0)
				(effects
					(font
						(size 1.27 1.27)
						(thickness 0.15)
					)
					(justify left bottom)
					(hide yes)
				)
			)
			(property "License" "Apache-2.0"
				(at 20.32 -25.4 0)
				(effects
					(font
						(size 1.27 1.27)
						(thickness 0.15)
					)
					(justify left bottom)
					(hide yes)
				)
			)
			(property "Author" "Antmicro"
				(at 20.32 -27.94 0)
				(effects
					(font
						(size 1.27 1.27)
						(thickness 0.15)
					)
					(justify left bottom)
					(hide yes)
				)
			)
			(property "Val" "20k"
				(at 20.32 -7.62 0)
				(effects
					(font
						(size 1.27 1.27)
						(thickness 0.15)
					)
					(justify left bottom)
				)
			)
			(property "Tolerance" "1%"
				(at 20.32 -10.16 0)
				(effects
					(font
						(size 1.27 1.27)
					)
					(justify left bottom)
					(hide yes)
				)
			)
			(property "ki_keywords" "0402, SMT, RESISTOR, PASSIVE"
				(at 0 0 0)
				(effects
					(font
						(size 1.27 1.27)
					)
					(hide yes)
				)
			)
			(symbol "R_20k_0402_0_1"
				(rectangle
					(start 0.635 0.889)
					(end 4.445 -0.889)
					(stroke
						(width 0.254)
						(type default)
					)
					(fill
						(type none)
					)
				)
			)
			(symbol "R_20k_0402_1_1"
				(pin passive line
					(at 0 0 0)
					(length 0.635)
					(name "~"
						(effects
							(font
								(size 1.27 1.27)
							)
						)
					)
					(number "1"
						(effects
							(font
								(size 1.27 1.27)
							)
						)
					)
				)
				(pin passive line
					(at 5.08 0 180)
					(length 0.635)
					(name "~"
						(effects
							(font
								(size 1.27 1.27)
							)
						)
					)
					(number "2"
						(effects
							(font
								(size 1.27 1.27)
							)
						)
					)
				)
			)
		)
	(symbol "antmicroResistors0402:R_220R_0402"
			(pin_numbers
				(hide yes)
			)
			(pin_names
				(hide yes)
			)
			(exclude_from_sim no)
			(in_bom yes)
			(on_board yes)
			(property "Reference" "R"
				(at 20.32 -5.08 0)
				(effects
					(font
						(size 1.27 1.27)
						(thickness 0.15)
					)
					(justify left bottom)
				)
			)
			(property "Value" "R_220R_0402"
				(at 20.32 -12.7 0)
				(effects
					(font
						(size 1.27 1.27)
						(thickness 0.15)
					)
					(justify left bottom)
					(hide yes)
				)
			)
			(property "Footprint" "antmicro-footprints:R_0402_1005Metric"
				(at 20.32 -15.24 0)
				(effects
					(font
						(size 1.27 1.27)
						(thickness 0.15)
					)
					(justify left bottom)
					(hide yes)
				)
			)
			(property "Datasheet" "https://www.bourns.com/docs/product-datasheets/cr.pdf"
				(at 20.32 -17.78 0)
				(effects
					(font
						(size 1.27 1.27)
						(thickness 0.15)
					)
					(justify left bottom)
					(hide yes)
				)
			)
			(property "Description" "SMD Chip Resistor, 220 ohm, ± 1%, 62.5 mW, 0402 [1005 Metric], Thick Film, General Purpose"
				(at 0 0 0)
				(effects
					(font
						(size 1.27 1.27)
					)
					(hide yes)
				)
			)
			(property "MPN" "CR0402-FX-2200GLF"
				(at 20.32 -20.32 0)
				(effects
					(font
						(size 1.27 1.27)
						(thickness 0.15)
					)
					(justify left bottom)
					(hide yes)
				)
			)
			(property "Manufacturer" "Bourns"
				(at 20.32 -22.86 0)
				(effects
					(font
						(size 1.27 1.27)
						(thickness 0.15)
					)
					(justify left bottom)
					(hide yes)
				)
			)
			(property "License" "Apache-2.0"
				(at 20.32 -25.4 0)
				(effects
					(font
						(size 1.27 1.27)
						(thickness 0.15)
					)
					(justify left bottom)
					(hide yes)
				)
			)
			(property "Author" "Antmicro"
				(at 20.32 -27.94 0)
				(effects
					(font
						(size 1.27 1.27)
						(thickness 0.15)
					)
					(justify left bottom)
					(hide yes)
				)
			)
			(property "Val" "220R"
				(at 20.32 -7.62 0)
				(effects
					(font
						(size 1.27 1.27)
						(thickness 0.15)
					)
					(justify left bottom)
				)
			)
			(property "Tolerance" "1%"
				(at 20.32 -10.16 0)
				(effects
					(font
						(size 1.27 1.27)
					)
					(justify left bottom)
					(hide yes)
				)
			)
			(property "ki_keywords" "0402, SMT, RESISTOR, PASSIVE"
				(at 0 0 0)
				(effects
					(font
						(size 1.27 1.27)
					)
					(hide yes)
				)
			)
			(symbol "R_220R_0402_0_1"
				(rectangle
					(start 0.635 0.889)
					(end 4.445 -0.889)
					(stroke
						(width 0.254)
						(type default)
					)
					(fill
						(type none)
					)
				)
			)
			(symbol "R_220R_0402_1_1"
				(pin passive line
					(at 0 0 0)
					(length 0.635)
					(name "~"
						(effects
							(font
								(size 1.27 1.27)
							)
						)
					)
					(number "1"
						(effects
							(font
								(size 1.27 1.27)
							)
						)
					)
				)
				(pin passive line
					(at 5.08 0 180)
					(length 0.635)
					(name "~"
						(effects
							(font
								(size 1.27 1.27)
							)
						)
					)
					(number "2"
						(effects
							(font
								(size 1.27 1.27)
							)
						)
					)
				)
			)
		)
	(symbol "antmicroResistors0402:R_22R_0402"
			(pin_numbers
				(hide yes)
			)
			(pin_names
				(hide yes)
			)
			(exclude_from_sim no)
			(in_bom yes)
			(on_board yes)
			(property "Reference" "R"
				(at 20.32 -5.08 0)
				(effects
					(font
						(size 1.27 1.27)
						(thickness 0.15)
					)
					(justify left bottom)
				)
			)
			(property "Value" "R_22R_0402"
				(at 20.32 -12.7 0)
				(effects
					(font
						(size 1.27 1.27)
						(thickness 0.15)
					)
					(justify left bottom)
					(hide yes)
				)
			)
			(property "Footprint" "antmicro-footprints:R_0402_1005Metric"
				(at 20.32 -15.24 0)
				(effects
					(font
						(size 1.27 1.27)
						(thickness 0.15)
					)
					(justify left bottom)
					(hide yes)
				)
			)
			(property "Datasheet" "https://www.bourns.com/docs/product-datasheets/cr.pdf"
				(at 20.32 -17.78 0)
				(effects
					(font
						(size 1.27 1.27)
						(thickness 0.15)
					)
					(justify left bottom)
					(hide yes)
				)
			)
			(property "Description" "SMD Chip Resistor, 22 ohm, ± 1%, 62.5 mW, 0402 [1005 Metric], Thick Film, General Purpose"
				(at 0 0 0)
				(effects
					(font
						(size 1.27 1.27)
					)
					(hide yes)
				)
			)
			(property "MPN" "CR0402-FX-22R0GLF"
				(at 20.32 -20.32 0)
				(effects
					(font
						(size 1.27 1.27)
						(thickness 0.15)
					)
					(justify left bottom)
					(hide yes)
				)
			)
			(property "Manufacturer" "Bourns"
				(at 20.32 -22.86 0)
				(effects
					(font
						(size 1.27 1.27)
						(thickness 0.15)
					)
					(justify left bottom)
					(hide yes)
				)
			)
			(property "License" "Apache-2.0"
				(at 20.32 -25.4 0)
				(effects
					(font
						(size 1.27 1.27)
						(thickness 0.15)
					)
					(justify left bottom)
					(hide yes)
				)
			)
			(property "Author" "Antmicro"
				(at 20.32 -27.94 0)
				(effects
					(font
						(size 1.27 1.27)
						(thickness 0.15)
					)
					(justify left bottom)
					(hide yes)
				)
			)
			(property "Val" "22R"
				(at 20.32 -7.62 0)
				(effects
					(font
						(size 1.27 1.27)
						(thickness 0.15)
					)
					(justify left bottom)
				)
			)
			(property "Tolerance" "1%"
				(at 20.32 -10.16 0)
				(effects
					(font
						(size 1.27 1.27)
					)
					(justify left bottom)
					(hide yes)
				)
			)
			(symbol "R_22R_0402_0_1"
				(rectangle
					(start 0.635 0.889)
					(end 4.445 -0.889)
					(stroke
						(width 0.254)
						(type default)
					)
					(fill
						(type none)
					)
				)
			)
			(symbol "R_22R_0402_1_1"
				(pin passive line
					(at 0 0 0)
					(length 0.635)
					(name "~"
						(effects
							(font
								(size 1.27 1.27)
							)
						)
					)
					(number "1"
						(effects
							(font
								(size 1.27 1.27)
							)
						)
					)
				)
				(pin passive line
					(at 5.08 0 180)
					(length 0.635)
					(name "~"
						(effects
							(font
								(size 1.27 1.27)
							)
						)
					)
					(number "2"
						(effects
							(font
								(size 1.27 1.27)
							)
						)
					)
				)
			)
		)
	(symbol "antmicroResistors0402:R_2k2_0402"
			(pin_numbers
				(hide yes)
			)
			(pin_names
				(hide yes)
			)
			(exclude_from_sim no)
			(in_bom yes)
			(on_board yes)
			(property "Reference" "R"
				(at 20.32 -5.08 0)
				(effects
					(font
						(size 1.27 1.27)
						(thickness 0.15)
					)
					(justify left bottom)
				)
			)
			(property "Value" "R_2k2_0402"
				(at 20.32 -12.7 0)
				(effects
					(font
						(size 1.27 1.27)
						(thickness 0.15)
					)
					(justify left bottom)
					(hide yes)
				)
			)
			(property "Footprint" "antmicro-footprints:R_0402_1005Metric"
				(at 20.32 -15.24 0)
				(effects
					(font
						(size 1.27 1.27)
						(thickness 0.15)
					)
					(justify left bottom)
					(hide yes)
				)
			)
			(property "Datasheet" "https://www.bourns.com/docs/product-datasheets/cr.pdf"
				(at 20.32 -17.78 0)
				(effects
					(font
						(size 1.27 1.27)
						(thickness 0.15)
					)
					(justify left bottom)
					(hide yes)
				)
			)
			(property "Description" "SMD Chip Resistor, 2.2 kohm, ± 1%, 62.5 mW, 0402 [1005 Metric], Thick Film, General Purpose"
				(at 0 0 0)
				(effects
					(font
						(size 1.27 1.27)
					)
					(hide yes)
				)
			)
			(property "MPN" "CR0402-FX-2201GLF"
				(at 20.32 -20.32 0)
				(effects
					(font
						(size 1.27 1.27)
						(thickness 0.15)
					)
					(justify left bottom)
					(hide yes)
				)
			)
			(property "Manufacturer" "Bourns"
				(at 20.32 -22.86 0)
				(effects
					(font
						(size 1.27 1.27)
						(thickness 0.15)
					)
					(justify left bottom)
					(hide yes)
				)
			)
			(property "License" "Apache-2.0"
				(at 20.32 -25.4 0)
				(effects
					(font
						(size 1.27 1.27)
						(thickness 0.15)
					)
					(justify left bottom)
					(hide yes)
				)
			)
			(property "Author" "Antmicro"
				(at 20.32 -27.94 0)
				(effects
					(font
						(size 1.27 1.27)
						(thickness 0.15)
					)
					(justify left bottom)
					(hide yes)
				)
			)
			(property "Val" "2k2"
				(at 20.32 -7.62 0)
				(effects
					(font
						(size 1.27 1.27)
						(thickness 0.15)
					)
					(justify left bottom)
				)
			)
			(property "Tolerance" "1%"
				(at 20.32 -10.16 0)
				(effects
					(font
						(size 1.27 1.27)
					)
					(justify left bottom)
					(hide yes)
				)
			)
			(property "ki_keywords" "0402, SMT, RESISTOR, PASSIVE"
				(at 0 0 0)
				(effects
					(font
						(size 1.27 1.27)
					)
					(hide yes)
				)
			)
			(symbol "R_2k2_0402_0_1"
				(rectangle
					(start 0.635 0.889)
					(end 4.445 -0.889)
					(stroke
						(width 0.254)
						(type default)
					)
					(fill
						(type none)
					)
				)
			)
			(symbol "R_2k2_0402_1_1"
				(pin passive line
					(at 0 0 0)
					(length 0.635)
					(name "~"
						(effects
							(font
								(size 1.27 1.27)
							)
						)
					)
					(number "1"
						(effects
							(font
								(size 1.27 1.27)
							)
						)
					)
				)
				(pin passive line
					(at 5.08 0 180)
					(length 0.635)
					(name "~"
						(effects
							(font
								(size 1.27 1.27)
							)
						)
					)
					(number "2"
						(effects
							(font
								(size 1.27 1.27)
							)
						)
					)
				)
			)
		)
	(symbol "antmicroResistors0402:R_330R_0402"
			(pin_numbers
				(hide yes)
			)
			(pin_names
				(hide yes)
			)
			(exclude_from_sim no)
			(in_bom yes)
			(on_board yes)
			(property "Reference" "R"
				(at 20.32 -5.08 0)
				(effects
					(font
						(size 1.27 1.27)
						(thickness 0.15)
					)
					(justify left bottom)
				)
			)
			(property "Value" "R_330R_0402"
				(at 20.32 -12.7 0)
				(effects
					(font
						(size 1.27 1.27)
						(thickness 0.15)
					)
					(justify left bottom)
					(hide yes)
				)
			)
			(property "Footprint" "antmicro-footprints:R_0402_1005Metric"
				(at 20.32 -15.24 0)
				(effects
					(font
						(size 1.27 1.27)
						(thickness 0.15)
					)
					(justify left bottom)
					(hide yes)
				)
			)
			(property "Datasheet" "https://www.bourns.com/docs/product-datasheets/cr.pdf"
				(at 20.32 -17.78 0)
				(effects
					(font
						(size 1.27 1.27)
						(thickness 0.15)
					)
					(justify left bottom)
					(hide yes)
				)
			)
			(property "Description" "SMD Chip Resistor, 330 ohm, ± 1%, 62.5 mW, 0402 [1005 Metric], Thick Film, General Purpose"
				(at 0 0 0)
				(effects
					(font
						(size 1.27 1.27)
					)
					(hide yes)
				)
			)
			(property "MPN" "CR0402-FX-3300GLF"
				(at 20.32 -20.32 0)
				(effects
					(font
						(size 1.27 1.27)
						(thickness 0.15)
					)
					(justify left bottom)
					(hide yes)
				)
			)
			(property "Manufacturer" "Bourns"
				(at 20.32 -22.86 0)
				(effects
					(font
						(size 1.27 1.27)
						(thickness 0.15)
					)
					(justify left bottom)
					(hide yes)
				)
			)
			(property "License" "Apache-2.0"
				(at 20.32 -25.4 0)
				(effects
					(font
						(size 1.27 1.27)
						(thickness 0.15)
					)
					(justify left bottom)
					(hide yes)
				)
			)
			(property "Author" "Antmicro"
				(at 20.32 -27.94 0)
				(effects
					(font
						(size 1.27 1.27)
						(thickness 0.15)
					)
					(justify left bottom)
					(hide yes)
				)
			)
			(property "Val" "330R"
				(at 20.32 -7.62 0)
				(effects
					(font
						(size 1.27 1.27)
						(thickness 0.15)
					)
					(justify left bottom)
				)
			)
			(property "Tolerance" "1%"
				(at 20.32 -10.16 0)
				(effects
					(font
						(size 1.27 1.27)
					)
					(justify left bottom)
					(hide yes)
				)
			)
			(property "ki_keywords" "0402, SMT, RESISTOR, PASSIVE"
				(at 0 0 0)
				(effects
					(font
						(size 1.27 1.27)
					)
					(hide yes)
				)
			)
			(symbol "R_330R_0402_0_1"
				(rectangle
					(start 0.635 0.889)
					(end 4.445 -0.889)
					(stroke
						(width 0.254)
						(type default)
					)
					(fill
						(type none)
					)
				)
			)
			(symbol "R_330R_0402_1_1"
				(pin passive line
					(at 0 0 0)
					(length 0.635)
					(name "~"
						(effects
							(font
								(size 1.27 1.27)
							)
						)
					)
					(number "1"
						(effects
							(font
								(size 1.27 1.27)
							)
						)
					)
				)
				(pin passive line
					(at 5.08 0 180)
					(length 0.635)
					(name "~"
						(effects
							(font
								(size 1.27 1.27)
							)
						)
					)
					(number "2"
						(effects
							(font
								(size 1.27 1.27)
							)
						)
					)
				)
			)
		)
	(symbol "antmicroResistors0402:R_47k_0402"
			(pin_numbers
				(hide yes)
			)
			(pin_names
				(hide yes)
			)
			(exclude_from_sim no)
			(in_bom yes)
			(on_board yes)
			(property "Reference" "R"
				(at 20.32 -5.08 0)
				(effects
					(font
						(size 1.27 1.27)
						(thickness 0.15)
					)
					(justify left bottom)
				)
			)
			(property "Value" "R_47k_0402"
				(at 20.32 -12.7 0)
				(effects
					(font
						(size 1.27 1.27)
						(thickness 0.15)
					)
					(justify left bottom)
					(hide yes)
				)
			)
			(property "Footprint" "antmicro-footprints:R_0402_1005Metric"
				(at 20.32 -15.24 0)
				(effects
					(font
						(size 1.27 1.27)
						(thickness 0.15)
					)
					(justify left bottom)
					(hide yes)
				)
			)
			(property "Datasheet" "https://www.bourns.com/docs/product-datasheets/cr.pdf"
				(at 20.32 -17.78 0)
				(effects
					(font
						(size 1.27 1.27)
						(thickness 0.15)
					)
					(justify left bottom)
					(hide yes)
				)
			)
			(property "Description" "SMD Chip Resistor, 47 kohm, ± 1%, 62.5 mW, 0402 [1005 Metric], Thick Film, General Purpose"
				(at 0 0 0)
				(effects
					(font
						(size 1.27 1.27)
					)
					(hide yes)
				)
			)
			(property "MPN" "CR0402-FX-4702GLF"
				(at 20.32 -20.32 0)
				(effects
					(font
						(size 1.27 1.27)
						(thickness 0.15)
					)
					(justify left bottom)
					(hide yes)
				)
			)
			(property "Manufacturer" "Bourns"
				(at 20.32 -22.86 0)
				(effects
					(font
						(size 1.27 1.27)
						(thickness 0.15)
					)
					(justify left bottom)
					(hide yes)
				)
			)
			(property "License" "Apache-2.0"
				(at 20.32 -25.4 0)
				(effects
					(font
						(size 1.27 1.27)
						(thickness 0.15)
					)
					(justify left bottom)
					(hide yes)
				)
			)
			(property "Author" "Antmicro"
				(at 20.32 -27.94 0)
				(effects
					(font
						(size 1.27 1.27)
						(thickness 0.15)
					)
					(justify left bottom)
					(hide yes)
				)
			)
			(property "Val" "47k"
				(at 20.32 -7.62 0)
				(effects
					(font
						(size 1.27 1.27)
						(thickness 0.15)
					)
					(justify left bottom)
				)
			)
			(property "Tolerance" "1%"
				(at 20.32 -10.16 0)
				(effects
					(font
						(size 1.27 1.27)
					)
					(justify left bottom)
					(hide yes)
				)
			)
			(property "ki_keywords" "0402, SMT, RESISTOR, PASSIVE"
				(at 0 0 0)
				(effects
					(font
						(size 1.27 1.27)
					)
					(hide yes)
				)
			)
			(symbol "R_47k_0402_0_1"
				(rectangle
					(start 0.635 0.889)
					(end 4.445 -0.889)
					(stroke
						(width 0.254)
						(type default)
					)
					(fill
						(type none)
					)
				)
			)
			(symbol "R_47k_0402_1_1"
				(pin passive line
					(at 0 0 0)
					(length 0.635)
					(name "~"
						(effects
							(font
								(size 1.27 1.27)
							)
						)
					)
					(number "1"
						(effects
							(font
								(size 1.27 1.27)
							)
						)
					)
				)
				(pin passive line
					(at 5.08 0 180)
					(length 0.635)
					(name "~"
						(effects
							(font
								(size 1.27 1.27)
							)
						)
					)
					(number "2"
						(effects
							(font
								(size 1.27 1.27)
							)
						)
					)
				)
			)
		)
	(symbol "antmicroResistors0402:R_4k7_0402"
			(pin_numbers
				(hide yes)
			)
			(pin_names
				(hide yes)
			)
			(exclude_from_sim no)
			(in_bom yes)
			(on_board yes)
			(property "Reference" "R"
				(at 20.32 -5.08 0)
				(effects
					(font
						(size 1.27 1.27)
						(thickness 0.15)
					)
					(justify left bottom)
				)
			)
			(property "Value" "R_4k7_0402"
				(at 20.32 -12.7 0)
				(effects
					(font
						(size 1.27 1.27)
						(thickness 0.15)
					)
					(justify left bottom)
					(hide yes)
				)
			)
			(property "Footprint" "antmicro-footprints:R_0402_1005Metric"
				(at 20.32 -15.24 0)
				(effects
					(font
						(size 1.27 1.27)
						(thickness 0.15)
					)
					(justify left bottom)
					(hide yes)
				)
			)
			(property "Datasheet" "https://www.bourns.com/docs/product-datasheets/cr.pdf"
				(at 20.32 -17.78 0)
				(effects
					(font
						(size 1.27 1.27)
						(thickness 0.15)
					)
					(justify left bottom)
					(hide yes)
				)
			)
			(property "Description" "SMD Chip Resistor, 4.7 kohm, ± 1%, 62.5 mW, 0402 [1005 Metric], Thick Film, General Purpose"
				(at 0 0 0)
				(effects
					(font
						(size 1.27 1.27)
					)
					(hide yes)
				)
			)
			(property "MPN" "CR0402-FX-4701GLF"
				(at 20.32 -20.32 0)
				(effects
					(font
						(size 1.27 1.27)
						(thickness 0.15)
					)
					(justify left bottom)
					(hide yes)
				)
			)
			(property "Manufacturer" "Bourns"
				(at 20.32 -22.86 0)
				(effects
					(font
						(size 1.27 1.27)
						(thickness 0.15)
					)
					(justify left bottom)
					(hide yes)
				)
			)
			(property "License" "Apache-2.0"
				(at 20.32 -25.4 0)
				(effects
					(font
						(size 1.27 1.27)
						(thickness 0.15)
					)
					(justify left bottom)
					(hide yes)
				)
			)
			(property "Author" "Antmicro"
				(at 20.32 -27.94 0)
				(effects
					(font
						(size 1.27 1.27)
						(thickness 0.15)
					)
					(justify left bottom)
					(hide yes)
				)
			)
			(property "Val" "4k7"
				(at 20.32 -7.62 0)
				(effects
					(font
						(size 1.27 1.27)
						(thickness 0.15)
					)
					(justify left bottom)
				)
			)
			(property "Tolerance" "1%"
				(at 20.32 -10.16 0)
				(effects
					(font
						(size 1.27 1.27)
					)
					(justify left bottom)
					(hide yes)
				)
			)
			(property "ki_keywords" "0402, SMT, RESISTOR, PASSIVE"
				(at 0 0 0)
				(effects
					(font
						(size 1.27 1.27)
					)
					(hide yes)
				)
			)
			(symbol "R_4k7_0402_0_1"
				(rectangle
					(start 0.635 0.889)
					(end 4.445 -0.889)
					(stroke
						(width 0.254)
						(type default)
					)
					(fill
						(type none)
					)
				)
			)
			(symbol "R_4k7_0402_1_1"
				(pin passive line
					(at 0 0 0)
					(length 0.635)
					(name "~"
						(effects
							(font
								(size 1.27 1.27)
							)
						)
					)
					(number "1"
						(effects
							(font
								(size 1.27 1.27)
							)
						)
					)
				)
				(pin passive line
					(at 5.08 0 180)
					(length 0.635)
					(name "~"
						(effects
							(font
								(size 1.27 1.27)
							)
						)
					)
					(number "2"
						(effects
							(font
								(size 1.27 1.27)
							)
						)
					)
				)
			)
		)
	(symbol "antmicroResistors0402:R_5k11_0402"
			(pin_numbers
				(hide yes)
			)
			(pin_names
				(hide yes)
			)
			(exclude_from_sim no)
			(in_bom yes)
			(on_board yes)
			(property "Reference" "R"
				(at 20.32 -5.08 0)
				(effects
					(font
						(size 1.27 1.27)
						(thickness 0.15)
					)
					(justify left bottom)
				)
			)
			(property "Value" "R_5k11_0402"
				(at 20.32 -12.7 0)
				(effects
					(font
						(size 1.27 1.27)
						(thickness 0.15)
					)
					(justify left bottom)
					(hide yes)
				)
			)
			(property "Footprint" "antmicro-footprints:R_0402_1005Metric"
				(at 20.32 -15.24 0)
				(effects
					(font
						(size 1.27 1.27)
						(thickness 0.15)
					)
					(justify left bottom)
					(hide yes)
				)
			)
			(property "Datasheet" "https://www.bourns.com/docs/product-datasheets/cr.pdf"
				(at 20.32 -17.78 0)
				(effects
					(font
						(size 1.27 1.27)
						(thickness 0.15)
					)
					(justify left bottom)
					(hide yes)
				)
			)
			(property "Description" "SMD Chip Resistor, 5.11 kohm, ± 1%, 63 mW, 0402 [1005 Metric], Thick Film, General Purpose"
				(at 0 0 0)
				(effects
					(font
						(size 1.27 1.27)
					)
					(hide yes)
				)
			)
			(property "MPN" "CR0402-FX-5111GLF"
				(at 20.32 -20.32 0)
				(effects
					(font
						(size 1.27 1.27)
						(thickness 0.15)
					)
					(justify left bottom)
					(hide yes)
				)
			)
			(property "Manufacturer" "Bourns"
				(at 20.32 -22.86 0)
				(effects
					(font
						(size 1.27 1.27)
						(thickness 0.15)
					)
					(justify left bottom)
					(hide yes)
				)
			)
			(property "License" "Apache-2.0"
				(at 20.32 -25.4 0)
				(effects
					(font
						(size 1.27 1.27)
						(thickness 0.15)
					)
					(justify left bottom)
					(hide yes)
				)
			)
			(property "Author" "Antmicro"
				(at 20.32 -27.94 0)
				(effects
					(font
						(size 1.27 1.27)
						(thickness 0.15)
					)
					(justify left bottom)
					(hide yes)
				)
			)
			(property "Val" "5k11"
				(at 20.32 -7.62 0)
				(effects
					(font
						(size 1.27 1.27)
						(thickness 0.15)
					)
					(justify left bottom)
				)
			)
			(property "Tolerance" "1%"
				(at 20.32 -10.16 0)
				(effects
					(font
						(size 1.27 1.27)
					)
					(justify left bottom)
					(hide yes)
				)
			)
			(property "ki_keywords" "0402, SMT, RESISTOR, PASSIVE"
				(at 0 0 0)
				(effects
					(font
						(size 1.27 1.27)
					)
					(hide yes)
				)
			)
			(symbol "R_5k11_0402_0_1"
				(rectangle
					(start 0.635 0.889)
					(end 4.445 -0.889)
					(stroke
						(width 0.254)
						(type default)
					)
					(fill
						(type none)
					)
				)
			)
			(symbol "R_5k11_0402_1_1"
				(pin passive line
					(at 0 0 0)
					(length 0.635)
					(name "~"
						(effects
							(font
								(size 1.27 1.27)
							)
						)
					)
					(number "1"
						(effects
							(font
								(size 1.27 1.27)
							)
						)
					)
				)
				(pin passive line
					(at 5.08 0 180)
					(length 0.635)
					(name "~"
						(effects
							(font
								(size 1.27 1.27)
							)
						)
					)
					(number "2"
						(effects
							(font
								(size 1.27 1.27)
							)
						)
					)
				)
			)
		)
	(symbol "antmicroResistors0402:R_80R6_0402_EIA"
			(pin_numbers
				(hide yes)
			)
			(pin_names
				(hide yes)
			)
			(exclude_from_sim no)
			(in_bom yes)
			(on_board yes)
			(property "Reference" "R"
				(at 20.32 -5.08 0)
				(effects
					(font
						(size 1.27 1.27)
						(thickness 0.15)
					)
					(justify left bottom)
				)
			)
			(property "Value" "R_80R6_0402_EIA"
				(at 20.32 -12.7 0)
				(effects
					(font
						(size 1.27 1.27)
						(thickness 0.15)
					)
					(justify left bottom)
					(hide yes)
				)
			)
			(property "Footprint" "antmicro-footprints:R_0402_1005Metric_EIA"
				(at 20.32 -15.24 0)
				(effects
					(font
						(size 1.27 1.27)
						(thickness 0.15)
					)
					(justify left bottom)
					(hide yes)
				)
			)
			(property "Datasheet" "https://www.bourns.com/docs/product-datasheets/cr.pdf"
				(at 20.32 -17.78 0)
				(effects
					(font
						(size 1.27 1.27)
						(thickness 0.15)
					)
					(justify left bottom)
					(hide yes)
				)
			)
			(property "Description" "SMD Chip Resistor, 80.6 ohm, ± 1%, 62.5 mW, 0402 [1005 Metric], Thick Film, General Purpose"
				(at 0 0 0)
				(effects
					(font
						(size 1.27 1.27)
					)
					(hide yes)
				)
			)
			(property "MPN" "MC00625W0402180R6"
				(at 20.32 -20.32 0)
				(effects
					(font
						(size 1.27 1.27)
						(thickness 0.15)
					)
					(justify left bottom)
					(hide yes)
				)
			)
			(property "Manufacturer" "Multicomp Pro"
				(at 20.32 -22.86 0)
				(effects
					(font
						(size 1.27 1.27)
						(thickness 0.15)
					)
					(justify left bottom)
					(hide yes)
				)
			)
			(property "License" "Apache-2.0"
				(at 20.32 -25.4 0)
				(effects
					(font
						(size 1.27 1.27)
						(thickness 0.15)
					)
					(justify left bottom)
					(hide yes)
				)
			)
			(property "Author" "Antmicro"
				(at 20.32 -27.94 0)
				(effects
					(font
						(size 1.27 1.27)
						(thickness 0.15)
					)
					(justify left bottom)
					(hide yes)
				)
			)
			(property "Val" "80R6"
				(at 20.32 -7.62 0)
				(effects
					(font
						(size 1.27 1.27)
						(thickness 0.15)
					)
					(justify left bottom)
				)
			)
			(property "Tolerance" "1%"
				(at 20.32 -10.16 0)
				(effects
					(font
						(size 1.27 1.27)
					)
					(justify left bottom)
					(hide yes)
				)
			)
			(property "ki_keywords" "0402, SMT, RESISTOR, PASSIVE"
				(at 0 0 0)
				(effects
					(font
						(size 1.27 1.27)
					)
					(hide yes)
				)
			)
			(symbol "R_80R6_0402_EIA_0_1"
				(rectangle
					(start 0.635 0.889)
					(end 4.445 -0.889)
					(stroke
						(width 0.254)
						(type default)
					)
					(fill
						(type none)
					)
				)
			)
			(symbol "R_80R6_0402_EIA_1_1"
				(pin passive line
					(at 0 0 0)
					(length 0.635)
					(name "~"
						(effects
							(font
								(size 1.27 1.27)
							)
						)
					)
					(number "1"
						(effects
							(font
								(size 1.27 1.27)
							)
						)
					)
				)
				(pin passive line
					(at 5.08 0 180)
					(length 0.635)
					(name "~"
						(effects
							(font
								(size 1.27 1.27)
							)
						)
					)
					(number "2"
						(effects
							(font
								(size 1.27 1.27)
							)
						)
					)
				)
			)
		)
	(symbol "antmicroResistors0402:R_80k6_0402"
			(pin_numbers
				(hide yes)
			)
			(pin_names
				(hide yes)
			)
			(exclude_from_sim no)
			(in_bom yes)
			(on_board yes)
			(property "Reference" "R"
				(at 20.32 -5.08 0)
				(effects
					(font
						(size 1.27 1.27)
						(thickness 0.15)
					)
					(justify left bottom)
				)
			)
			(property "Value" "R_80k6_0402"
				(at 20.32 -12.7 0)
				(effects
					(font
						(size 1.27 1.27)
						(thickness 0.15)
					)
					(justify left bottom)
					(hide yes)
				)
			)
			(property "Footprint" "antmicro-footprints:R_0402_1005Metric"
				(at 20.32 -15.24 0)
				(effects
					(font
						(size 1.27 1.27)
						(thickness 0.15)
					)
					(justify left bottom)
					(hide yes)
				)
			)
			(property "Datasheet" "https://www.bourns.com/docs/product-datasheets/cr.pdf"
				(at 20.32 -17.78 0)
				(effects
					(font
						(size 1.27 1.27)
						(thickness 0.15)
					)
					(justify left bottom)
					(hide yes)
				)
			)
			(property "Description" "SMD Chip Resistor, 80.6 kohm, ± 1%, 100 mW, 0402 [1005 Metric], Thick Film, Precision"
				(at 0 0 0)
				(effects
					(font
						(size 1.27 1.27)
					)
					(hide yes)
				)
			)
			(property "MPN" "CR0402-FX-8062GLF"
				(at 20.32 -20.32 0)
				(effects
					(font
						(size 1.27 1.27)
						(thickness 0.15)
					)
					(justify left bottom)
					(hide yes)
				)
			)
			(property "Manufacturer" "Bourns"
				(at 20.32 -22.86 0)
				(effects
					(font
						(size 1.27 1.27)
						(thickness 0.15)
					)
					(justify left bottom)
					(hide yes)
				)
			)
			(property "License" "Apache-2.0"
				(at 20.32 -25.4 0)
				(effects
					(font
						(size 1.27 1.27)
						(thickness 0.15)
					)
					(justify left bottom)
					(hide yes)
				)
			)
			(property "Author" "Antmicro"
				(at 20.32 -27.94 0)
				(effects
					(font
						(size 1.27 1.27)
						(thickness 0.15)
					)
					(justify left bottom)
					(hide yes)
				)
			)
			(property "Val" "80k6"
				(at 20.32 -7.62 0)
				(effects
					(font
						(size 1.27 1.27)
						(thickness 0.15)
					)
					(justify left bottom)
				)
			)
			(property "Tolerance" "1%"
				(at 20.32 -10.16 0)
				(effects
					(font
						(size 1.27 1.27)
					)
					(justify left bottom)
					(hide yes)
				)
			)
			(property "ki_keywords" "0402, SMT, RESISTOR, PASSIVE"
				(at 0 0 0)
				(effects
					(font
						(size 1.27 1.27)
					)
					(hide yes)
				)
			)
			(symbol "R_80k6_0402_0_1"
				(rectangle
					(start 0.635 0.889)
					(end 4.445 -0.889)
					(stroke
						(width 0.254)
						(type default)
					)
					(fill
						(type none)
					)
				)
			)
			(symbol "R_80k6_0402_1_1"
				(pin passive line
					(at 0 0 0)
					(length 0.635)
					(name "~"
						(effects
							(font
								(size 1.27 1.27)
							)
						)
					)
					(number "1"
						(effects
							(font
								(size 1.27 1.27)
							)
						)
					)
				)
				(pin passive line
					(at 5.08 0 180)
					(length 0.635)
					(name "~"
						(effects
							(font
								(size 1.27 1.27)
							)
						)
					)
					(number "2"
						(effects
							(font
								(size 1.27 1.27)
							)
						)
					)
				)
			)
		)
	(symbol "antmicroResistors0603:R_0R_22.4A_0603"
			(pin_numbers
				(hide yes)
			)
			(pin_names
				(hide yes)
			)
			(exclude_from_sim no)
			(in_bom yes)
			(on_board yes)
			(property "Reference" "R"
				(at 15.24 -2.54 0)
				(effects
					(font
						(size 1.27 1.27)
						(thickness 0.15)
					)
					(justify left bottom)
				)
			)
			(property "Value" "R_0R_22.4A_0603"
				(at 15.24 -5.08 0)
				(effects
					(font
						(size 1.27 1.27)
						(thickness 0.15)
					)
					(justify left bottom)
				)
			)
			(property "Footprint" "antmicro-footprints:R_0603_1608Metric"
				(at 15.24 -10.16 0)
				(effects
					(font
						(size 1.27 1.27)
						(thickness 0.15)
					)
					(justify left bottom)
					(hide yes)
				)
			)
			(property "Datasheet" "https://fscdn.rohm.com/en/products/databook/datasheet/passive/resistor/chip_resistor/pmr-jpw-e.pdf"
				(at 15.24 -12.7 0)
				(effects
					(font
						(size 1.27 1.27)
						(thickness 0.15)
					)
					(justify left bottom)
					(hide yes)
				)
			)
			(property "Description" "SMD Chip Resistor"
				(at 0 0 0)
				(effects
					(font
						(size 1.27 1.27)
					)
					(hide yes)
				)
			)
			(property "MPN" "PMR03EZPJ000"
				(at 15.24 -15.24 0)
				(effects
					(font
						(size 1.27 1.27)
						(thickness 0.15)
					)
					(justify left bottom)
					(hide yes)
				)
			)
			(property "Manufacturer" "ROHM Semiconductor"
				(at 15.24 -17.78 0)
				(effects
					(font
						(size 1.27 1.27)
						(thickness 0.15)
					)
					(justify left bottom)
					(hide yes)
				)
			)
			(property "Val" "0R"
				(at 15.24 -7.62 0)
				(effects
					(font
						(size 1.27 1.27)
						(thickness 0.15)
					)
					(justify left bottom)
				)
			)
			(property "Max. Curr." "22.4A"
				(at 15.24 -20.32 0)
				(effects
					(font
						(size 1.27 1.27)
						(thickness 0.15)
					)
					(justify left bottom)
				)
			)
			(property "Author" "Antmicro"
				(at 15.24 -22.86 0)
				(effects
					(font
						(size 1.27 1.27)
						(thickness 0.15)
					)
					(justify left bottom)
					(hide yes)
				)
			)
			(property "License" "Apache-2.0"
				(at 15.24 -25.4 0)
				(effects
					(font
						(size 1.27 1.27)
						(thickness 0.15)
					)
					(justify left bottom)
					(hide yes)
				)
			)
			(property "Tolerance" "template_tolerance"
				(at 20.32 -10.16 0)
				(effects
					(font
						(size 1.27 1.27)
					)
					(justify left bottom)
					(hide yes)
				)
			)
			(property "ki_keywords" "0603, SMT, RESISTOR, PASSIVE"
				(at 0 0 0)
				(effects
					(font
						(size 1.27 1.27)
					)
					(hide yes)
				)
			)
			(symbol "R_0R_22.4A_0603_0_1"
				(rectangle
					(start 0.635 0.889)
					(end 4.445 -0.889)
					(stroke
						(width 0.254)
						(type default)
					)
					(fill
						(type none)
					)
				)
			)
			(symbol "R_0R_22.4A_0603_1_1"
				(pin passive line
					(at 0 0 0)
					(length 0.635)
					(name "~"
						(effects
							(font
								(size 1.27 1.27)
							)
						)
					)
					(number "1"
						(effects
							(font
								(size 1.27 1.27)
							)
						)
					)
				)
				(pin passive line
					(at 5.08 0 180)
					(length 0.635)
					(name "~"
						(effects
							(font
								(size 1.27 1.27)
							)
						)
					)
					(number "2"
						(effects
							(font
								(size 1.27 1.27)
							)
						)
					)
				)
			)
		)
	(symbol "antmicroResistorsmisc:R_0R01_1206"
			(pin_numbers
				(hide yes)
			)
			(pin_names
				(hide yes)
			)
			(exclude_from_sim no)
			(in_bom yes)
			(on_board yes)
			(property "Reference" "R"
				(at 20.32 -5.08 0)
				(effects
					(font
						(size 1.27 1.27)
						(thickness 0.15)
					)
					(justify left bottom)
				)
			)
			(property "Value" "R_0R01_1206"
				(at 20.32 -12.7 0)
				(effects
					(font
						(size 1.27 1.27)
						(thickness 0.15)
					)
					(justify left bottom)
					(hide yes)
				)
			)
			(property "Footprint" "antmicro-footprints:R_1206_3216Metric"
				(at 20.32 -15.24 0)
				(effects
					(font
						(size 1.27 1.27)
						(thickness 0.15)
					)
					(justify left bottom)
					(hide yes)
				)
			)
			(property "Datasheet" "https://www.yageo.com/upload/media/product/productsearch/datasheet/rchip/PYu-RL_Group_521_RoHS_L_2.pdf"
				(at 20.32 -17.78 0)
				(effects
					(font
						(size 1.27 1.27)
						(thickness 0.15)
					)
					(justify left bottom)
					(hide yes)
				)
			)
			(property "Description" "SMD Chip Resistor, 0.01 ohm, ± 1%, 500 mW, 1206 [3216 Metric], Thick Film, General Purpose"
				(at 0 0 0)
				(effects
					(font
						(size 1.27 1.27)
					)
					(hide yes)
				)
			)
			(property "MPN" "RL1206FR-7W0R01L"
				(at 20.32 -20.32 0)
				(effects
					(font
						(size 1.27 1.27)
						(thickness 0.15)
					)
					(justify left bottom)
					(hide yes)
				)
			)
			(property "Manufacturer" "YAGEO"
				(at 20.32 -22.86 0)
				(effects
					(font
						(size 1.27 1.27)
						(thickness 0.15)
					)
					(justify left bottom)
					(hide yes)
				)
			)
			(property "License" "Apache-2.0"
				(at 20.32 -25.4 0)
				(effects
					(font
						(size 1.27 1.27)
						(thickness 0.15)
					)
					(justify left bottom)
					(hide yes)
				)
			)
			(property "Author" "Antmicro"
				(at 20.32 -27.94 0)
				(effects
					(font
						(size 1.27 1.27)
						(thickness 0.15)
					)
					(justify left bottom)
					(hide yes)
				)
			)
			(property "Val" "0R01"
				(at 20.32 -7.62 0)
				(effects
					(font
						(size 1.27 1.27)
						(thickness 0.15)
					)
					(justify left bottom)
				)
			)
			(property "Tolerance" "1%"
				(at 20.32 -10.16 0)
				(effects
					(font
						(size 1.27 1.27)
					)
					(justify left bottom)
					(hide yes)
				)
			)
			(property "ki_keywords" "0402, SMT, RESISTOR, PASSIVE"
				(at 0 0 0)
				(effects
					(font
						(size 1.27 1.27)
					)
					(hide yes)
				)
			)
			(symbol "R_0R01_1206_0_1"
				(rectangle
					(start 0.635 0.889)
					(end 4.445 -0.889)
					(stroke
						(width 0.254)
						(type default)
					)
					(fill
						(type none)
					)
				)
			)
			(symbol "R_0R01_1206_1_1"
				(pin passive line
					(at 0 0 0)
					(length 0.635)
					(name "~"
						(effects
							(font
								(size 1.27 1.27)
							)
						)
					)
					(number "1"
						(effects
							(font
								(size 1.27 1.27)
							)
						)
					)
				)
				(pin passive line
					(at 5.08 0 180)
					(length 0.635)
					(name "~"
						(effects
							(font
								(size 1.27 1.27)
							)
						)
					)
					(number "2"
						(effects
							(font
								(size 1.27 1.27)
							)
						)
					)
				)
			)
		)
	(symbol "antmicroResistorsmisc:R_0R_0201"
			(pin_numbers
				(hide yes)
			)
			(pin_names
				(hide yes)
			)
			(exclude_from_sim no)
			(in_bom yes)
			(on_board yes)
			(property "Reference" "R"
				(at 20.32 -5.08 0)
				(effects
					(font
						(size 1.27 1.27)
						(thickness 0.15)
					)
					(justify left bottom)
				)
			)
			(property "Value" "R_0R_0201"
				(at 20.32 -12.7 0)
				(effects
					(font
						(size 1.27 1.27)
						(thickness 0.15)
					)
					(justify left bottom)
					(hide yes)
				)
			)
			(property "Footprint" "antmicro-footprints:R_0201"
				(at 20.32 -15.24 0)
				(effects
					(font
						(size 1.27 1.27)
						(thickness 0.15)
					)
					(justify left bottom)
					(hide yes)
				)
			)
			(property "Datasheet" "https://www.bourns.com/docs/product-datasheets/cr.pdf"
				(at 20.32 -17.78 0)
				(effects
					(font
						(size 1.27 1.27)
						(thickness 0.15)
					)
					(justify left bottom)
					(hide yes)
				)
			)
			(property "Description" "SMD Chip Resistor"
				(at 0 0 0)
				(effects
					(font
						(size 1.27 1.27)
					)
					(hide yes)
				)
			)
			(property "MPN" "CR0201-FX-0R00GLF"
				(at 20.32 -20.32 0)
				(effects
					(font
						(size 1.27 1.27)
						(thickness 0.15)
					)
					(justify left bottom)
					(hide yes)
				)
			)
			(property "Manufacturer" "Bourns"
				(at 20.32 -22.86 0)
				(effects
					(font
						(size 1.27 1.27)
						(thickness 0.15)
					)
					(justify left bottom)
					(hide yes)
				)
			)
			(property "License" "Apache-2.0"
				(at 20.32 -25.4 0)
				(effects
					(font
						(size 1.27 1.27)
						(thickness 0.15)
					)
					(justify left bottom)
					(hide yes)
				)
			)
			(property "Author" "Antmicro"
				(at 20.32 -27.94 0)
				(effects
					(font
						(size 1.27 1.27)
						(thickness 0.15)
					)
					(justify left bottom)
					(hide yes)
				)
			)
			(property "Val" "0R"
				(at 20.32 -7.62 0)
				(effects
					(font
						(size 1.27 1.27)
						(thickness 0.15)
					)
					(justify left bottom)
				)
			)
			(property "Tolerance" "1%"
				(at 20.32 -10.16 0)
				(effects
					(font
						(size 1.27 1.27)
					)
					(justify left bottom)
					(hide yes)
				)
			)
			(symbol "R_0R_0201_0_1"
				(rectangle
					(start 0.635 0.889)
					(end 4.445 -0.889)
					(stroke
						(width 0.254)
						(type default)
					)
					(fill
						(type none)
					)
				)
			)
			(symbol "R_0R_0201_1_1"
				(pin passive line
					(at 0 0 0)
					(length 0.635)
					(name "~"
						(effects
							(font
								(size 1.27 1.27)
							)
						)
					)
					(number "1"
						(effects
							(font
								(size 1.27 1.27)
							)
						)
					)
				)
				(pin passive line
					(at 5.08 0 180)
					(length 0.635)
					(name "~"
						(effects
							(font
								(size 1.27 1.27)
							)
						)
					)
					(number "2"
						(effects
							(font
								(size 1.27 1.27)
							)
						)
					)
				)
			)
		)
	(symbol "antmicroResonators:Resonator_12MHz_ABM8G"
			(pin_names
				(hide yes)
			)
			(exclude_from_sim no)
			(in_bom yes)
			(on_board yes)
			(property "Reference" "Y"
				(at 15.24 -5.08 0)
				(effects
					(font
						(size 1.27 1.27)
						(thickness 0.15)
					)
					(justify left bottom)
				)
			)
			(property "Value" "Resonator_12MHz_ABM8G"
				(at 15.24 -12.7 0)
				(effects
					(font
						(size 1.27 1.27)
						(thickness 0.15)
					)
					(justify left bottom)
					(hide yes)
				)
			)
			(property "Footprint" "antmicro-footprints:Resonator_SMD_Abracon_ABM8G_3.2x2.5mm"
				(at 15.24 -15.24 0)
				(effects
					(font
						(size 1.27 1.27)
						(thickness 0.15)
					)
					(justify left bottom)
					(hide yes)
				)
			)
			(property "Datasheet" "https://abracon.com/Resonators/ABM8G.pdf"
				(at 15.24 -17.78 0)
				(effects
					(font
						(size 1.27 1.27)
						(thickness 0.15)
					)
					(justify left bottom)
					(hide yes)
				)
			)
			(property "Description" "Crystal, 24 MHz, SMT, 3.2mm x 2.5mm, 30 ppm, 18 pF, 20 ppm, ABM8G"
				(at 0 0 0)
				(effects
					(font
						(size 1.27 1.27)
					)
					(hide yes)
				)
			)
			(property "MPN" "ABM8G-12.000MHZ-18-D2Y-T"
				(at 15.24 -7.62 0)
				(effects
					(font
						(size 1.27 1.27)
						(thickness 0.15)
					)
					(justify left bottom)
					(hide yes)
				)
			)
			(property "Manufacturer" "Abracon"
				(at 15.24 -20.32 0)
				(effects
					(font
						(size 1.27 1.27)
						(thickness 0.15)
					)
					(justify left bottom)
					(hide yes)
				)
			)
			(property "Author" "Antmicro"
				(at 15.24 -22.86 0)
				(effects
					(font
						(size 1.27 1.27)
						(thickness 0.15)
					)
					(justify left bottom)
					(hide yes)
				)
			)
			(property "License" "Apache-2.0"
				(at 15.24 -25.4 0)
				(effects
					(font
						(size 1.27 1.27)
						(thickness 0.15)
					)
					(justify left bottom)
					(hide yes)
				)
			)
			(property "Val" "12 MHz"
				(at 15.24 -10.16 0)
				(effects
					(font
						(size 1.27 1.27)
						(thickness 0.15)
					)
					(justify left bottom)
				)
			)
			(property "ki_keywords" "SMT, CERAMIC, OSCILLATOR"
				(at 0 0 0)
				(effects
					(font
						(size 1.27 1.27)
					)
					(hide yes)
				)
			)
			(symbol "Resonator_12MHz_ABM8G_1_1"
				(polyline
					(pts
						(xy 1.905 1.905) (xy 1.905 2.54) (xy 5.715 2.54) (xy 5.715 1.905)
					)
					(stroke
						(width 0.254)
						(type default)
					)
					(fill
						(type none)
					)
				)
				(polyline
					(pts
						(xy 1.905 -1.905) (xy 1.905 -2.54) (xy 5.715 -2.54) (xy 5.715 -1.905)
					)
					(stroke
						(width 0.254)
						(type default)
					)
					(fill
						(type none)
					)
				)
				(polyline
					(pts
						(xy 2.54 1.27) (xy 2.54 -1.27)
					)
					(stroke
						(width 0.254)
						(type default)
					)
					(fill
						(type background)
					)
				)
				(rectangle
					(start 3.175 1.905)
					(end 4.445 -1.905)
					(stroke
						(width 0.254)
						(type default)
					)
					(fill
						(type background)
					)
				)
				(polyline
					(pts
						(xy 5.08 1.27) (xy 5.08 -1.27)
					)
					(stroke
						(width 0.254)
						(type default)
					)
					(fill
						(type background)
					)
				)
				(pin passive line
					(at 0 0 0)
					(length 2.54)
					(name "~"
						(effects
							(font
								(size 1.27 1.27)
							)
						)
					)
					(number "1"
						(effects
							(font
								(size 1.27 1.27)
							)
						)
					)
				)
				(pin passive line
					(at 3.81 -5.08 90)
					(length 2.54)
					(name "SH"
						(effects
							(font
								(size 1.27 1.27)
							)
						)
					)
					(number "2"
						(effects
							(font
								(size 1.27 1.27)
							)
						)
					)
				)
				(pin passive line
					(at 3.81 -5.08 90)
					(length 2.54)
					(hide yes)
					(name "SH"
						(effects
							(font
								(size 1.27 1.27)
							)
						)
					)
					(number "4"
						(effects
							(font
								(size 1.27 1.27)
							)
						)
					)
				)
				(pin passive line
					(at 7.62 0 180)
					(length 2.54)
					(name "~"
						(effects
							(font
								(size 1.27 1.27)
							)
						)
					)
					(number "3"
						(effects
							(font
								(size 1.27 1.27)
							)
						)
					)
				)
			)
		)
	(symbol "antmicroResonators:Resonator_25MHz_ABM8G"
			(pin_names
				(hide yes)
			)
			(exclude_from_sim no)
			(in_bom yes)
			(on_board yes)
			(property "Reference" "Y"
				(at 15.24 -5.08 0)
				(effects
					(font
						(size 1.27 1.27)
						(thickness 0.15)
					)
					(justify left bottom)
				)
			)
			(property "Value" "Resonator_25MHz_ABM8G"
				(at 15.24 -12.7 0)
				(effects
					(font
						(size 1.27 1.27)
						(thickness 0.15)
					)
					(justify left bottom)
					(hide yes)
				)
			)
			(property "Footprint" "antmicro-footprints:Resonator_SMD_Abracon_ABM8G_3.2x2.5mm"
				(at 15.24 -15.24 0)
				(effects
					(font
						(size 1.27 1.27)
						(thickness 0.15)
					)
					(justify left bottom)
					(hide yes)
				)
			)
			(property "Datasheet" "https://abracon.com/Resonators/ABM8G.pdf"
				(at 15.24 -17.78 0)
				(effects
					(font
						(size 1.27 1.27)
						(thickness 0.15)
					)
					(justify left bottom)
					(hide yes)
				)
			)
			(property "Description" "Crystal, 25 MHz, SMD, 3.2mm x 2.5mm, 30 ppm, 18 pF, 20 ppm, ABM8G"
				(at 0 0 0)
				(effects
					(font
						(size 1.27 1.27)
					)
					(hide yes)
				)
			)
			(property "MPN" "ABM8G-25.000MHZ-18-D2Y-T3"
				(at 15.24 -7.62 0)
				(effects
					(font
						(size 1.27 1.27)
						(thickness 0.15)
					)
					(justify left bottom)
					(hide yes)
				)
			)
			(property "Manufacturer" "Abracon"
				(at 15.24 -20.32 0)
				(effects
					(font
						(size 1.27 1.27)
						(thickness 0.15)
					)
					(justify left bottom)
					(hide yes)
				)
			)
			(property "Author" "Antmicro"
				(at 15.24 -22.86 0)
				(effects
					(font
						(size 1.27 1.27)
						(thickness 0.15)
					)
					(justify left bottom)
					(hide yes)
				)
			)
			(property "License" "Apache-2.0"
				(at 15.24 -25.4 0)
				(effects
					(font
						(size 1.27 1.27)
						(thickness 0.15)
					)
					(justify left bottom)
					(hide yes)
				)
			)
			(property "Val" "25 MHz"
				(at 15.24 -10.16 0)
				(effects
					(font
						(size 1.27 1.27)
						(thickness 0.15)
					)
					(justify left bottom)
				)
			)
			(property "ki_keywords" "SMT, CERAMIC, OSCILLATOR"
				(at 0 0 0)
				(effects
					(font
						(size 1.27 1.27)
					)
					(hide yes)
				)
			)
			(symbol "Resonator_25MHz_ABM8G_1_1"
				(polyline
					(pts
						(xy 1.905 1.905) (xy 1.905 2.54) (xy 5.715 2.54) (xy 5.715 1.905)
					)
					(stroke
						(width 0.254)
						(type default)
					)
					(fill
						(type none)
					)
				)
				(polyline
					(pts
						(xy 1.905 -1.905) (xy 1.905 -2.54) (xy 5.715 -2.54) (xy 5.715 -1.905)
					)
					(stroke
						(width 0.254)
						(type default)
					)
					(fill
						(type none)
					)
				)
				(polyline
					(pts
						(xy 2.54 1.27) (xy 2.54 -1.27)
					)
					(stroke
						(width 0.254)
						(type default)
					)
					(fill
						(type background)
					)
				)
				(rectangle
					(start 3.175 1.905)
					(end 4.445 -1.905)
					(stroke
						(width 0.254)
						(type default)
					)
					(fill
						(type background)
					)
				)
				(polyline
					(pts
						(xy 5.08 1.27) (xy 5.08 -1.27)
					)
					(stroke
						(width 0.254)
						(type default)
					)
					(fill
						(type background)
					)
				)
				(pin passive line
					(at 0 0 0)
					(length 2.54)
					(name "~"
						(effects
							(font
								(size 1.27 1.27)
							)
						)
					)
					(number "1"
						(effects
							(font
								(size 1.27 1.27)
							)
						)
					)
				)
				(pin passive line
					(at 3.81 -5.08 90)
					(length 2.54)
					(name "SH"
						(effects
							(font
								(size 1.27 1.27)
							)
						)
					)
					(number "2"
						(effects
							(font
								(size 1.27 1.27)
							)
						)
					)
				)
				(pin passive line
					(at 3.81 -5.08 90)
					(length 2.54)
					(hide yes)
					(name "SH"
						(effects
							(font
								(size 1.27 1.27)
							)
						)
					)
					(number "4"
						(effects
							(font
								(size 1.27 1.27)
							)
						)
					)
				)
				(pin passive line
					(at 7.62 0 180)
					(length 2.54)
					(name "~"
						(effects
							(font
								(size 1.27 1.27)
							)
						)
					)
					(number "3"
						(effects
							(font
								(size 1.27 1.27)
							)
						)
					)
				)
			)
		)
	(symbol "antmicroShuntsJumpers:Net-Tie_P0.127mm"
			(pin_numbers
				(hide yes)
			)
			(pin_names
				(hide yes)
			)
			(exclude_from_sim no)
			(in_bom no)
			(on_board yes)
			(property "Reference" "TP"
				(at 21.59 -5.08 0)
				(effects
					(font
						(size 1.27 1.27)
						(thickness 0.15)
					)
					(justify left bottom)
					(hide yes)
				)
			)
			(property "Value" "Net-Tie_P0.127mm"
				(at 21.59 -7.62 0)
				(effects
					(font
						(size 1.27 1.27)
						(thickness 0.15)
					)
					(justify left bottom)
					(hide yes)
				)
			)
			(property "Footprint" "antmicro-footprints:NetTie-2_SMD_Pad0.127mm"
				(at 21.59 -12.7 0)
				(effects
					(font
						(size 1.27 1.27)
						(thickness 0.15)
					)
					(justify left bottom)
					(hide yes)
				)
			)
			(property "Datasheet" ""
				(at 21.59 -15.24 0)
				(effects
					(font
						(size 1.27 1.27)
						(thickness 0.15)
					)
					(justify left bottom)
					(hide yes)
				)
			)
			(property "Description" "Net tie, 2 pins"
				(at 0 0 0)
				(effects
					(font
						(size 1.27 1.27)
					)
					(hide yes)
				)
			)
			(property "MPN" ""
				(at 21.59 -10.16 0)
				(effects
					(font
						(size 1.27 1.27)
						(thickness 0.15)
					)
					(justify left bottom)
				)
			)
			(property "Manufacturer" ""
				(at 21.59 -17.78 0)
				(effects
					(font
						(size 1.27 1.27)
						(thickness 0.15)
					)
					(justify left bottom)
					(hide yes)
				)
			)
			(property "Author" "Antmicro"
				(at 21.59 -20.32 0)
				(effects
					(font
						(size 1.27 1.27)
						(thickness 0.15)
					)
					(justify left bottom)
					(hide yes)
				)
			)
			(property "License" "Apache-2.0"
				(at 21.59 -22.86 0)
				(effects
					(font
						(size 1.27 1.27)
						(thickness 0.15)
					)
					(justify left bottom)
					(hide yes)
				)
			)
			(property "ki_fp_filters" "Net*Tie*"
				(at 0 0 0)
				(effects
					(font
						(size 1.27 1.27)
					)
					(hide yes)
				)
			)
			(symbol "Net-Tie_P0.127mm_1_1"
				(polyline
					(pts
						(xy 1.27 0) (xy 2.54 0)
					)
					(stroke
						(width 0.254)
						(type default)
					)
					(fill
						(type none)
					)
				)
				(pin passive line
					(at 0 0 0)
					(length 2.54)
					(name "1"
						(effects
							(font
								(size 1.27 1.27)
							)
						)
					)
					(number "1"
						(effects
							(font
								(size 1.27 1.27)
							)
						)
					)
				)
				(pin passive line
					(at 3.81 0 180)
					(length 2.54)
					(name "2"
						(effects
							(font
								(size 1.27 1.27)
							)
						)
					)
					(number "2"
						(effects
							(font
								(size 1.27 1.27)
							)
						)
					)
				)
			)
		)
	(symbol "antmicroSlideSwitches:CVS-03B"
			(pin_names
				(hide yes)
			)
			(exclude_from_sim no)
			(in_bom yes)
			(on_board yes)
			(property "Reference" "SW"
				(at 26.67 -2.54 0)
				(effects
					(font
						(size 1.27 1.27)
						(thickness 0.15)
					)
					(justify left bottom)
				)
			)
			(property "Value" "CVS-03B"
				(at 26.67 -5.08 0)
				(effects
					(font
						(size 1.27 1.27)
						(thickness 0.15)
					)
					(justify left bottom)
				)
			)
			(property "Footprint" "antmicro-footprints:SW_DIP_SPSTx03_Slide_Copal_CVS-03xB_W5.9mm_P1mm"
				(at 26.67 -7.62 0)
				(effects
					(font
						(size 1.27 1.27)
						(thickness 0.15)
					)
					(justify left bottom)
					(hide yes)
				)
			)
			(property "Datasheet" "https://www.mouser.com/datasheet/2/972/cvs-1827291.pdf"
				(at 26.67 -10.16 0)
				(effects
					(font
						(size 1.27 1.27)
						(thickness 0.15)
					)
					(justify left bottom)
					(hide yes)
				)
			)
			(property "Description" "Slide switch"
				(at 0 0 0)
				(effects
					(font
						(size 1.27 1.27)
					)
					(hide yes)
				)
			)
			(property "MPN" "CVS-03B"
				(at 26.67 -12.7 0)
				(effects
					(font
						(size 1.27 1.27)
						(thickness 0.15)
					)
					(justify left bottom)
					(hide yes)
				)
			)
			(property "Manufacturer" "Nidec Components"
				(at 26.67 -15.24 0)
				(effects
					(font
						(size 1.27 1.27)
						(thickness 0.15)
					)
					(justify left bottom)
					(hide yes)
				)
			)
			(property "Author" "Antmicro"
				(at 26.67 -17.78 0)
				(effects
					(font
						(size 1.27 1.27)
						(thickness 0.15)
					)
					(justify left bottom)
					(hide yes)
				)
			)
			(property "License" "Apache-2.0"
				(at 26.67 -20.32 0)
				(effects
					(font
						(size 1.27 1.27)
						(thickness 0.15)
					)
					(justify left bottom)
					(hide yes)
				)
			)
			(property "ki_keywords" "HORIZONTAL, SMT, SWITCH, MECHANICAL"
				(at 0 0 0)
				(effects
					(font
						(size 1.27 1.27)
					)
					(hide yes)
				)
			)
			(property "ki_fp_filters" "SW?DIP?x2*"
				(at 0 0 0)
				(effects
					(font
						(size 1.27 1.27)
					)
					(hide yes)
				)
			)
			(symbol "CVS-03B_1_1"
				(rectangle
					(start 2.54 2.54)
					(end 10.16 -8.89)
					(stroke
						(width 0.254)
						(type default)
					)
					(fill
						(type background)
					)
				)
				(polyline
					(pts
						(xy 3.81 0) (xy 2.54 0)
					)
					(stroke
						(width 0.254)
						(type default)
					)
					(fill
						(type none)
					)
				)
				(polyline
					(pts
						(xy 3.81 -2.54) (xy 2.54 -2.54)
					)
					(stroke
						(width 0.254)
						(type default)
					)
					(fill
						(type none)
					)
				)
				(polyline
					(pts
						(xy 3.827 -5.0976) (xy 2.557 -5.0976)
					)
					(stroke
						(width 0.254)
						(type default)
					)
					(fill
						(type none)
					)
				)
				(circle
					(center 4.318 0)
					(radius 0.508)
					(stroke
						(width 0.254)
						(type default)
					)
					(fill
						(type none)
					)
				)
				(circle
					(center 4.318 -2.54)
					(radius 0.508)
					(stroke
						(width 0.254)
						(type default)
					)
					(fill
						(type none)
					)
				)
				(circle
					(center 4.318 -5.08)
					(radius 0.508)
					(stroke
						(width 0.254)
						(type default)
					)
					(fill
						(type none)
					)
				)
				(polyline
					(pts
						(xy 4.826 0.127) (xy 8.7122 1.1684)
					)
					(stroke
						(width 0.254)
						(type default)
					)
					(fill
						(type none)
					)
				)
				(polyline
					(pts
						(xy 4.826 -2.413) (xy 8.7122 -1.3716)
					)
					(stroke
						(width 0.254)
						(type default)
					)
					(fill
						(type none)
					)
				)
				(polyline
					(pts
						(xy 4.826 -4.953) (xy 8.7122 -3.9116)
					)
					(stroke
						(width 0.254)
						(type default)
					)
					(fill
						(type none)
					)
				)
				(circle
					(center 8.382 0)
					(radius 0.508)
					(stroke
						(width 0.254)
						(type default)
					)
					(fill
						(type none)
					)
				)
				(circle
					(center 8.382 -2.54)
					(radius 0.508)
					(stroke
						(width 0.254)
						(type default)
					)
					(fill
						(type none)
					)
				)
				(circle
					(center 8.382 -5.08)
					(radius 0.508)
					(stroke
						(width 0.254)
						(type default)
					)
					(fill
						(type none)
					)
				)
				(polyline
					(pts
						(xy 10.16 0) (xy 8.89 0)
					)
					(stroke
						(width 0.254)
						(type default)
					)
					(fill
						(type none)
					)
				)
				(polyline
					(pts
						(xy 10.16 -2.54) (xy 8.89 -2.54)
					)
					(stroke
						(width 0.254)
						(type default)
					)
					(fill
						(type none)
					)
				)
				(polyline
					(pts
						(xy 10.16 -5.08) (xy 8.89 -5.08)
					)
					(stroke
						(width 0.254)
						(type default)
					)
					(fill
						(type none)
					)
				)
				(text "SH"
					(at 8.255 -7.62 0)
					(effects
						(font
							(size 1.27 1.27)
							(thickness 0.15)
						)
					)
				)
				(pin passive line
					(at 0 0 0)
					(length 2.54)
					(name "1"
						(effects
							(font
								(size 1.27 1.27)
							)
						)
					)
					(number "1"
						(effects
							(font
								(size 1.27 1.27)
							)
						)
					)
				)
				(pin passive line
					(at 0 -2.54 0)
					(length 2.54)
					(name "2"
						(effects
							(font
								(size 1.27 1.27)
							)
						)
					)
					(number "2"
						(effects
							(font
								(size 1.27 1.27)
							)
						)
					)
				)
				(pin passive line
					(at 0 -5.08 0)
					(length 2.54)
					(name "3"
						(effects
							(font
								(size 1.27 1.27)
							)
						)
					)
					(number "3"
						(effects
							(font
								(size 1.27 1.27)
							)
						)
					)
				)
				(pin passive line
					(at 12.7 0 180)
					(length 2.54)
					(name "6"
						(effects
							(font
								(size 1.27 1.27)
							)
						)
					)
					(number "6"
						(effects
							(font
								(size 1.27 1.27)
							)
						)
					)
				)
				(pin passive line
					(at 12.7 -2.54 180)
					(length 2.54)
					(name "5"
						(effects
							(font
								(size 1.27 1.27)
							)
						)
					)
					(number "5"
						(effects
							(font
								(size 1.27 1.27)
							)
						)
					)
				)
				(pin passive line
					(at 12.7 -5.08 180)
					(length 2.54)
					(name "4"
						(effects
							(font
								(size 1.27 1.27)
							)
						)
					)
					(number "4"
						(effects
							(font
								(size 1.27 1.27)
							)
						)
					)
				)
				(pin power_in line
					(at 12.7 -7.62 180)
					(length 2.54)
					(name "7"
						(effects
							(font
								(size 1.27 1.27)
							)
						)
					)
					(number "7"
						(effects
							(font
								(size 1.27 1.27)
							)
						)
					)
				)
			)
		)
	(symbol "antmicroSlideSwitches:SW_CVS-02B"
			(exclude_from_sim no)
			(in_bom yes)
			(on_board yes)
			(property "Reference" "SW"
				(at 26.67 -2.54 0)
				(effects
					(font
						(size 1.27 1.27)
						(thickness 0.15)
					)
					(justify left bottom)
				)
			)
			(property "Value" "SW_CVS-02B"
				(at 26.67 -5.08 0)
				(effects
					(font
						(size 1.27 1.27)
						(thickness 0.15)
					)
					(justify left bottom)
				)
			)
			(property "Footprint" "antmicro-footprints:SW_DIP_SPSTx02_Slide_Copal_CVS-02xB_W5.9mm_P1mm"
				(at 26.67 -7.62 0)
				(effects
					(font
						(size 1.27 1.27)
						(thickness 0.15)
					)
					(justify left bottom)
					(hide yes)
				)
			)
			(property "Datasheet" "https://www.mouser.com/datasheet/2/972/cvs-1827291.pdf"
				(at 26.67 -10.16 0)
				(effects
					(font
						(size 1.27 1.27)
						(thickness 0.15)
					)
					(justify left bottom)
					(hide yes)
				)
			)
			(property "Description" "Slide switch"
				(at 0 0 0)
				(effects
					(font
						(size 1.27 1.27)
					)
					(hide yes)
				)
			)
			(property "MPN" "CVS-02B"
				(at 26.67 -12.7 0)
				(effects
					(font
						(size 1.27 1.27)
						(thickness 0.15)
					)
					(justify left bottom)
					(hide yes)
				)
			)
			(property "Manufacturer" "Nidec Components"
				(at 26.67 -15.24 0)
				(effects
					(font
						(size 1.27 1.27)
						(thickness 0.15)
					)
					(justify left bottom)
					(hide yes)
				)
			)
			(property "Author" "Antmicro"
				(at 26.67 -17.78 0)
				(effects
					(font
						(size 1.27 1.27)
						(thickness 0.15)
					)
					(justify left bottom)
					(hide yes)
				)
			)
			(property "License" "Apache-2.0"
				(at 26.67 -20.32 0)
				(effects
					(font
						(size 1.27 1.27)
						(thickness 0.15)
					)
					(justify left bottom)
					(hide yes)
				)
			)
			(property "ki_keywords" "HORIZONTAL, SMT, SWITCH, MECHANICAL"
				(at 0 0 0)
				(effects
					(font
						(size 1.27 1.27)
					)
					(hide yes)
				)
			)
			(property "ki_fp_filters" "SW?DIP?x2*"
				(at 0 0 0)
				(effects
					(font
						(size 1.27 1.27)
					)
					(hide yes)
				)
			)
			(symbol "SW_CVS-02B_1_1"
				(rectangle
					(start 2.54 2.54)
					(end 10.16 -7.62)
					(stroke
						(width 0.254)
						(type default)
					)
					(fill
						(type background)
					)
				)
				(polyline
					(pts
						(xy 3.81 0) (xy 2.54 0)
					)
					(stroke
						(width 0.254)
						(type default)
					)
					(fill
						(type none)
					)
				)
				(polyline
					(pts
						(xy 3.81 -2.54) (xy 2.54 -2.54)
					)
					(stroke
						(width 0.254)
						(type default)
					)
					(fill
						(type none)
					)
				)
				(circle
					(center 4.318 0)
					(radius 0.508)
					(stroke
						(width 0.254)
						(type default)
					)
					(fill
						(type none)
					)
				)
				(circle
					(center 4.318 -2.54)
					(radius 0.508)
					(stroke
						(width 0.254)
						(type default)
					)
					(fill
						(type none)
					)
				)
				(polyline
					(pts
						(xy 4.826 0.127) (xy 8.7122 1.1684)
					)
					(stroke
						(width 0.254)
						(type default)
					)
					(fill
						(type none)
					)
				)
				(polyline
					(pts
						(xy 4.826 -2.413) (xy 8.7122 -1.3716)
					)
					(stroke
						(width 0.254)
						(type default)
					)
					(fill
						(type none)
					)
				)
				(circle
					(center 8.382 0)
					(radius 0.508)
					(stroke
						(width 0.254)
						(type default)
					)
					(fill
						(type none)
					)
				)
				(circle
					(center 8.382 -2.54)
					(radius 0.508)
					(stroke
						(width 0.254)
						(type default)
					)
					(fill
						(type none)
					)
				)
				(polyline
					(pts
						(xy 10.16 0) (xy 8.89 0)
					)
					(stroke
						(width 0.254)
						(type default)
					)
					(fill
						(type none)
					)
				)
				(polyline
					(pts
						(xy 10.16 -2.54) (xy 8.89 -2.54)
					)
					(stroke
						(width 0.254)
						(type default)
					)
					(fill
						(type none)
					)
				)
				(pin passive line
					(at 0 0 0)
					(length 2.54)
					(name "~"
						(effects
							(font
								(size 1.27 1.27)
							)
						)
					)
					(number "1"
						(effects
							(font
								(size 1.27 1.27)
							)
						)
					)
				)
				(pin passive line
					(at 0 -2.54 0)
					(length 2.54)
					(name "~"
						(effects
							(font
								(size 1.27 1.27)
							)
						)
					)
					(number "2"
						(effects
							(font
								(size 1.27 1.27)
							)
						)
					)
				)
				(pin passive line
					(at 12.7 0 180)
					(length 2.54)
					(name "~"
						(effects
							(font
								(size 1.27 1.27)
							)
						)
					)
					(number "4"
						(effects
							(font
								(size 1.27 1.27)
							)
						)
					)
				)
				(pin passive line
					(at 12.7 -2.54 180)
					(length 2.54)
					(name "~"
						(effects
							(font
								(size 1.27 1.27)
							)
						)
					)
					(number "3"
						(effects
							(font
								(size 1.27 1.27)
							)
						)
					)
				)
				(pin power_in line
					(at 12.7 -5.08 180)
					(length 2.54)
					(name "SH"
						(effects
							(font
								(size 1.27 1.27)
							)
						)
					)
					(number "SH"
						(effects
							(font
								(size 1.27 1.27)
							)
						)
					)
				)
			)
		)
	(symbol "antmicroSlideSwitches:SW_CVS-08TB"
			(pin_names
				(hide yes)
			)
			(exclude_from_sim no)
			(in_bom yes)
			(on_board yes)
			(property "Reference" "SW"
				(at 26.67 -2.54 0)
				(effects
					(font
						(size 1.27 1.27)
						(thickness 0.15)
					)
					(justify left bottom)
				)
			)
			(property "Value" "SW_CVS-08TB"
				(at 26.67 -5.08 0)
				(effects
					(font
						(size 1.27 1.27)
						(thickness 0.15)
					)
					(justify left bottom)
				)
			)
			(property "Footprint" "antmicro-footprints:SW_DIP_SPSTx08_Slide_Copal_CVS-08xB_W5.9mm_P1mm"
				(at 26.67 -7.62 0)
				(effects
					(font
						(size 1.27 1.27)
						(thickness 0.15)
					)
					(justify left bottom)
					(hide yes)
				)
			)
			(property "Datasheet" "https://www.mouser.com/datasheet/2/972/cvs-1827291.pdf"
				(at 26.67 -10.16 0)
				(effects
					(font
						(size 1.27 1.27)
						(thickness 0.15)
					)
					(justify left bottom)
					(hide yes)
				)
			)
			(property "Description" "DIP / SIP Switch, 8 Circuits, Slide, Surface Mount, SPST, 6 V, 100 mA"
				(at 0 0 0)
				(effects
					(font
						(size 1.27 1.27)
					)
					(hide yes)
				)
			)
			(property "MPN" "CVS-08TB"
				(at 26.67 -12.7 0)
				(effects
					(font
						(size 1.27 1.27)
						(thickness 0.15)
					)
					(justify left bottom)
					(hide yes)
				)
			)
			(property "Manufacturer" "Nidec Components"
				(at 26.67 -15.24 0)
				(effects
					(font
						(size 1.27 1.27)
						(thickness 0.15)
					)
					(justify left bottom)
					(hide yes)
				)
			)
			(property "Author" "Antmicro"
				(at 26.67 -17.78 0)
				(effects
					(font
						(size 1.27 1.27)
						(thickness 0.15)
					)
					(justify left bottom)
					(hide yes)
				)
			)
			(property "License" "Apache-2.0"
				(at 26.67 -20.32 0)
				(effects
					(font
						(size 1.27 1.27)
						(thickness 0.15)
					)
					(justify left bottom)
					(hide yes)
				)
			)
			(property "ki_keywords" "SWITCH, SLIDE, SPST"
				(at 0 0 0)
				(effects
					(font
						(size 1.27 1.27)
					)
					(hide yes)
				)
			)
			(property "ki_fp_filters" "SW?DIP?x2*"
				(at 0 0 0)
				(effects
					(font
						(size 1.27 1.27)
					)
					(hide yes)
				)
			)
			(symbol "SW_CVS-08TB_1_1"
				(rectangle
					(start 2.54 2.54)
					(end 10.16 -21.59)
					(stroke
						(width 0.254)
						(type default)
					)
					(fill
						(type background)
					)
				)
				(polyline
					(pts
						(xy 2.54 0) (xy 3.81 0)
					)
					(stroke
						(width 0.254)
						(type default)
					)
					(fill
						(type none)
					)
				)
				(polyline
					(pts
						(xy 2.54 -2.54) (xy 3.81 -2.54)
					)
					(stroke
						(width 0.254)
						(type default)
					)
					(fill
						(type none)
					)
				)
				(polyline
					(pts
						(xy 2.54 -5.08) (xy 3.81 -5.08)
					)
					(stroke
						(width 0.254)
						(type default)
					)
					(fill
						(type none)
					)
				)
				(polyline
					(pts
						(xy 2.54 -7.62) (xy 3.81 -7.62)
					)
					(stroke
						(width 0.254)
						(type default)
					)
					(fill
						(type none)
					)
				)
				(polyline
					(pts
						(xy 2.54 -10.16) (xy 3.81 -10.16)
					)
					(stroke
						(width 0.254)
						(type default)
					)
					(fill
						(type none)
					)
				)
				(polyline
					(pts
						(xy 2.54 -12.7) (xy 3.81 -12.7)
					)
					(stroke
						(width 0.254)
						(type default)
					)
					(fill
						(type none)
					)
				)
				(polyline
					(pts
						(xy 2.54 -17.78) (xy 3.81 -17.78)
					)
					(stroke
						(width 0.254)
						(type default)
					)
					(fill
						(type none)
					)
				)
				(polyline
					(pts
						(xy 2.5435 -15.235) (xy 3.8135 -15.235)
					)
					(stroke
						(width 0.254)
						(type default)
					)
					(fill
						(type none)
					)
				)
				(circle
					(center 4.318 0)
					(radius 0.508)
					(stroke
						(width 0.254)
						(type default)
					)
					(fill
						(type none)
					)
				)
				(circle
					(center 4.318 -2.54)
					(radius 0.508)
					(stroke
						(width 0.254)
						(type default)
					)
					(fill
						(type none)
					)
				)
				(circle
					(center 4.318 -5.08)
					(radius 0.508)
					(stroke
						(width 0.254)
						(type default)
					)
					(fill
						(type none)
					)
				)
				(circle
					(center 4.318 -7.62)
					(radius 0.508)
					(stroke
						(width 0.254)
						(type default)
					)
					(fill
						(type none)
					)
				)
				(circle
					(center 4.318 -10.16)
					(radius 0.508)
					(stroke
						(width 0.254)
						(type default)
					)
					(fill
						(type none)
					)
				)
				(circle
					(center 4.318 -12.7)
					(radius 0.508)
					(stroke
						(width 0.254)
						(type default)
					)
					(fill
						(type none)
					)
				)
				(circle
					(center 4.318 -15.24)
					(radius 0.508)
					(stroke
						(width 0.254)
						(type default)
					)
					(fill
						(type none)
					)
				)
				(circle
					(center 4.318 -17.78)
					(radius 0.508)
					(stroke
						(width 0.254)
						(type default)
					)
					(fill
						(type none)
					)
				)
				(polyline
					(pts
						(xy 4.826 0.127) (xy 8.7122 1.1684)
					)
					(stroke
						(width 0.254)
						(type default)
					)
					(fill
						(type none)
					)
				)
				(polyline
					(pts
						(xy 4.826 -2.413) (xy 8.7122 -1.3716)
					)
					(stroke
						(width 0.254)
						(type default)
					)
					(fill
						(type none)
					)
				)
				(polyline
					(pts
						(xy 4.826 -4.953) (xy 8.7122 -3.9116)
					)
					(stroke
						(width 0.254)
						(type default)
					)
					(fill
						(type none)
					)
				)
				(polyline
					(pts
						(xy 4.826 -7.493) (xy 8.7122 -6.4516)
					)
					(stroke
						(width 0.254)
						(type default)
					)
					(fill
						(type none)
					)
				)
				(polyline
					(pts
						(xy 4.826 -10.033) (xy 8.7122 -8.9916)
					)
					(stroke
						(width 0.254)
						(type default)
					)
					(fill
						(type none)
					)
				)
				(polyline
					(pts
						(xy 4.826 -12.573) (xy 8.7122 -11.5316)
					)
					(stroke
						(width 0.254)
						(type default)
					)
					(fill
						(type none)
					)
				)
				(polyline
					(pts
						(xy 4.826 -15.113) (xy 8.7122 -14.0716)
					)
					(stroke
						(width 0.254)
						(type default)
					)
					(fill
						(type none)
					)
				)
				(polyline
					(pts
						(xy 4.826 -17.653) (xy 8.7122 -16.6116)
					)
					(stroke
						(width 0.254)
						(type default)
					)
					(fill
						(type none)
					)
				)
				(circle
					(center 8.382 0)
					(radius 0.508)
					(stroke
						(width 0.254)
						(type default)
					)
					(fill
						(type none)
					)
				)
				(circle
					(center 8.382 -2.54)
					(radius 0.508)
					(stroke
						(width 0.254)
						(type default)
					)
					(fill
						(type none)
					)
				)
				(circle
					(center 8.382 -5.08)
					(radius 0.508)
					(stroke
						(width 0.254)
						(type default)
					)
					(fill
						(type none)
					)
				)
				(circle
					(center 8.382 -7.62)
					(radius 0.508)
					(stroke
						(width 0.254)
						(type default)
					)
					(fill
						(type none)
					)
				)
				(circle
					(center 8.382 -10.16)
					(radius 0.508)
					(stroke
						(width 0.254)
						(type default)
					)
					(fill
						(type none)
					)
				)
				(circle
					(center 8.382 -12.7)
					(radius 0.508)
					(stroke
						(width 0.254)
						(type default)
					)
					(fill
						(type none)
					)
				)
				(circle
					(center 8.382 -15.24)
					(radius 0.508)
					(stroke
						(width 0.254)
						(type default)
					)
					(fill
						(type none)
					)
				)
				(circle
					(center 8.382 -17.78)
					(radius 0.508)
					(stroke
						(width 0.254)
						(type default)
					)
					(fill
						(type none)
					)
				)
				(polyline
					(pts
						(xy 8.89 0) (xy 10.16 0)
					)
					(stroke
						(width 0.254)
						(type default)
					)
					(fill
						(type none)
					)
				)
				(polyline
					(pts
						(xy 8.89 -2.54) (xy 10.16 -2.54)
					)
					(stroke
						(width 0.254)
						(type default)
					)
					(fill
						(type none)
					)
				)
				(polyline
					(pts
						(xy 8.89 -5.08) (xy 10.16 -5.08)
					)
					(stroke
						(width 0.254)
						(type default)
					)
					(fill
						(type none)
					)
				)
				(polyline
					(pts
						(xy 8.89 -7.62) (xy 10.16 -7.62)
					)
					(stroke
						(width 0.254)
						(type default)
					)
					(fill
						(type none)
					)
				)
				(polyline
					(pts
						(xy 8.89 -10.16) (xy 10.16 -10.16)
					)
					(stroke
						(width 0.254)
						(type default)
					)
					(fill
						(type none)
					)
				)
				(polyline
					(pts
						(xy 8.89 -12.7) (xy 10.16 -12.7)
					)
					(stroke
						(width 0.254)
						(type default)
					)
					(fill
						(type none)
					)
				)
				(polyline
					(pts
						(xy 8.89 -17.78) (xy 10.16 -17.78)
					)
					(stroke
						(width 0.254)
						(type default)
					)
					(fill
						(type none)
					)
				)
				(polyline
					(pts
						(xy 8.8935 -15.235) (xy 10.1635 -15.235)
					)
					(stroke
						(width 0.254)
						(type default)
					)
					(fill
						(type none)
					)
				)
				(text "SH"
					(at 6.985 -20.955 0)
					(effects
						(font
							(size 1.27 1.27)
							(thickness 0.15)
						)
						(justify left bottom)
					)
				)
				(pin passive line
					(at 0 0 0)
					(length 2.54)
					(name "1"
						(effects
							(font
								(size 1.27 1.27)
							)
						)
					)
					(number "1"
						(effects
							(font
								(size 1.27 1.27)
							)
						)
					)
				)
				(pin passive line
					(at 0 -2.54 0)
					(length 2.54)
					(name "2"
						(effects
							(font
								(size 1.27 1.27)
							)
						)
					)
					(number "2"
						(effects
							(font
								(size 1.27 1.27)
							)
						)
					)
				)
				(pin passive line
					(at 0 -5.08 0)
					(length 2.54)
					(name "3"
						(effects
							(font
								(size 1.27 1.27)
							)
						)
					)
					(number "3"
						(effects
							(font
								(size 1.27 1.27)
							)
						)
					)
				)
				(pin passive line
					(at 0 -7.62 0)
					(length 2.54)
					(name "4"
						(effects
							(font
								(size 1.27 1.27)
							)
						)
					)
					(number "4"
						(effects
							(font
								(size 1.27 1.27)
							)
						)
					)
				)
				(pin passive line
					(at 0 -10.16 0)
					(length 2.54)
					(name "5"
						(effects
							(font
								(size 1.27 1.27)
							)
						)
					)
					(number "5"
						(effects
							(font
								(size 1.27 1.27)
							)
						)
					)
				)
				(pin passive line
					(at 0 -12.7 0)
					(length 2.54)
					(name "6"
						(effects
							(font
								(size 1.27 1.27)
							)
						)
					)
					(number "6"
						(effects
							(font
								(size 1.27 1.27)
							)
						)
					)
				)
				(pin passive line
					(at 0 -15.24 0)
					(length 2.54)
					(name "7"
						(effects
							(font
								(size 1.27 1.27)
							)
						)
					)
					(number "7"
						(effects
							(font
								(size 1.27 1.27)
							)
						)
					)
				)
				(pin passive line
					(at 0 -17.78 0)
					(length 2.54)
					(name "8"
						(effects
							(font
								(size 1.27 1.27)
							)
						)
					)
					(number "8"
						(effects
							(font
								(size 1.27 1.27)
							)
						)
					)
				)
				(pin passive line
					(at 12.7 0 180)
					(length 2.54)
					(name "16"
						(effects
							(font
								(size 1.27 1.27)
							)
						)
					)
					(number "16"
						(effects
							(font
								(size 1.27 1.27)
							)
						)
					)
				)
				(pin passive line
					(at 12.7 -2.54 180)
					(length 2.54)
					(name "15"
						(effects
							(font
								(size 1.27 1.27)
							)
						)
					)
					(number "15"
						(effects
							(font
								(size 1.27 1.27)
							)
						)
					)
				)
				(pin passive line
					(at 12.7 -5.08 180)
					(length 2.54)
					(name "14"
						(effects
							(font
								(size 1.27 1.27)
							)
						)
					)
					(number "14"
						(effects
							(font
								(size 1.27 1.27)
							)
						)
					)
				)
				(pin passive line
					(at 12.7 -7.62 180)
					(length 2.54)
					(name "13"
						(effects
							(font
								(size 1.27 1.27)
							)
						)
					)
					(number "13"
						(effects
							(font
								(size 1.27 1.27)
							)
						)
					)
				)
				(pin passive line
					(at 12.7 -10.16 180)
					(length 2.54)
					(name "12"
						(effects
							(font
								(size 1.27 1.27)
							)
						)
					)
					(number "12"
						(effects
							(font
								(size 1.27 1.27)
							)
						)
					)
				)
				(pin passive line
					(at 12.7 -12.7 180)
					(length 2.54)
					(name "11"
						(effects
							(font
								(size 1.27 1.27)
							)
						)
					)
					(number "11"
						(effects
							(font
								(size 1.27 1.27)
							)
						)
					)
				)
				(pin passive line
					(at 12.7 -15.24 180)
					(length 2.54)
					(name "10"
						(effects
							(font
								(size 1.27 1.27)
							)
						)
					)
					(number "10"
						(effects
							(font
								(size 1.27 1.27)
							)
						)
					)
				)
				(pin passive line
					(at 12.7 -17.78 180)
					(length 2.54)
					(name "9"
						(effects
							(font
								(size 1.27 1.27)
							)
						)
					)
					(number "9"
						(effects
							(font
								(size 1.27 1.27)
							)
						)
					)
				)
				(pin power_in line
					(at 12.7 -20.32 180)
					(length 2.54)
					(name "17"
						(effects
							(font
								(size 1.27 1.27)
							)
						)
					)
					(number "17"
						(effects
							(font
								(size 1.27 1.27)
							)
						)
					)
				)
			)
		)
	(symbol "antmicroTVSDiodes:ESDA25P35-1U1M"
			(pin_names
				(hide yes)
			)
			(exclude_from_sim no)
			(in_bom yes)
			(on_board yes)
			(property "Reference" "D"
				(at 24.13 -5.08 0)
				(effects
					(font
						(size 1.27 1.27)
						(thickness 0.15)
					)
					(justify left bottom)
				)
			)
			(property "Value" "ESDA25P35-1U1M"
				(at 24.13 -7.62 0)
				(effects
					(font
						(size 1.27 1.27)
						(thickness 0.15)
					)
					(justify left bottom)
				)
			)
			(property "Footprint" "antmicro-footprints:ESDA25P35-1U1M"
				(at 24.13 -10.16 0)
				(effects
					(font
						(size 1.27 1.27)
						(thickness 0.15)
					)
					(justify left bottom)
					(hide yes)
				)
			)
			(property "Datasheet" "https://www.st.com/resource/en/datasheet/esda25p35-1u1m.pdf"
				(at 24.13 -12.7 0)
				(effects
					(font
						(size 1.27 1.27)
						(thickness 0.15)
					)
					(justify left bottom)
					(hide yes)
				)
			)
			(property "Description" "TVS diode"
				(at 0 0 0)
				(effects
					(font
						(size 1.27 1.27)
					)
					(hide yes)
				)
			)
			(property "MPN" "ESDA25P35-1U1M"
				(at 24.13 -15.24 0)
				(effects
					(font
						(size 1.27 1.27)
						(thickness 0.15)
					)
					(justify left bottom)
					(hide yes)
				)
			)
			(property "Manufacturer" "STMicroelectronics"
				(at 24.13 -17.78 0)
				(effects
					(font
						(size 1.27 1.27)
						(thickness 0.15)
					)
					(justify left bottom)
					(hide yes)
				)
			)
			(property "Author" "Antmicro"
				(at 24.13 -20.32 0)
				(effects
					(font
						(size 1.27 1.27)
						(thickness 0.15)
					)
					(justify left bottom)
					(hide yes)
				)
			)
			(property "License" "Apache-2.0"
				(at 24.13 -22.86 0)
				(effects
					(font
						(size 1.27 1.27)
						(thickness 0.15)
					)
					(justify left bottom)
					(hide yes)
				)
			)
			(property "ki_keywords" "0603, SMT, DIODE, SEMICONDUCTOR, TVS, ESD"
				(at 0 0 0)
				(effects
					(font
						(size 1.27 1.27)
					)
					(hide yes)
				)
			)
			(symbol "ESDA25P35-1U1M_0_1"
				(polyline
					(pts
						(xy 1.778 1.016) (xy 3.302 0) (xy 1.778 -1.016) (xy 1.778 1.016)
					)
					(stroke
						(width 0.254)
						(type default)
					)
					(fill
						(type outline)
					)
				)
				(polyline
					(pts
						(xy 2.667 1.778) (xy 3.302 1.27)
					)
					(stroke
						(width 0.254)
						(type default)
					)
					(fill
						(type none)
					)
				)
				(polyline
					(pts
						(xy 3.302 0) (xy 1.778 0)
					)
					(stroke
						(width 0)
						(type default)
					)
					(fill
						(type none)
					)
				)
			)
			(symbol "ESDA25P35-1U1M_1_1"
				(polyline
					(pts
						(xy 3.302 -1.27) (xy 3.302 1.27)
					)
					(stroke
						(width 0.254)
						(type default)
					)
					(fill
						(type none)
					)
				)
				(polyline
					(pts
						(xy 3.302 -1.27) (xy 3.937 -1.778)
					)
					(stroke
						(width 0.254)
						(type default)
					)
					(fill
						(type none)
					)
				)
				(pin passive line
					(at 0 0 0)
					(length 1.778)
					(name "K"
						(effects
							(font
								(size 1.27 1.27)
							)
						)
					)
					(number "1"
						(effects
							(font
								(size 1.27 1.27)
							)
						)
					)
				)
				(pin passive line
					(at 5.08 0 180)
					(length 1.778)
					(name "A"
						(effects
							(font
								(size 1.27 1.27)
							)
						)
					)
					(number "2"
						(effects
							(font
								(size 1.27 1.27)
							)
						)
					)
				)
			)
		)
	(symbol "antmicroTVSDiodes:TPD4E05U06QDQARQ1"
			(exclude_from_sim no)
			(in_bom yes)
			(on_board yes)
			(property "Reference" "U"
				(at 24.13 0 0)
				(effects
					(font
						(size 1.27 1.27)
						(thickness 0.15)
					)
					(justify left bottom)
				)
			)
			(property "Value" "TPD4E05U06QDQARQ1"
				(at 24.13 -2.54 0)
				(effects
					(font
						(size 1.27 1.27)
						(thickness 0.15)
					)
					(justify left bottom)
				)
			)
			(property "Footprint" "antmicro-footprints:USON-10_2.5x1mm_P0.5mm"
				(at 24.13 -5.08 0)
				(effects
					(font
						(size 1.27 1.27)
						(thickness 0.15)
					)
					(justify left bottom)
					(hide yes)
				)
			)
			(property "Datasheet" "https://www.ti.com/lit/ds/symlink/tpd4e05u06-q1.pdf?HQS=dis-mous-null-mousermode-dsf-pf-null-wwe&ts=1663591265741&ref_url=https%253A%252F%252Fwww.mouser.com%252F"
				(at 24.13 -7.62 0)
				(effects
					(font
						(size 1.27 1.27)
						(thickness 0.15)
					)
					(justify left bottom)
					(hide yes)
				)
			)
			(property "Description" "ESD protection"
				(at 0 0 0)
				(effects
					(font
						(size 1.27 1.27)
					)
					(hide yes)
				)
			)
			(property "Manufacturer" "Texas Instruments"
				(at 24.13 -10.16 0)
				(effects
					(font
						(size 1.27 1.27)
						(thickness 0.15)
					)
					(justify left bottom)
					(hide yes)
				)
			)
			(property "MPN" "TPD4E05U06QDQARQ1"
				(at 24.13 -12.7 0)
				(effects
					(font
						(size 1.27 1.27)
						(thickness 0.15)
					)
					(justify left bottom)
					(hide yes)
				)
			)
			(property "Author" "Antmicro"
				(at 24.13 -15.24 0)
				(effects
					(font
						(size 1.27 1.27)
						(thickness 0.15)
					)
					(justify left bottom)
					(hide yes)
				)
			)
			(property "License" "Apache-2.0"
				(at 24.13 -17.78 0)
				(effects
					(font
						(size 1.27 1.27)
						(thickness 0.15)
					)
					(justify left bottom)
					(hide yes)
				)
			)
			(property "ki_keywords" "SMT, DIODE, IC, TVS, ESD"
				(at 0 0 0)
				(effects
					(font
						(size 1.27 1.27)
					)
					(hide yes)
				)
			)
			(symbol "TPD4E05U06QDQARQ1_1_1"
				(rectangle
					(start 2.54 2.54)
					(end 8.89 -11.43)
					(stroke
						(width 0.254)
						(type default)
					)
					(fill
						(type background)
					)
				)
				(polyline
					(pts
						(xy 2.54 0) (xy 7.62 0)
					)
					(stroke
						(width 0.254)
						(type default)
					)
					(fill
						(type background)
					)
				)
				(polyline
					(pts
						(xy 2.54 -2.54) (xy 7.62 -2.54)
					)
					(stroke
						(width 0.254)
						(type default)
					)
					(fill
						(type background)
					)
				)
				(polyline
					(pts
						(xy 2.54 -5.08) (xy 7.62 -5.08)
					)
					(stroke
						(width 0.254)
						(type default)
					)
					(fill
						(type background)
					)
				)
				(polyline
					(pts
						(xy 2.54 -7.62) (xy 7.62 -7.62)
					)
					(stroke
						(width 0.254)
						(type default)
					)
					(fill
						(type background)
					)
				)
				(polyline
					(pts
						(xy 4.826 -0.635) (xy 5.08 -0.381) (xy 5.08 0.381) (xy 5.334 0.635)
					)
					(stroke
						(width 0.254)
						(type default)
					)
					(fill
						(type background)
					)
				)
				(polyline
					(pts
						(xy 4.826 -3.175) (xy 5.08 -2.921) (xy 5.08 -2.159) (xy 5.334 -1.905)
					)
					(stroke
						(width 0.254)
						(type default)
					)
					(fill
						(type background)
					)
				)
				(polyline
					(pts
						(xy 4.826 -5.715) (xy 5.08 -5.461) (xy 5.08 -4.699) (xy 5.334 -4.445)
					)
					(stroke
						(width 0.254)
						(type default)
					)
					(fill
						(type background)
					)
				)
				(polyline
					(pts
						(xy 4.826 -8.255) (xy 5.08 -8.001) (xy 5.08 -7.239) (xy 5.334 -6.985)
					)
					(stroke
						(width 0.254)
						(type default)
					)
					(fill
						(type background)
					)
				)
				(polyline
					(pts
						(xy 5.08 0) (xy 3.81 -0.635) (xy 3.81 0.635) (xy 5.08 0)
					)
					(stroke
						(width 0.254)
						(type default)
					)
					(fill
						(type background)
					)
				)
				(polyline
					(pts
						(xy 5.08 0) (xy 6.35 -0.635) (xy 6.35 0.635) (xy 5.08 0)
					)
					(stroke
						(width 0.254)
						(type default)
					)
					(fill
						(type background)
					)
				)
				(polyline
					(pts
						(xy 5.08 -2.54) (xy 3.81 -3.175) (xy 3.81 -1.905) (xy 5.08 -2.54)
					)
					(stroke
						(width 0.254)
						(type default)
					)
					(fill
						(type background)
					)
				)
				(polyline
					(pts
						(xy 5.08 -2.54) (xy 6.35 -3.175) (xy 6.35 -1.905) (xy 5.08 -2.54)
					)
					(stroke
						(width 0.254)
						(type default)
					)
					(fill
						(type background)
					)
				)
				(polyline
					(pts
						(xy 5.08 -5.08) (xy 3.81 -5.715) (xy 3.81 -4.445) (xy 5.08 -5.08)
					)
					(stroke
						(width 0.254)
						(type default)
					)
					(fill
						(type background)
					)
				)
				(polyline
					(pts
						(xy 5.08 -5.08) (xy 6.35 -4.445) (xy 6.35 -5.715) (xy 5.08 -5.08)
					)
					(stroke
						(width 0.254)
						(type default)
					)
					(fill
						(type background)
					)
				)
				(polyline
					(pts
						(xy 5.08 -7.62) (xy 3.81 -8.255) (xy 3.81 -6.985) (xy 5.08 -7.62)
					)
					(stroke
						(width 0.254)
						(type default)
					)
					(fill
						(type background)
					)
				)
				(polyline
					(pts
						(xy 6.35 -6.985) (xy 6.35 -8.255) (xy 5.08 -7.62) (xy 6.35 -6.985)
					)
					(stroke
						(width 0.254)
						(type default)
					)
					(fill
						(type background)
					)
				)
				(polyline
					(pts
						(xy 7.62 0) (xy 7.62 -10.16)
					)
					(stroke
						(width 0.254)
						(type default)
					)
					(fill
						(type background)
					)
				)
				(circle
					(center 7.62 -2.54)
					(radius 0.254)
					(stroke
						(width 0.254)
						(type default)
					)
					(fill
						(type background)
					)
				)
				(circle
					(center 7.62 -5.08)
					(radius 0.254)
					(stroke
						(width 0.254)
						(type default)
					)
					(fill
						(type background)
					)
				)
				(circle
					(center 7.62 -5.08)
					(radius 0.254)
					(stroke
						(width 0.254)
						(type default)
					)
					(fill
						(type background)
					)
				)
				(circle
					(center 7.62 -7.62)
					(radius 0.254)
					(stroke
						(width 0.254)
						(type default)
					)
					(fill
						(type background)
					)
				)
				(polyline
					(pts
						(xy 7.62 -10.16) (xy 2.54 -10.16)
					)
					(stroke
						(width 0.254)
						(type default)
					)
					(fill
						(type background)
					)
				)
				(pin passive line
					(at 0 0 0)
					(length 2.54)
					(name "~"
						(effects
							(font
								(size 1.27 1.27)
							)
						)
					)
					(number "1"
						(effects
							(font
								(size 1.27 1.27)
							)
						)
					)
				)
				(pin passive line
					(at 0 0 0)
					(length 2.54)
					(hide yes)
					(name "~"
						(effects
							(font
								(size 1.27 1.27)
							)
						)
					)
					(number "10"
						(effects
							(font
								(size 1.27 1.27)
							)
						)
					)
				)
				(pin passive line
					(at 0 -2.54 0)
					(length 2.54)
					(name "~"
						(effects
							(font
								(size 1.27 1.27)
							)
						)
					)
					(number "2"
						(effects
							(font
								(size 1.27 1.27)
							)
						)
					)
				)
				(pin passive line
					(at 0 -2.54 0)
					(length 2.54)
					(hide yes)
					(name "~"
						(effects
							(font
								(size 1.27 1.27)
							)
						)
					)
					(number "9"
						(effects
							(font
								(size 1.27 1.27)
							)
						)
					)
				)
				(pin passive line
					(at 0 -5.08 0)
					(length 2.54)
					(name "~"
						(effects
							(font
								(size 1.27 1.27)
							)
						)
					)
					(number "4"
						(effects
							(font
								(size 1.27 1.27)
							)
						)
					)
				)
				(pin passive line
					(at 0 -5.08 0)
					(length 2.54)
					(hide yes)
					(name "~"
						(effects
							(font
								(size 1.27 1.27)
							)
						)
					)
					(number "7"
						(effects
							(font
								(size 1.27 1.27)
							)
						)
					)
				)
				(pin passive line
					(at 0 -7.62 0)
					(length 2.54)
					(name "~"
						(effects
							(font
								(size 1.27 1.27)
							)
						)
					)
					(number "5"
						(effects
							(font
								(size 1.27 1.27)
							)
						)
					)
				)
				(pin passive line
					(at 0 -7.62 0)
					(length 2.54)
					(hide yes)
					(name "~"
						(effects
							(font
								(size 1.27 1.27)
							)
						)
					)
					(number "6"
						(effects
							(font
								(size 1.27 1.27)
							)
						)
					)
				)
				(pin power_in line
					(at 0 -10.16 0)
					(length 2.54)
					(name "~"
						(effects
							(font
								(size 1.27 1.27)
							)
						)
					)
					(number "3"
						(effects
							(font
								(size 1.27 1.27)
							)
						)
					)
				)
				(pin passive line
					(at 0 -10.16 0)
					(length 2.54)
					(hide yes)
					(name "~"
						(effects
							(font
								(size 1.27 1.27)
							)
						)
					)
					(number "8"
						(effects
							(font
								(size 1.27 1.27)
							)
						)
					)
				)
			)
		)
	(symbol "antmicroTestPoints:TP_1206_SMD_RCW-0C"
			(pin_names
				(hide yes)
			)
			(exclude_from_sim no)
			(in_bom no)
			(on_board yes)
			(property "Reference" "TP"
				(at 17.78 -5.08 0)
				(effects
					(font
						(size 1.27 1.27)
						(thickness 0.15)
					)
					(justify left bottom)
				)
			)
			(property "Value" "TP_1206_SMD_RCW-0C"
				(at 17.78 -7.62 0)
				(effects
					(font
						(size 1.27 1.27)
						(thickness 0.15)
					)
					(justify left bottom)
				)
			)
			(property "Footprint" "antmicro-footprints:TP_1206_SMD_RCW-0C"
				(at 17.78 -10.16 0)
				(effects
					(font
						(size 1.27 1.27)
						(thickness 0.15)
					)
					(justify left bottom)
					(hide yes)
				)
			)
			(property "Datasheet" "https://www.te.com/commerce/DocumentDelivery/DDEController?Action=srchrtrv&DocNm=1773266&DocType=DS&DocLang=English"
				(at 17.78 -12.7 0)
				(effects
					(font
						(size 1.27 1.27)
						(thickness 0.15)
					)
					(justify left bottom)
					(hide yes)
				)
			)
			(property "Description" "Circuit Probe Pad, SMD, Test Point, 1206"
				(at 0 0 0)
				(effects
					(font
						(size 1.27 1.27)
					)
					(hide yes)
				)
			)
			(property "MPN" "RCW-0C"
				(at 17.78 -15.24 0)
				(effects
					(font
						(size 1.27 1.27)
						(thickness 0.15)
					)
					(justify left bottom)
					(hide yes)
				)
			)
			(property "Manufacturer" "TE Connectivity"
				(at 17.78 -17.78 0)
				(effects
					(font
						(size 1.27 1.27)
						(thickness 0.15)
					)
					(justify left bottom)
					(hide yes)
				)
			)
			(property "Author" "Antmicro"
				(at 17.78 -20.32 0)
				(effects
					(font
						(size 1.27 1.27)
						(thickness 0.15)
					)
					(justify left bottom)
					(hide yes)
				)
			)
			(property "License" "Apache-2.0"
				(at 17.78 -22.86 0)
				(effects
					(font
						(size 1.27 1.27)
						(thickness 0.15)
					)
					(justify left bottom)
					(hide yes)
				)
			)
			(property "ki_keywords" "1206, SMT, TESTPOINT, PASSIVE"
				(at 0 0 0)
				(effects
					(font
						(size 1.27 1.27)
					)
					(hide yes)
				)
			)
			(symbol "TP_1206_SMD_RCW-0C_1_1"
				(circle
					(center 3.175 0)
					(radius 0.635)
					(stroke
						(width 0.254)
						(type default)
					)
					(fill
						(type none)
					)
				)
				(pin passive line
					(at 0 0 0)
					(length 2.54)
					(name "1"
						(effects
							(font
								(size 1.27 1.27)
							)
						)
					)
					(number "1"
						(effects
							(font
								(size 1.27 1.27)
							)
						)
					)
				)
			)
		)
	(symbol "antmicroTestPoints:TP_1mm_SMD"
			(pin_names
				(hide yes)
			)
			(exclude_from_sim no)
			(in_bom no)
			(on_board yes)
			(property "Reference" "TP"
				(at 15.24 -5.08 0)
				(effects
					(font
						(size 1.27 1.27)
						(thickness 0.15)
					)
					(justify left bottom)
				)
			)
			(property "Value" "TP_1mm_SMD"
				(at 15.24 -7.62 0)
				(effects
					(font
						(size 1.27 1.27)
						(thickness 0.15)
					)
					(justify left bottom)
					(hide yes)
				)
			)
			(property "Footprint" "antmicro-footprints:TP_SMD_1mm"
				(at 15.24 -10.16 0)
				(effects
					(font
						(size 1.27 1.27)
						(thickness 0.15)
					)
					(justify left bottom)
					(hide yes)
				)
			)
			(property "Datasheet" ""
				(at 17.78 -12.7 0)
				(effects
					(font
						(size 1.27 1.27)
						(thickness 0.15)
					)
					(justify left bottom)
					(hide yes)
				)
			)
			(property "Description" "Test point 1mm SMD"
				(at 0 0 0)
				(effects
					(font
						(size 1.27 1.27)
					)
					(hide yes)
				)
			)
			(property "MPN" ""
				(at 0 0 0)
				(effects
					(font
						(size 1.27 1.27)
					)
					(hide yes)
				)
			)
			(property "Manufacturer" ""
				(at 0 0 0)
				(effects
					(font
						(size 1.27 1.27)
					)
					(hide yes)
				)
			)
			(property "Author" "Antmicro"
				(at 15.24 -15.24 0)
				(effects
					(font
						(size 1.27 1.27)
						(thickness 0.15)
					)
					(justify left bottom)
					(hide yes)
				)
			)
			(property "License" "Apache-2.0"
				(at 15.24 -17.78 0)
				(effects
					(font
						(size 1.27 1.27)
						(thickness 0.15)
					)
					(justify left bottom)
					(hide yes)
				)
			)
			(property "ki_keywords" "TESTPOINT"
				(at 0 0 0)
				(effects
					(font
						(size 1.27 1.27)
					)
					(hide yes)
				)
			)
			(symbol "TP_1mm_SMD_1_1"
				(circle
					(center 3.175 0)
					(radius 0.635)
					(stroke
						(width 0.254)
						(type default)
					)
					(fill
						(type none)
					)
				)
				(pin passive line
					(at 0 0 0)
					(length 2.54)
					(name "1"
						(effects
							(font
								(size 1.27 1.27)
							)
						)
					)
					(number "1"
						(effects
							(font
								(size 1.27 1.27)
							)
						)
					)
				)
			)
		)
	(symbol "antmicroTransistorsFETsMOSFETsSingle:BSS138PW,115"
			(pin_names
				(offset 0)
			)
			(exclude_from_sim no)
			(in_bom yes)
			(on_board yes)
			(property "Reference" "Q"
				(at 3.81 -6.35 0)
				(effects
					(font
						(size 1.27 1.27)
						(thickness 0.15)
					)
					(justify left bottom)
				)
			)
			(property "Value" "BSS138PW,115"
				(at 22.86 -8.89 0)
				(effects
					(font
						(size 1.27 1.27)
						(thickness 0.15)
					)
					(justify left bottom)
					(hide yes)
				)
			)
			(property "Footprint" "antmicro-footprints:SC70-3"
				(at 22.86 -11.43 0)
				(effects
					(font
						(size 1.27 1.27)
						(thickness 0.15)
					)
					(justify left bottom)
					(hide yes)
				)
			)
			(property "Datasheet" "https://assets.nexperia.com/documents/data-sheet/BSS138PW.pdf"
				(at 22.86 -13.97 0)
				(effects
					(font
						(size 1.27 1.27)
						(thickness 0.15)
					)
					(justify left bottom)
					(hide yes)
				)
			)
			(property "Description" "Power MOSFET, N Channel, 60 V, 320 mA, 0.9 ohm, SOT-323, Surface Mount"
				(at 22.86 -26.67 0)
				(effects
					(font
						(size 1.27 1.27)
					)
					(justify left bottom)
					(hide yes)
				)
			)
			(property "MPN" "BSS138PW,115"
				(at 22.86 -16.51 0)
				(effects
					(font
						(size 1.27 1.27)
						(thickness 0.15)
					)
					(justify left bottom)
				)
			)
			(property "Manufacturer" "Nexperia"
				(at 22.86 -19.05 0)
				(effects
					(font
						(size 1.27 1.27)
						(thickness 0.15)
					)
					(justify left bottom)
					(hide yes)
				)
			)
			(property "Author" "Antmicro"
				(at 22.86 -21.59 0)
				(effects
					(font
						(size 1.27 1.27)
						(thickness 0.15)
					)
					(justify left bottom)
					(hide yes)
				)
			)
			(property "License" "Apache-2.0"
				(at 22.86 -24.13 0)
				(effects
					(font
						(size 1.27 1.27)
						(thickness 0.15)
					)
					(justify left bottom)
					(hide yes)
				)
			)
			(property "ki_keywords" "SMT, TRANSISTOR, SEMICONDUCTOR, MOSFET, NMOS"
				(at 0 0 0)
				(effects
					(font
						(size 1.27 1.27)
					)
					(hide yes)
				)
			)
			(symbol "BSS138PW,115_1_1"
				(polyline
					(pts
						(xy 2.54 0) (xy 4.572 0) (xy 4.572 3.937)
					)
					(stroke
						(width 0.254)
						(type default)
					)
					(fill
						(type none)
					)
				)
				(polyline
					(pts
						(xy 5.08 4.445) (xy 5.08 3.429)
					)
					(stroke
						(width 0.254)
						(type default)
					)
					(fill
						(type background)
					)
				)
				(polyline
					(pts
						(xy 5.08 2.54) (xy 5.08 3.048)
					)
					(stroke
						(width 0.254)
						(type default)
					)
					(fill
						(type background)
					)
				)
				(polyline
					(pts
						(xy 5.08 2.54) (xy 5.08 2.032)
					)
					(stroke
						(width 0.254)
						(type default)
					)
					(fill
						(type background)
					)
				)
				(polyline
					(pts
						(xy 5.08 2.54) (xy 5.842 3.048) (xy 5.842 2.032) (xy 5.08 2.54)
					)
					(stroke
						(width 0.254)
						(type default)
					)
					(fill
						(type outline)
					)
				)
				(polyline
					(pts
						(xy 5.08 1.143) (xy 5.08 1.651)
					)
					(stroke
						(width 0.254)
						(type default)
					)
					(fill
						(type background)
					)
				)
				(polyline
					(pts
						(xy 5.08 1.143) (xy 5.08 0.635)
					)
					(stroke
						(width 0.254)
						(type default)
					)
					(fill
						(type background)
					)
				)
				(circle
					(center 6.35 2.54)
					(radius 3.302)
					(stroke
						(width 0.254)
						(type default)
					)
					(fill
						(type background)
					)
				)
				(polyline
					(pts
						(xy 7.493 0.635) (xy 8.636 0.635) (xy 8.636 3.937) (xy 8.636 4.445) (xy 7.493 4.445)
					)
					(stroke
						(width 0.254)
						(type default)
					)
					(fill
						(type background)
					)
				)
				(polyline
					(pts
						(xy 7.62 6.35) (xy 7.62 3.937) (xy 5.08 3.937)
					)
					(stroke
						(width 0.254)
						(type default)
					)
					(fill
						(type background)
					)
				)
				(circle
					(center 7.62 4.445)
					(radius 0.127)
					(stroke
						(width 0.254)
						(type default)
					)
					(fill
						(type background)
					)
				)
				(polyline
					(pts
						(xy 7.62 1.143) (xy 5.08 1.143)
					)
					(stroke
						(width 0.254)
						(type default)
					)
					(fill
						(type background)
					)
				)
				(circle
					(center 7.62 1.143)
					(radius 0.127)
					(stroke
						(width 0.254)
						(type default)
					)
					(fill
						(type background)
					)
				)
				(circle
					(center 7.62 0.635)
					(radius 0.127)
					(stroke
						(width 0.254)
						(type default)
					)
					(fill
						(type background)
					)
				)
				(polyline
					(pts
						(xy 7.62 -1.27) (xy 7.62 2.54) (xy 5.08 2.54)
					)
					(stroke
						(width 0.254)
						(type default)
					)
					(fill
						(type background)
					)
				)
				(polyline
					(pts
						(xy 8.636 3.048) (xy 8.128 2.286) (xy 9.144 2.286) (xy 8.636 3.048)
					)
					(stroke
						(width 0.254)
						(type default)
					)
					(fill
						(type outline)
					)
				)
				(polyline
					(pts
						(xy 9.144 3.048) (xy 8.128 3.048)
					)
					(stroke
						(width 0.254)
						(type default)
					)
					(fill
						(type background)
					)
				)
				(pin input line
					(at 0 0 0)
					(length 2.54)
					(name "G"
						(effects
							(font
								(size 1.27 1.27)
							)
						)
					)
					(number "1"
						(effects
							(font
								(size 1.27 1.27)
							)
						)
					)
				)
				(pin passive line
					(at 7.62 8.89 270)
					(length 2.54)
					(name "D"
						(effects
							(font
								(size 1.27 1.27)
							)
						)
					)
					(number "3"
						(effects
							(font
								(size 1.27 1.27)
							)
						)
					)
				)
				(pin passive line
					(at 7.62 -3.81 90)
					(length 2.54)
					(name "S"
						(effects
							(font
								(size 1.27 1.27)
							)
						)
					)
					(number "2"
						(effects
							(font
								(size 1.27 1.27)
							)
						)
					)
				)
			)
		)
	(symbol "antmicroTransistorsFETsMOSFETsSingle:SI7613DN-T1-GE3"
			(pin_names
				(offset 0)
			)
			(exclude_from_sim no)
			(in_bom yes)
			(on_board yes)
			(property "Reference" "Q"
				(at 15.24 5.08 0)
				(effects
					(font
						(size 1.27 1.27)
						(thickness 0.15)
					)
					(justify left bottom)
				)
			)
			(property "Value" "SI7613DN-T1-GE3"
				(at 15.24 2.54 0)
				(effects
					(font
						(size 1.27 1.27)
						(thickness 0.15)
					)
					(justify left bottom)
				)
			)
			(property "Footprint" "antmicro-footprints:Vishay_PowerPAK_1212-8_Single"
				(at 15.24 1.27 0)
				(effects
					(font
						(size 1.27 1.27)
						(thickness 0.15)
					)
					(justify left bottom)
					(hide yes)
				)
			)
			(property "Datasheet" "https://www.vishay.com/docs/64809/si7613dn.pdf"
				(at 15.24 -1.27 0)
				(effects
					(font
						(size 1.27 1.27)
						(thickness 0.15)
					)
					(justify left bottom)
					(hide yes)
				)
			)
			(property "Description" "Power MOSFET, P Channel, 20 V, 35 A, 0.0072 ohm, PowerPAK 1212, Surface Mount"
				(at 0 0 0)
				(effects
					(font
						(size 1.27 1.27)
					)
					(hide yes)
				)
			)
			(property "MPN" "SI7613DN-T1-GE3"
				(at 15.24 -5.08 0)
				(effects
					(font
						(size 1.27 1.27)
						(thickness 0.15)
					)
					(justify left bottom)
					(hide yes)
				)
			)
			(property "Manufacturer" "Vishay"
				(at 15.24 -7.62 0)
				(effects
					(font
						(size 1.27 1.27)
						(thickness 0.15)
					)
					(justify left bottom)
					(hide yes)
				)
			)
			(property "Author" "Antmicro"
				(at 15.24 -10.16 0)
				(effects
					(font
						(size 1.27 1.27)
						(thickness 0.15)
					)
					(justify left bottom)
					(hide yes)
				)
			)
			(property "License" "Apache-2.0"
				(at 15.24 -12.7 0)
				(effects
					(font
						(size 1.27 1.27)
						(thickness 0.15)
					)
					(justify left bottom)
					(hide yes)
				)
			)
			(property "ki_keywords" "SMT, TRANSISTOR, SEMICONDUCTOR, MOSFET, PMOS"
				(at 0 0 0)
				(effects
					(font
						(size 1.27 1.27)
					)
					(hide yes)
				)
			)
			(symbol "SI7613DN-T1-GE3_1_1"
				(polyline
					(pts
						(xy 2.54 0) (xy 4.572 0) (xy 4.572 3.937)
					)
					(stroke
						(width 0.254)
						(type default)
					)
					(fill
						(type none)
					)
				)
				(polyline
					(pts
						(xy 5.08 4.445) (xy 5.08 3.429)
					)
					(stroke
						(width 0.254)
						(type default)
					)
					(fill
						(type background)
					)
				)
				(polyline
					(pts
						(xy 5.08 2.54) (xy 5.08 3.048)
					)
					(stroke
						(width 0.254)
						(type default)
					)
					(fill
						(type background)
					)
				)
				(polyline
					(pts
						(xy 5.08 2.54) (xy 5.08 2.032)
					)
					(stroke
						(width 0.254)
						(type default)
					)
					(fill
						(type background)
					)
				)
				(polyline
					(pts
						(xy 5.08 1.143) (xy 5.08 1.651)
					)
					(stroke
						(width 0.254)
						(type default)
					)
					(fill
						(type background)
					)
				)
				(polyline
					(pts
						(xy 5.08 1.143) (xy 5.08 0.635)
					)
					(stroke
						(width 0.254)
						(type default)
					)
					(fill
						(type background)
					)
				)
				(circle
					(center 6.35 2.54)
					(radius 3.302)
					(stroke
						(width 0.254)
						(type default)
					)
					(fill
						(type background)
					)
				)
				(polyline
					(pts
						(xy 7.239 2.54) (xy 6.477 3.048) (xy 6.477 2.032) (xy 7.239 2.54)
					)
					(stroke
						(width 0.254)
						(type default)
					)
					(fill
						(type outline)
					)
				)
				(polyline
					(pts
						(xy 7.493 0.635) (xy 8.636 0.635) (xy 8.636 3.937) (xy 8.636 4.445) (xy 7.493 4.445)
					)
					(stroke
						(width 0.254)
						(type default)
					)
					(fill
						(type background)
					)
				)
				(polyline
					(pts
						(xy 7.62 6.35) (xy 7.62 3.937) (xy 5.08 3.937)
					)
					(stroke
						(width 0.254)
						(type default)
					)
					(fill
						(type none)
					)
				)
				(circle
					(center 7.62 4.445)
					(radius 0.127)
					(stroke
						(width 0.254)
						(type default)
					)
					(fill
						(type background)
					)
				)
				(polyline
					(pts
						(xy 7.62 1.143) (xy 5.08 1.143)
					)
					(stroke
						(width 0.254)
						(type default)
					)
					(fill
						(type background)
					)
				)
				(circle
					(center 7.62 1.143)
					(radius 0.127)
					(stroke
						(width 0.254)
						(type default)
					)
					(fill
						(type background)
					)
				)
				(circle
					(center 7.62 0.635)
					(radius 0.127)
					(stroke
						(width 0.254)
						(type default)
					)
					(fill
						(type background)
					)
				)
				(polyline
					(pts
						(xy 7.62 -1.27) (xy 7.62 2.54) (xy 5.08 2.54)
					)
					(stroke
						(width 0.254)
						(type default)
					)
					(fill
						(type none)
					)
				)
				(polyline
					(pts
						(xy 8.636 2.286) (xy 8.128 3.048) (xy 9.144 3.048) (xy 8.636 2.286)
					)
					(stroke
						(width 0.254)
						(type default)
					)
					(fill
						(type outline)
					)
				)
				(polyline
					(pts
						(xy 9.144 2.2352) (xy 8.128 2.2352)
					)
					(stroke
						(width 0.254)
						(type default)
					)
					(fill
						(type background)
					)
				)
				(pin passive line
					(at 0 0 0)
					(length 2.54)
					(name "G"
						(effects
							(font
								(size 1.27 1.27)
							)
						)
					)
					(number "4"
						(effects
							(font
								(size 1.27 1.27)
							)
						)
					)
				)
				(pin passive line
					(at 7.62 8.89 270)
					(length 2.54)
					(name "D"
						(effects
							(font
								(size 1.27 1.27)
							)
						)
					)
					(number "5"
						(effects
							(font
								(size 1.27 1.27)
							)
						)
					)
				)
				(pin passive line
					(at 7.62 -3.81 90)
					(length 2.54)
					(name "S"
						(effects
							(font
								(size 1.27 1.27)
							)
						)
					)
					(number "1"
						(effects
							(font
								(size 1.27 1.27)
							)
						)
					)
				)
				(pin passive line
					(at 7.62 -3.81 90)
					(length 2.54)
					(hide yes)
					(name "S"
						(effects
							(font
								(size 1.27 1.27)
							)
						)
					)
					(number "2"
						(effects
							(font
								(size 1.27 1.27)
							)
						)
					)
				)
				(pin passive line
					(at 7.62 -3.81 90)
					(length 2.54)
					(hide yes)
					(name "S"
						(effects
							(font
								(size 1.27 1.27)
							)
						)
					)
					(number "3"
						(effects
							(font
								(size 1.27 1.27)
							)
						)
					)
				)
			)
		)
	(symbol "antmicroUSBConnectors:USB-C_GCT_USB4105-GF-A"
			(exclude_from_sim no)
			(in_bom yes)
			(on_board yes)
			(property "Reference" "J"
				(at 38.1 -2.54 0)
				(effects
					(font
						(size 1.27 1.27)
						(thickness 0.15)
					)
					(justify left bottom)
				)
			)
			(property "Value" "USB-C_GCT_USB4105-GF-A"
				(at 38.1 -5.08 0)
				(effects
					(font
						(size 1.27 1.27)
						(thickness 0.15)
					)
					(justify left bottom)
				)
			)
			(property "Footprint" "antmicro-footprints:USB-C_Receptacle_GCT_USB4105-GF-A"
				(at 38.1 -7.62 0)
				(effects
					(font
						(size 1.27 1.27)
						(thickness 0.15)
					)
					(justify left bottom)
					(hide yes)
				)
			)
			(property "Datasheet" "https://gct.co/files/drawings/usb4105.pdf"
				(at 38.1 -10.16 0)
				(effects
					(font
						(size 1.27 1.27)
						(thickness 0.15)
					)
					(justify left bottom)
					(hide yes)
				)
			)
			(property "Description" "USB-C (USB TYPE-C) USB 2.0 Receptacle Connector 24 (16+8 Dummy) Position Surface Mount, Right Angle"
				(at 0 0 0)
				(effects
					(font
						(size 1.27 1.27)
					)
					(hide yes)
				)
			)
			(property "Manufacturer" "GCT"
				(at 38.1 -12.7 0)
				(effects
					(font
						(size 1.27 1.27)
						(thickness 0.15)
					)
					(justify left bottom)
					(hide yes)
				)
			)
			(property "MPN" "USB4105-GF-A"
				(at 38.1 -15.24 0)
				(effects
					(font
						(size 1.27 1.27)
						(thickness 0.15)
					)
					(justify left bottom)
					(hide yes)
				)
			)
			(property "Author" "Antmicro"
				(at 38.1 -17.78 0)
				(effects
					(font
						(size 1.27 1.27)
						(thickness 0.15)
					)
					(justify left bottom)
					(hide yes)
				)
			)
			(property "License" "Apache-2.0"
				(at 38.1 -20.32 0)
				(effects
					(font
						(size 1.27 1.27)
						(thickness 0.15)
					)
					(justify left bottom)
					(hide yes)
				)
			)
			(property "VSD_Class" "USB-C"
				(at 38.1 -22.86 0)
				(effects
					(font
						(size 1.27 1.27)
					)
					(justify left bottom)
					(hide yes)
				)
			)
			(property "ki_keywords" "USB, CONNECTOR, SMT, HORIZONTAL"
				(at 0 0 0)
				(effects
					(font
						(size 1.27 1.27)
					)
					(hide yes)
				)
			)
			(symbol "USB-C_GCT_USB4105-GF-A_1_1"
				(rectangle
					(start -22.86 2.54)
					(end -3.81 -38.1)
					(stroke
						(width 0.254)
						(type default)
					)
					(fill
						(type background)
					)
				)
				(circle
					(center -20.066 -18.034)
					(radius 0.284)
					(stroke
						(width 0.254)
						(type default)
					)
					(fill
						(type outline)
					)
				)
				(polyline
					(pts
						(xy -19.812 -16.383) (xy -19.177 -15.24) (xy -18.542 -16.383) (xy -19.812 -16.383)
					)
					(stroke
						(width 0.254)
						(type default)
					)
					(fill
						(type outline)
					)
				)
				(polyline
					(pts
						(xy -19.177 -19.558) (xy -18.288 -18.669) (xy -18.288 -18.034)
					)
					(stroke
						(width 0.254)
						(type default)
					)
					(fill
						(type background)
					)
				)
				(polyline
					(pts
						(xy -19.177 -19.939) (xy -20.066 -19.05) (xy -20.066 -18.415)
					)
					(stroke
						(width 0.254)
						(type default)
					)
					(fill
						(type background)
					)
				)
				(polyline
					(pts
						(xy -19.177 -20.701) (xy -19.177 -16.383)
					)
					(stroke
						(width 0.254)
						(type default)
					)
					(fill
						(type background)
					)
				)
				(circle
					(center -19.177 -20.828)
					(radius 0.5236)
					(stroke
						(width 0.254)
						(type default)
					)
					(fill
						(type outline)
					)
				)
				(rectangle
					(start -18.669 -18.034)
					(end -17.907 -17.272)
					(stroke
						(width 0.254)
						(type default)
					)
					(fill
						(type outline)
					)
				)
				(polyline
					(pts
						(xy -16.51 -21.59) (xy -16.51 -13.97)
					)
					(stroke
						(width 0.254)
						(type default)
					)
					(fill
						(type background)
					)
				)
				(rectangle
					(start -15.24 -21.59)
					(end -13.97 -13.97)
					(stroke
						(width 0.254)
						(type default)
					)
					(fill
						(type outline)
					)
				)
				(arc
					(start -15.24 -13.97)
					(mid -14.605 -13.3377)
					(end -13.97 -13.97)
					(stroke
						(width 0.254)
						(type default)
					)
					(fill
						(type outline)
					)
				)
				(arc
					(start -15.24 -13.97)
					(mid -14.605 -13.3377)
					(end -13.97 -13.97)
					(stroke
						(width 0.254)
						(type default)
					)
					(fill
						(type background)
					)
				)
				(arc
					(start -16.51 -13.97)
					(mid -14.605 -12.0733)
					(end -12.7 -13.97)
					(stroke
						(width 0.254)
						(type default)
					)
					(fill
						(type background)
					)
				)
				(arc
					(start -12.7 -21.59)
					(mid -14.605 -23.4867)
					(end -16.51 -21.59)
					(stroke
						(width 0.254)
						(type default)
					)
					(fill
						(type background)
					)
				)
				(arc
					(start -13.97 -21.59)
					(mid -14.605 -22.2223)
					(end -15.24 -21.59)
					(stroke
						(width 0.254)
						(type default)
					)
					(fill
						(type outline)
					)
				)
				(arc
					(start -13.97 -21.59)
					(mid -14.605 -22.2223)
					(end -15.24 -21.59)
					(stroke
						(width 0.254)
						(type default)
					)
					(fill
						(type background)
					)
				)
				(polyline
					(pts
						(xy -12.7 -13.97) (xy -12.7 -21.59)
					)
					(stroke
						(width 0.254)
						(type default)
					)
					(fill
						(type background)
					)
				)
				(pin passive line
					(at 0 0 180)
					(length 3.81)
					(name "VBUS"
						(effects
							(font
								(size 1.27 1.27)
							)
						)
					)
					(number "A4"
						(effects
							(font
								(size 1.27 1.27)
							)
						)
					)
				)
				(pin passive line
					(at 0 0 180)
					(length 3.81)
					(hide yes)
					(name "VBUS"
						(effects
							(font
								(size 1.27 1.27)
							)
						)
					)
					(number "A9"
						(effects
							(font
								(size 1.27 1.27)
							)
						)
					)
				)
				(pin passive line
					(at 0 0 180)
					(length 3.81)
					(hide yes)
					(name "VBUS"
						(effects
							(font
								(size 1.27 1.27)
							)
						)
					)
					(number "B4"
						(effects
							(font
								(size 1.27 1.27)
							)
						)
					)
				)
				(pin passive line
					(at 0 0 180)
					(length 3.81)
					(hide yes)
					(name "VBUS"
						(effects
							(font
								(size 1.27 1.27)
							)
						)
					)
					(number "B9"
						(effects
							(font
								(size 1.27 1.27)
							)
						)
					)
				)
				(pin bidirectional line
					(at 0 -5.08 180)
					(length 3.81)
					(name "CC_{1}"
						(effects
							(font
								(size 1.27 1.27)
							)
						)
					)
					(number "A5"
						(effects
							(font
								(size 1.27 1.27)
							)
						)
					)
				)
				(pin bidirectional line
					(at 0 -7.62 180)
					(length 3.81)
					(name "CC_{2}"
						(effects
							(font
								(size 1.27 1.27)
							)
						)
					)
					(number "B5"
						(effects
							(font
								(size 1.27 1.27)
							)
						)
					)
				)
				(pin bidirectional line
					(at 0 -12.7 180)
					(length 3.81)
					(name "D_{A}+"
						(effects
							(font
								(size 1.27 1.27)
							)
						)
					)
					(number "A6"
						(effects
							(font
								(size 1.27 1.27)
							)
						)
					)
				)
				(pin bidirectional line
					(at 0 -15.24 180)
					(length 3.81)
					(name "D_{A}-"
						(effects
							(font
								(size 1.27 1.27)
							)
						)
					)
					(number "A7"
						(effects
							(font
								(size 1.27 1.27)
							)
						)
					)
				)
				(pin bidirectional line
					(at 0 -17.78 180)
					(length 3.81)
					(name "D_{B}+"
						(effects
							(font
								(size 1.27 1.27)
							)
						)
					)
					(number "B6"
						(effects
							(font
								(size 1.27 1.27)
							)
						)
					)
				)
				(pin bidirectional line
					(at 0 -20.32 180)
					(length 3.81)
					(name "D_{B}-"
						(effects
							(font
								(size 1.27 1.27)
							)
						)
					)
					(number "B7"
						(effects
							(font
								(size 1.27 1.27)
							)
						)
					)
				)
				(pin bidirectional line
					(at 0 -25.4 180)
					(length 3.81)
					(name "SBU_{1}"
						(effects
							(font
								(size 1.27 1.27)
							)
						)
					)
					(number "A8"
						(effects
							(font
								(size 1.27 1.27)
							)
						)
					)
				)
				(pin bidirectional line
					(at 0 -27.94 180)
					(length 3.81)
					(name "SBU_{2}"
						(effects
							(font
								(size 1.27 1.27)
							)
						)
					)
					(number "B8"
						(effects
							(font
								(size 1.27 1.27)
							)
						)
					)
				)
				(pin power_in line
					(at 0 -33.02 180)
					(length 3.81)
					(name "GND"
						(effects
							(font
								(size 1.27 1.27)
							)
						)
					)
					(number "A1"
						(effects
							(font
								(size 1.27 1.27)
							)
						)
					)
				)
				(pin passive line
					(at 0 -33.02 180)
					(length 3.81)
					(hide yes)
					(name "GND"
						(effects
							(font
								(size 1.27 1.27)
							)
						)
					)
					(number "A12"
						(effects
							(font
								(size 1.27 1.27)
							)
						)
					)
				)
				(pin passive line
					(at 0 -33.02 180)
					(length 3.81)
					(hide yes)
					(name "GND"
						(effects
							(font
								(size 1.27 1.27)
							)
						)
					)
					(number "B1"
						(effects
							(font
								(size 1.27 1.27)
							)
						)
					)
				)
				(pin passive line
					(at 0 -33.02 180)
					(length 3.81)
					(hide yes)
					(name "GND"
						(effects
							(font
								(size 1.27 1.27)
							)
						)
					)
					(number "B12"
						(effects
							(font
								(size 1.27 1.27)
							)
						)
					)
				)
				(pin passive line
					(at 0 -35.56 180)
					(length 3.81)
					(name "SH"
						(effects
							(font
								(size 1.27 1.27)
							)
						)
					)
					(number "SH"
						(effects
							(font
								(size 1.27 1.27)
							)
						)
					)
				)
			)
		)
	(symbol "antmicroVideoConnectors:HDMI-A_WE_685119134923"
			(exclude_from_sim no)
			(in_bom yes)
			(on_board yes)
			(property "Reference" "J"
				(at 35.56 -2.54 0)
				(effects
					(font
						(size 1.27 1.27)
						(thickness 0.15)
					)
					(justify left bottom)
				)
			)
			(property "Value" "HDMI-A_WE_685119134923"
				(at 35.56 -5.08 0)
				(effects
					(font
						(size 1.27 1.27)
						(thickness 0.15)
					)
					(justify left bottom)
				)
			)
			(property "Footprint" "antmicro-footprints:HDMI-A_Receptacle_WE_685119134923"
				(at 35.56 -7.62 0)
				(effects
					(font
						(size 1.27 1.27)
						(thickness 0.15)
					)
					(justify left bottom)
					(hide yes)
				)
			)
			(property "Datasheet" "https://www.we-online.com/components/products/datasheet/685119134923.pdf"
				(at 35.56 -10.16 0)
				(effects
					(font
						(size 1.27 1.27)
						(thickness 0.15)
					)
					(justify left bottom)
					(hide yes)
				)
			)
			(property "Description" "HDMI Receptacle Connector 19 Position Surface Mount, Right Angle; Through Hole"
				(at 0 0 0)
				(effects
					(font
						(size 1.27 1.27)
					)
					(hide yes)
				)
			)
			(property "MPN" "685119134923"
				(at 35.56 -12.7 0)
				(effects
					(font
						(size 1.27 1.27)
						(thickness 0.15)
					)
					(justify left bottom)
					(hide yes)
				)
			)
			(property "Manufacturer" "Würth Elektronik"
				(at 35.56 -15.24 0)
				(effects
					(font
						(size 1.27 1.27)
						(thickness 0.15)
					)
					(justify left bottom)
					(hide yes)
				)
			)
			(property "Author" "Antmicro"
				(at 35.56 -17.78 0)
				(effects
					(font
						(size 1.27 1.27)
						(thickness 0.15)
					)
					(justify left bottom)
					(hide yes)
				)
			)
			(property "License" "Apache-2.0"
				(at 35.56 -20.32 0)
				(effects
					(font
						(size 1.27 1.27)
						(thickness 0.15)
					)
					(justify left bottom)
					(hide yes)
				)
			)
			(property "ki_keywords" "HDMI, CONNECTOR, THT"
				(at 0 0 0)
				(effects
					(font
						(size 1.27 1.27)
					)
					(hide yes)
				)
			)
			(property "ki_fp_filters" "685119134923"
				(at 0 0 0)
				(effects
					(font
						(size 1.27 1.27)
					)
					(hide yes)
				)
			)
			(symbol "HDMI-A_WE_685119134923_0_0"
				(polyline
					(pts
						(xy 13.97 0) (xy 13.97 1.524) (xy 13.97 0.762) (xy 15.875 0.762) (xy 15.875 1.524) (xy 15.875 0)
					)
					(stroke
						(width 0.635)
						(type default)
					)
					(fill
						(type none)
					)
				)
				(polyline
					(pts
						(xy 16.637 1.524) (xy 18.288 1.524) (xy 18.542 1.27) (xy 18.542 0.254) (xy 18.288 0) (xy 16.637 0)
						(xy 16.637 0.762)
					)
					(stroke
						(width 0.635)
						(type default)
					)
					(fill
						(type none)
					)
				)
				(polyline
					(pts
						(xy 22.098 0) (xy 22.098 1.524)
					)
					(stroke
						(width 0.635)
						(type default)
					)
					(fill
						(type none)
					)
				)
			)
			(symbol "HDMI-A_WE_685119134923_0_1"
				(polyline
					(pts
						(xy 10.16 -15.24) (xy 13.97 -15.24) (xy 15.875 -17.145) (xy 15.875 -28.575) (xy 13.97 -30.48)
						(xy 10.16 -30.48) (xy 10.16 -15.24)
					)
					(stroke
						(width 0.635)
						(type default)
					)
					(fill
						(type none)
					)
				)
				(polyline
					(pts
						(xy 12.065 -16.51) (xy 13.335 -16.51) (xy 13.97 -17.145) (xy 13.97 -28.575) (xy 13.335 -29.21)
						(xy 12.065 -29.21) (xy 12.065 -16.51)
					)
					(stroke
						(width 0.254)
						(type default)
					)
					(fill
						(type outline)
					)
				)
				(polyline
					(pts
						(xy 19.304 0) (xy 19.304 1.524) (xy 20.32 1.524) (xy 20.32 0) (xy 20.32 1.524) (xy 21.082 1.524)
						(xy 21.336 1.27) (xy 21.336 0)
					)
					(stroke
						(width 0.635)
						(type default)
					)
					(fill
						(type none)
					)
				)
			)
			(symbol "HDMI-A_WE_685119134923_1_1"
				(rectangle
					(start 2.54 2.54)
					(end 22.86 -53.34)
					(stroke
						(width 0.254)
						(type default)
					)
					(fill
						(type background)
					)
				)
				(pin bidirectional line
					(at 0 0 0)
					(length 2.54)
					(name "D2+"
						(effects
							(font
								(size 1.27 1.27)
							)
						)
					)
					(number "1"
						(effects
							(font
								(size 1.27 1.27)
							)
						)
					)
				)
				(pin bidirectional line
					(at 0 -2.54 0)
					(length 2.54)
					(name "D2-"
						(effects
							(font
								(size 1.27 1.27)
							)
						)
					)
					(number "3"
						(effects
							(font
								(size 1.27 1.27)
							)
						)
					)
				)
				(pin bidirectional line
					(at 0 -7.62 0)
					(length 2.54)
					(name "D1+"
						(effects
							(font
								(size 1.27 1.27)
							)
						)
					)
					(number "4"
						(effects
							(font
								(size 1.27 1.27)
							)
						)
					)
				)
				(pin bidirectional line
					(at 0 -10.16 0)
					(length 2.54)
					(name "D1-"
						(effects
							(font
								(size 1.27 1.27)
							)
						)
					)
					(number "6"
						(effects
							(font
								(size 1.27 1.27)
							)
						)
					)
				)
				(pin bidirectional line
					(at 0 -15.24 0)
					(length 2.54)
					(name "D0+"
						(effects
							(font
								(size 1.27 1.27)
							)
						)
					)
					(number "7"
						(effects
							(font
								(size 1.27 1.27)
							)
						)
					)
				)
				(pin bidirectional line
					(at 0 -17.78 0)
					(length 2.54)
					(name "D0-"
						(effects
							(font
								(size 1.27 1.27)
							)
						)
					)
					(number "9"
						(effects
							(font
								(size 1.27 1.27)
							)
						)
					)
				)
				(pin bidirectional line
					(at 0 -22.86 0)
					(length 2.54)
					(name "CK+"
						(effects
							(font
								(size 1.27 1.27)
							)
						)
					)
					(number "10"
						(effects
							(font
								(size 1.27 1.27)
							)
						)
					)
				)
				(pin bidirectional line
					(at 0 -25.4 0)
					(length 2.54)
					(name "CK-"
						(effects
							(font
								(size 1.27 1.27)
							)
						)
					)
					(number "12"
						(effects
							(font
								(size 1.27 1.27)
							)
						)
					)
				)
				(pin bidirectional line
					(at 0 -30.48 0)
					(length 2.54)
					(name "SCL"
						(effects
							(font
								(size 1.27 1.27)
							)
						)
					)
					(number "15"
						(effects
							(font
								(size 1.27 1.27)
							)
						)
					)
				)
				(pin bidirectional line
					(at 0 -33.02 0)
					(length 2.54)
					(name "SDA"
						(effects
							(font
								(size 1.27 1.27)
							)
						)
					)
					(number "16"
						(effects
							(font
								(size 1.27 1.27)
							)
						)
					)
				)
				(pin bidirectional line
					(at 0 -38.1 0)
					(length 2.54)
					(name "CEC"
						(effects
							(font
								(size 1.27 1.27)
							)
						)
					)
					(number "13"
						(effects
							(font
								(size 1.27 1.27)
							)
						)
					)
				)
				(pin bidirectional line
					(at 0 -43.18 0)
					(length 2.54)
					(name "HPD/HEAC-"
						(effects
							(font
								(size 1.27 1.27)
							)
						)
					)
					(number "19"
						(effects
							(font
								(size 1.27 1.27)
							)
						)
					)
					(alternate "HEAC-" passive line)
					(alternate "HPD" passive line)
				)
				(pin bidirectional line
					(at 0 -45.72 0)
					(length 2.54)
					(name "UTILITY/HEAC+"
						(effects
							(font
								(size 1.27 1.27)
							)
						)
					)
					(number "14"
						(effects
							(font
								(size 1.27 1.27)
							)
						)
					)
					(alternate "HEAC+" passive line)
					(alternate "UTILITY" passive line)
				)
				(pin power_in line
					(at 0 -50.8 0)
					(length 2.54)
					(name "+5V"
						(effects
							(font
								(size 1.27 1.27)
							)
						)
					)
					(number "18"
						(effects
							(font
								(size 1.27 1.27)
							)
						)
					)
				)
				(pin passive line
					(at 25.4 -38.1 180)
					(length 2.54)
					(name "D2S"
						(effects
							(font
								(size 1.27 1.27)
							)
						)
					)
					(number "2"
						(effects
							(font
								(size 1.27 1.27)
							)
						)
					)
				)
				(pin passive line
					(at 25.4 -40.64 180)
					(length 2.54)
					(name "D1S"
						(effects
							(font
								(size 1.27 1.27)
							)
						)
					)
					(number "5"
						(effects
							(font
								(size 1.27 1.27)
							)
						)
					)
				)
				(pin passive line
					(at 25.4 -43.18 180)
					(length 2.54)
					(name "D0S"
						(effects
							(font
								(size 1.27 1.27)
							)
						)
					)
					(number "8"
						(effects
							(font
								(size 1.27 1.27)
							)
						)
					)
				)
				(pin passive line
					(at 25.4 -45.72 180)
					(length 2.54)
					(name "CKS"
						(effects
							(font
								(size 1.27 1.27)
							)
						)
					)
					(number "11"
						(effects
							(font
								(size 1.27 1.27)
							)
						)
					)
				)
				(pin power_in line
					(at 25.4 -48.26 180)
					(length 2.54)
					(name "GND"
						(effects
							(font
								(size 1.27 1.27)
							)
						)
					)
					(number "17"
						(effects
							(font
								(size 1.27 1.27)
							)
						)
					)
				)
				(pin passive line
					(at 25.4 -50.8 180)
					(length 2.54)
					(name "SH"
						(effects
							(font
								(size 1.27 1.27)
							)
						)
					)
					(number "SH"
						(effects
							(font
								(size 1.27 1.27)
							)
						)
					)
				)
			)
		)
	(symbol "antmicroWire2BoardConnectors:JST_SH_1x4_BM04B-SRSS-TB-LF-SN"
			(pin_names
				(hide yes)
			)
			(exclude_from_sim no)
			(in_bom yes)
			(on_board yes)
			(property "Reference" "J"
				(at 20.32 -5.08 0)
				(effects
					(font
						(size 1.27 1.27)
						(thickness 0.15)
					)
					(justify left bottom)
				)
			)
			(property "Value" "JST_SH_1x4_BM04B-SRSS-TB-LF-SN"
				(at 20.32 -7.62 0)
				(effects
					(font
						(size 1.27 1.27)
						(thickness 0.15)
					)
					(justify left bottom)
					(hide yes)
				)
			)
			(property "Footprint" "antmicro-footprints:Conn_JST_SH_1x4_BM04B-SRSS-TB-LF-SN"
				(at 20.32 -10.16 0)
				(effects
					(font
						(size 1.27 1.27)
						(thickness 0.15)
					)
					(justify left bottom)
					(hide yes)
				)
			)
			(property "Datasheet" "https://www.jst-mfg.com/product/pdf/eng/eSH.pdf"
				(at 20.32 -12.7 0)
				(effects
					(font
						(size 1.27 1.27)
						(thickness 0.15)
					)
					(justify left bottom)
					(hide yes)
				)
			)
			(property "Description" "Pin Header, Top Entry, Wire-to-Board, 1 mm, 1 Rows, 4 Contacts, Surface Mount, SR"
				(at 0 0 0)
				(effects
					(font
						(size 1.27 1.27)
					)
					(hide yes)
				)
			)
			(property "MPN" "BM04B-SRSS-TB(LF)(SN) "
				(at 20.32 -15.24 0)
				(effects
					(font
						(size 1.27 1.27)
						(thickness 0.15)
					)
					(justify left bottom)
				)
			)
			(property "Manufacturer" "JST Automotive Connectors"
				(at 20.32 -17.78 0)
				(effects
					(font
						(size 1.27 1.27)
						(thickness 0.15)
					)
					(justify left bottom)
					(hide yes)
				)
			)
			(property "Author" "Antmicro"
				(at 20.32 -20.32 0)
				(effects
					(font
						(size 1.27 1.27)
						(thickness 0.15)
					)
					(justify left bottom)
					(hide yes)
				)
			)
			(property "License" "Apache-2.0"
				(at 20.32 -22.86 0)
				(effects
					(font
						(size 1.27 1.27)
						(thickness 0.15)
					)
					(justify left bottom)
					(hide yes)
				)
			)
			(property "ki_keywords" "VERTICAL, SMT, WIRE-BOARD, CONNECTOR"
				(at 0 0 0)
				(effects
					(font
						(size 1.27 1.27)
					)
					(hide yes)
				)
			)
			(symbol "JST_SH_1x4_BM04B-SRSS-TB-LF-SN_1_1"
				(rectangle
					(start 2.54 1.27)
					(end 5.08 -11.43)
					(stroke
						(width 0.254)
						(type default)
					)
					(fill
						(type background)
					)
				)
				(rectangle
					(start 2.54 0.127)
					(end 3.81 -0.127)
					(stroke
						(width 0.254)
						(type default)
					)
					(fill
						(type background)
					)
				)
				(rectangle
					(start 2.54 -2.413)
					(end 3.81 -2.667)
					(stroke
						(width 0.254)
						(type default)
					)
					(fill
						(type background)
					)
				)
				(rectangle
					(start 2.54 -4.953)
					(end 3.81 -5.207)
					(stroke
						(width 0.254)
						(type default)
					)
					(fill
						(type background)
					)
				)
				(rectangle
					(start 2.54 -7.493)
					(end 3.81 -7.747)
					(stroke
						(width 0.254)
						(type default)
					)
					(fill
						(type background)
					)
				)
				(rectangle
					(start 2.54 -10.033)
					(end 3.81 -10.287)
					(stroke
						(width 0.254)
						(type default)
					)
					(fill
						(type background)
					)
				)
				(pin passive line
					(at 0 0 0)
					(length 2.54)
					(name "Pin_1"
						(effects
							(font
								(size 1.27 1.27)
							)
						)
					)
					(number "1"
						(effects
							(font
								(size 1.27 1.27)
							)
						)
					)
				)
				(pin passive line
					(at 0 -2.54 0)
					(length 2.54)
					(name "Pin_2"
						(effects
							(font
								(size 1.27 1.27)
							)
						)
					)
					(number "2"
						(effects
							(font
								(size 1.27 1.27)
							)
						)
					)
				)
				(pin passive line
					(at 0 -5.08 0)
					(length 2.54)
					(name "Pin_3"
						(effects
							(font
								(size 1.27 1.27)
							)
						)
					)
					(number "3"
						(effects
							(font
								(size 1.27 1.27)
							)
						)
					)
				)
				(pin passive line
					(at 0 -7.62 0)
					(length 2.54)
					(name "Pin_4"
						(effects
							(font
								(size 1.27 1.27)
							)
						)
					)
					(number "4"
						(effects
							(font
								(size 1.27 1.27)
							)
						)
					)
				)
				(pin passive line
					(at 0 -10.16 0)
					(length 2.54)
					(name "MP"
						(effects
							(font
								(size 1.27 1.27)
							)
						)
					)
					(number "MP"
						(effects
							(font
								(size 1.27 1.27)
							)
						)
					)
				)
			)
		)
	(symbol "antmicropower:+12V"
			(power)
			(pin_names
				(offset 0)
			)
			(exclude_from_sim no)
			(in_bom yes)
			(on_board yes)
			(property "Reference" "#PWR"
				(at 0 -3.81 0)
				(effects
					(font
						(size 1.27 1.27)
					)
					(hide yes)
				)
			)
			(property "Value" "+12V"
				(at 0 3.556 0)
				(effects
					(font
						(size 1.27 1.27)
					)
				)
			)
			(property "Footprint" ""
				(at 0 0 0)
				(effects
					(font
						(size 1.27 1.27)
					)
					(hide yes)
				)
			)
			(property "Datasheet" ""
				(at 0 0 0)
				(effects
					(font
						(size 1.27 1.27)
					)
					(hide yes)
				)
			)
			(property "Description" ""
				(at 0 0 0)
				(effects
					(font
						(size 1.27 1.27)
					)
					(hide yes)
				)
			)
			(symbol "+12V_0_1"
				(polyline
					(pts
						(xy -0.762 1.27) (xy 0 2.54)
					)
					(stroke
						(width 0)
						(type default)
					)
					(fill
						(type none)
					)
				)
				(polyline
					(pts
						(xy 0 2.54) (xy 0.762 1.27)
					)
					(stroke
						(width 0)
						(type default)
					)
					(fill
						(type none)
					)
				)
				(polyline
					(pts
						(xy 0 0) (xy 0 2.54)
					)
					(stroke
						(width 0)
						(type default)
					)
					(fill
						(type none)
					)
				)
			)
			(symbol "+12V_1_1"
				(pin power_in line
					(at 0 0 90)
					(length 0)
					(hide yes)
					(name "+12V"
						(effects
							(font
								(size 1.27 1.27)
							)
						)
					)
					(number "1"
						(effects
							(font
								(size 1.27 1.27)
							)
						)
					)
				)
			)
		)
	(symbol "antmicropower:+1V0"
			(power)
			(pin_names
				(offset 0)
			)
			(exclude_from_sim no)
			(in_bom yes)
			(on_board yes)
			(property "Reference" "#PWR"
				(at 0 -3.81 0)
				(effects
					(font
						(size 1.27 1.27)
					)
					(hide yes)
				)
			)
			(property "Value" "+1V0"
				(at 0 3.556 0)
				(effects
					(font
						(size 1.27 1.27)
					)
				)
			)
			(property "Footprint" ""
				(at 0 0 0)
				(effects
					(font
						(size 1.27 1.27)
					)
					(hide yes)
				)
			)
			(property "Datasheet" ""
				(at 0 0 0)
				(effects
					(font
						(size 1.27 1.27)
					)
					(hide yes)
				)
			)
			(property "Description" ""
				(at 0 0 0)
				(effects
					(font
						(size 1.27 1.27)
					)
					(hide yes)
				)
			)
			(symbol "+1V0_0_1"
				(polyline
					(pts
						(xy -0.762 1.27) (xy 0 2.54)
					)
					(stroke
						(width 0)
						(type default)
					)
					(fill
						(type none)
					)
				)
				(polyline
					(pts
						(xy 0 2.54) (xy 0.762 1.27)
					)
					(stroke
						(width 0)
						(type default)
					)
					(fill
						(type none)
					)
				)
				(polyline
					(pts
						(xy 0 0) (xy 0 2.54)
					)
					(stroke
						(width 0)
						(type default)
					)
					(fill
						(type none)
					)
				)
			)
			(symbol "+1V0_1_1"
				(pin power_in line
					(at 0 0 90)
					(length 0)
					(hide yes)
					(name "+1V0"
						(effects
							(font
								(size 1.27 1.27)
							)
						)
					)
					(number "1"
						(effects
							(font
								(size 1.27 1.27)
							)
						)
					)
				)
			)
		)
	(symbol "antmicropower:+1V0_MGTAVCC"
			(power)
			(pin_names
				(offset 0)
			)
			(exclude_from_sim no)
			(in_bom yes)
			(on_board yes)
			(property "Reference" "#PWR?"
				(at 0 -3.81 0)
				(effects
					(font
						(size 1.27 1.27)
					)
					(hide yes)
				)
			)
			(property "Value" "+1V0_MGTAVCC"
				(at 0 3.81 0)
				(effects
					(font
						(size 1.27 1.27)
					)
				)
			)
			(property "Footprint" ""
				(at 0 0 0)
				(effects
					(font
						(size 1.27 1.27)
					)
					(hide yes)
				)
			)
			(property "Datasheet" ""
				(at 0 0 0)
				(effects
					(font
						(size 1.27 1.27)
					)
					(hide yes)
				)
			)
			(property "Description" ""
				(at 0 0 0)
				(effects
					(font
						(size 1.27 1.27)
					)
					(hide yes)
				)
			)
			(symbol "+1V0_MGTAVCC_0_1"
				(polyline
					(pts
						(xy -0.762 1.27) (xy 0 2.54)
					)
					(stroke
						(width 0)
						(type default)
					)
					(fill
						(type none)
					)
				)
				(polyline
					(pts
						(xy 0 2.54) (xy 0.762 1.27)
					)
					(stroke
						(width 0)
						(type default)
					)
					(fill
						(type none)
					)
				)
				(polyline
					(pts
						(xy 0 0) (xy 0 2.54)
					)
					(stroke
						(width 0)
						(type default)
					)
					(fill
						(type none)
					)
				)
			)
			(symbol "+1V0_MGTAVCC_1_1"
				(pin power_in line
					(at 0 0 90)
					(length 0)
					(hide yes)
					(name "+1V0_MGTAVCC"
						(effects
							(font
								(size 1.27 1.27)
							)
						)
					)
					(number "1"
						(effects
							(font
								(size 1.27 1.27)
							)
						)
					)
				)
			)
		)
	(symbol "antmicropower:+1V1"
			(power)
			(pin_names
				(offset 0)
			)
			(exclude_from_sim no)
			(in_bom yes)
			(on_board yes)
			(property "Reference" "#PWR"
				(at 0 -3.81 0)
				(effects
					(font
						(size 1.27 1.27)
					)
					(hide yes)
				)
			)
			(property "Value" "+1V1"
				(at 0 3.556 0)
				(effects
					(font
						(size 1.27 1.27)
					)
				)
			)
			(property "Footprint" ""
				(at 0 0 0)
				(effects
					(font
						(size 1.27 1.27)
					)
					(hide yes)
				)
			)
			(property "Datasheet" ""
				(at 0 0 0)
				(effects
					(font
						(size 1.27 1.27)
					)
					(hide yes)
				)
			)
			(property "Description" ""
				(at 0 0 0)
				(effects
					(font
						(size 1.27 1.27)
					)
					(hide yes)
				)
			)
			(symbol "+1V1_0_1"
				(polyline
					(pts
						(xy -0.762 1.27) (xy 0 2.54)
					)
					(stroke
						(width 0)
						(type default)
					)
					(fill
						(type none)
					)
				)
				(polyline
					(pts
						(xy 0 2.54) (xy 0.762 1.27)
					)
					(stroke
						(width 0)
						(type default)
					)
					(fill
						(type none)
					)
				)
				(polyline
					(pts
						(xy 0 0) (xy 0 2.54)
					)
					(stroke
						(width 0)
						(type default)
					)
					(fill
						(type none)
					)
				)
			)
			(symbol "+1V1_1_1"
				(pin power_in line
					(at 0 0 90)
					(length 0)
					(hide yes)
					(name "+1V1"
						(effects
							(font
								(size 1.27 1.27)
							)
						)
					)
					(number "1"
						(effects
							(font
								(size 1.27 1.27)
							)
						)
					)
				)
			)
		)
	(symbol "antmicropower:+1V2"
			(power)
			(pin_names
				(offset 0)
			)
			(exclude_from_sim no)
			(in_bom yes)
			(on_board yes)
			(property "Reference" "#PWR"
				(at 0 -3.81 0)
				(effects
					(font
						(size 1.27 1.27)
					)
					(hide yes)
				)
			)
			(property "Value" "+1V2"
				(at 0 3.556 0)
				(effects
					(font
						(size 1.27 1.27)
					)
				)
			)
			(property "Footprint" ""
				(at 0 0 0)
				(effects
					(font
						(size 1.27 1.27)
					)
					(hide yes)
				)
			)
			(property "Datasheet" ""
				(at 0 0 0)
				(effects
					(font
						(size 1.27 1.27)
					)
					(hide yes)
				)
			)
			(property "Description" ""
				(at 0 0 0)
				(effects
					(font
						(size 1.27 1.27)
					)
					(hide yes)
				)
			)
			(symbol "+1V2_0_1"
				(polyline
					(pts
						(xy -0.762 1.27) (xy 0 2.54)
					)
					(stroke
						(width 0)
						(type default)
					)
					(fill
						(type none)
					)
				)
				(polyline
					(pts
						(xy 0 2.54) (xy 0.762 1.27)
					)
					(stroke
						(width 0)
						(type default)
					)
					(fill
						(type none)
					)
				)
				(polyline
					(pts
						(xy 0 0) (xy 0 2.54)
					)
					(stroke
						(width 0)
						(type default)
					)
					(fill
						(type none)
					)
				)
			)
			(symbol "+1V2_1_1"
				(pin power_in line
					(at 0 0 90)
					(length 0)
					(hide yes)
					(name "+1V2"
						(effects
							(font
								(size 1.27 1.27)
							)
						)
					)
					(number "1"
						(effects
							(font
								(size 1.27 1.27)
							)
						)
					)
				)
			)
		)
	(symbol "antmicropower:+1V2_MGTAVTT"
			(power)
			(pin_names
				(offset 0)
			)
			(exclude_from_sim no)
			(in_bom yes)
			(on_board yes)
			(property "Reference" "#PWR?"
				(at 0 -3.81 0)
				(effects
					(font
						(size 1.27 1.27)
					)
					(hide yes)
				)
			)
			(property "Value" "+1V2_MGTAVTT"
				(at 0 3.81 0)
				(effects
					(font
						(size 1.27 1.27)
					)
				)
			)
			(property "Footprint" ""
				(at 0 0 0)
				(effects
					(font
						(size 1.27 1.27)
					)
					(hide yes)
				)
			)
			(property "Datasheet" ""
				(at 0 0 0)
				(effects
					(font
						(size 1.27 1.27)
					)
					(hide yes)
				)
			)
			(property "Description" ""
				(at 0 0 0)
				(effects
					(font
						(size 1.27 1.27)
					)
					(hide yes)
				)
			)
			(symbol "+1V2_MGTAVTT_0_1"
				(polyline
					(pts
						(xy -0.762 1.27) (xy 0 2.54)
					)
					(stroke
						(width 0)
						(type default)
					)
					(fill
						(type none)
					)
				)
				(polyline
					(pts
						(xy 0 2.54) (xy 0.762 1.27)
					)
					(stroke
						(width 0)
						(type default)
					)
					(fill
						(type none)
					)
				)
				(polyline
					(pts
						(xy 0 0) (xy 0 2.54)
					)
					(stroke
						(width 0)
						(type default)
					)
					(fill
						(type none)
					)
				)
			)
			(symbol "+1V2_MGTAVTT_1_1"
				(pin power_in line
					(at 0 0 90)
					(length 0)
					(hide yes)
					(name "+1V2_MGTAVTT"
						(effects
							(font
								(size 1.27 1.27)
							)
						)
					)
					(number "1"
						(effects
							(font
								(size 1.27 1.27)
							)
						)
					)
				)
			)
		)
	(symbol "antmicropower:+1V8"
			(power)
			(pin_numbers
				(hide yes)
			)
			(pin_names
				(hide yes)
			)
			(exclude_from_sim no)
			(in_bom yes)
			(on_board yes)
			(property "Reference" "#PWR"
				(at 15.24 -2.54 0)
				(effects
					(font
						(size 1.27 1.27)
						(thickness 0.15)
					)
					(justify left bottom)
					(hide yes)
				)
			)
			(property "Value" "+1V8"
				(at -3.175 2.54 0)
				(effects
					(font
						(size 1.27 1.27)
						(thickness 0.15)
					)
					(justify left bottom)
				)
			)
			(property "Footprint" ""
				(at 15.24 -7.62 0)
				(effects
					(font
						(size 1.27 1.27)
						(thickness 0.15)
					)
					(justify left bottom)
					(hide yes)
				)
			)
			(property "Datasheet" ""
				(at 15.24 -10.16 0)
				(effects
					(font
						(size 1.27 1.27)
						(thickness 0.15)
					)
					(justify left bottom)
					(hide yes)
				)
			)
			(property "Description" ""
				(at 0 0 0)
				(effects
					(font
						(size 1.27 1.27)
					)
					(hide yes)
				)
			)
			(property "Author" "Antmicro"
				(at 15.24 -5.08 0)
				(effects
					(font
						(size 1.27 1.27)
						(thickness 0.15)
					)
					(justify left bottom)
					(hide yes)
				)
			)
			(property "License" "Apache-2.0"
				(at 15.24 -7.62 0)
				(effects
					(font
						(size 1.27 1.27)
						(thickness 0.15)
					)
					(justify left bottom)
					(hide yes)
				)
			)
			(symbol "+1V8_1_1"
				(polyline
					(pts
						(xy -0.762 1.27) (xy 0 2.54)
					)
					(stroke
						(width 0)
						(type default)
					)
					(fill
						(type background)
					)
				)
				(polyline
					(pts
						(xy 0 2.54) (xy 0.762 1.27)
					)
					(stroke
						(width 0)
						(type default)
					)
					(fill
						(type background)
					)
				)
				(polyline
					(pts
						(xy 0 0) (xy 0 2.54)
					)
					(stroke
						(width 0)
						(type default)
					)
					(fill
						(type background)
					)
				)
				(pin power_in line
					(at 0 0 90)
					(length 0)
					(hide yes)
					(name "+1V8"
						(effects
							(font
								(size 1.27 1.27)
							)
						)
					)
					(number "1"
						(effects
							(font
								(size 1.27 1.27)
							)
						)
					)
				)
			)
		)
	(symbol "antmicropower:+3V3"
			(power)
			(pin_numbers
				(hide yes)
			)
			(pin_names
				(hide yes)
			)
			(exclude_from_sim no)
			(in_bom yes)
			(on_board yes)
			(property "Reference" "#PWR"
				(at 15.24 0 0)
				(effects
					(font
						(size 1.27 1.27)
						(thickness 0.15)
					)
					(justify left bottom)
					(hide yes)
				)
			)
			(property "Value" "+3V3"
				(at -3.175 2.54 0)
				(effects
					(font
						(size 1.27 1.27)
						(thickness 0.15)
					)
					(justify left bottom)
				)
			)
			(property "Footprint" ""
				(at 15.24 -7.62 0)
				(effects
					(font
						(size 1.27 1.27)
						(thickness 0.15)
					)
					(justify left bottom)
					(hide yes)
				)
			)
			(property "Datasheet" ""
				(at 15.24 -10.16 0)
				(effects
					(font
						(size 1.27 1.27)
						(thickness 0.15)
					)
					(justify left bottom)
					(hide yes)
				)
			)
			(property "Description" ""
				(at 0 0 0)
				(effects
					(font
						(size 1.27 1.27)
					)
					(hide yes)
				)
			)
			(property "Author" "Antmicro"
				(at 15.24 -2.54 0)
				(effects
					(font
						(size 1.27 1.27)
						(thickness 0.15)
					)
					(justify left bottom)
					(hide yes)
				)
			)
			(property "License" "Apache-2.0"
				(at 15.24 -5.08 0)
				(effects
					(font
						(size 1.27 1.27)
						(thickness 0.15)
					)
					(justify left bottom)
					(hide yes)
				)
			)
			(symbol "+3V3_0_1"
				(polyline
					(pts
						(xy 0 2.54) (xy -0.762 1.27)
					)
					(stroke
						(width 0)
						(type default)
					)
					(fill
						(type none)
					)
				)
				(polyline
					(pts
						(xy 0 2.54) (xy 0.762 1.27)
					)
					(stroke
						(width 0)
						(type default)
					)
					(fill
						(type none)
					)
				)
				(polyline
					(pts
						(xy 0 0) (xy 0 2.54)
					)
					(stroke
						(width 0)
						(type default)
					)
					(fill
						(type none)
					)
				)
			)
			(symbol "+3V3_1_1"
				(pin power_in line
					(at 0 0 90)
					(length 0)
					(hide yes)
					(name "+3V3"
						(effects
							(font
								(size 1.27 1.27)
							)
						)
					)
					(number "1"
						(effects
							(font
								(size 1.27 1.27)
							)
						)
					)
				)
			)
		)
	(symbol "antmicropower:+3V3_AON"
			(power)
			(pin_names
				(offset 0)
			)
			(exclude_from_sim no)
			(in_bom yes)
			(on_board yes)
			(property "Reference" "#PWR"
				(at 0 -3.81 0)
				(effects
					(font
						(size 1.27 1.27)
					)
					(hide yes)
				)
			)
			(property "Value" "+3V3_AON"
				(at 0 3.556 0)
				(effects
					(font
						(size 1.27 1.27)
					)
				)
			)
			(property "Footprint" ""
				(at 0 0 0)
				(effects
					(font
						(size 1.27 1.27)
					)
					(hide yes)
				)
			)
			(property "Datasheet" ""
				(at 0 0 0)
				(effects
					(font
						(size 1.27 1.27)
					)
					(hide yes)
				)
			)
			(property "Description" ""
				(at 0 0 0)
				(effects
					(font
						(size 1.27 1.27)
					)
					(hide yes)
				)
			)
			(symbol "+3V3_AON_0_1"
				(polyline
					(pts
						(xy -0.762 1.27) (xy 0 2.54)
					)
					(stroke
						(width 0)
						(type default)
					)
					(fill
						(type none)
					)
				)
				(polyline
					(pts
						(xy 0 2.54) (xy 0.762 1.27)
					)
					(stroke
						(width 0)
						(type default)
					)
					(fill
						(type none)
					)
				)
				(polyline
					(pts
						(xy 0 0) (xy 0 2.54)
					)
					(stroke
						(width 0)
						(type default)
					)
					(fill
						(type none)
					)
				)
			)
			(symbol "+3V3_AON_1_1"
				(pin power_in line
					(at 0 0 90)
					(length 0)
					(hide yes)
					(name "+3V3_AON"
						(effects
							(font
								(size 1.27 1.27)
							)
						)
					)
					(number "1"
						(effects
							(font
								(size 1.27 1.27)
							)
						)
					)
				)
			)
		)
	(symbol "antmicropower:+5V"
			(power)
			(pin_numbers
				(hide yes)
			)
			(pin_names
				(hide yes)
			)
			(exclude_from_sim no)
			(in_bom yes)
			(on_board yes)
			(property "Reference" "#PWR"
				(at 15.24 -2.54 0)
				(effects
					(font
						(size 1.27 1.27)
						(thickness 0.15)
					)
					(justify left bottom)
					(hide yes)
				)
			)
			(property "Value" "+5V"
				(at 15.24 -5.08 0)
				(effects
					(font
						(size 1.27 1.27)
						(thickness 0.15)
					)
					(justify left bottom)
				)
			)
			(property "Footprint" ""
				(at 15.24 -7.62 0)
				(effects
					(font
						(size 1.27 1.27)
						(thickness 0.15)
					)
					(justify left bottom)
					(hide yes)
				)
			)
			(property "Datasheet" ""
				(at 15.24 -10.16 0)
				(effects
					(font
						(size 1.27 1.27)
						(thickness 0.15)
					)
					(justify left bottom)
					(hide yes)
				)
			)
			(property "Description" ""
				(at 0 0 0)
				(effects
					(font
						(size 1.27 1.27)
					)
					(hide yes)
				)
			)
			(property "Author" "Antmicro"
				(at 15.24 -7.62 0)
				(effects
					(font
						(size 1.27 1.27)
						(thickness 0.15)
					)
					(justify left bottom)
					(hide yes)
				)
			)
			(property "License" "Apache-2.0"
				(at 15.24 -10.16 0)
				(effects
					(font
						(size 1.27 1.27)
						(thickness 0.15)
					)
					(justify left bottom)
					(hide yes)
				)
			)
			(symbol "+5V_1_1"
				(polyline
					(pts
						(xy -0.762 1.27) (xy 0 2.54)
					)
					(stroke
						(width 0)
						(type default)
					)
					(fill
						(type background)
					)
				)
				(polyline
					(pts
						(xy 0 2.54) (xy 0.762 1.27)
					)
					(stroke
						(width 0)
						(type default)
					)
					(fill
						(type background)
					)
				)
				(polyline
					(pts
						(xy 0 0) (xy 0 2.54)
					)
					(stroke
						(width 0)
						(type default)
					)
					(fill
						(type background)
					)
				)
				(pin power_in line
					(at 0 0 90)
					(length 0)
					(name "+5V"
						(effects
							(font
								(size 1.27 1.27)
							)
						)
					)
					(number "1"
						(effects
							(font
								(size 1.27 1.27)
							)
						)
					)
				)
			)
		)
	(symbol "antmicropower:GND"
			(power)
			(pin_numbers
				(hide yes)
			)
			(pin_names
				(hide yes)
			)
			(exclude_from_sim no)
			(in_bom yes)
			(on_board yes)
			(property "Reference" "#PWR"
				(at 8.89 -2.54 0)
				(effects
					(font
						(size 1.27 1.27)
						(thickness 0.15)
					)
					(justify left bottom)
					(hide yes)
				)
			)
			(property "Value" "GND"
				(at 8.89 -5.08 0)
				(effects
					(font
						(size 1.27 1.27)
						(thickness 0.15)
					)
					(justify left bottom)
				)
			)
			(property "Footprint" ""
				(at 8.89 -7.62 0)
				(effects
					(font
						(size 1.27 1.27)
						(thickness 0.15)
					)
					(justify left bottom)
					(hide yes)
				)
			)
			(property "Datasheet" ""
				(at 8.89 -12.7 0)
				(effects
					(font
						(size 1.27 1.27)
						(thickness 0.15)
					)
					(justify left bottom)
					(hide yes)
				)
			)
			(property "Description" ""
				(at 8.89 -15.24 0)
				(effects
					(font
						(size 1.27 1.27)
					)
					(justify left bottom)
					(hide yes)
				)
			)
			(property "Author" "Antmicro"
				(at 8.89 -7.62 0)
				(effects
					(font
						(size 1.27 1.27)
						(thickness 0.15)
					)
					(justify left bottom)
					(hide yes)
				)
			)
			(property "License" "Apache-2.0"
				(at 8.89 -10.16 0)
				(effects
					(font
						(size 1.27 1.27)
						(thickness 0.15)
					)
					(justify left bottom)
					(hide yes)
				)
			)
			(symbol "GND_1_1"
				(polyline
					(pts
						(xy 0 0) (xy 0 -1.27) (xy 1.27 -1.27) (xy 0 -2.54) (xy -1.27 -1.27) (xy 0 -1.27)
					)
					(stroke
						(width 0)
						(type default)
					)
					(fill
						(type none)
					)
				)
				(pin power_in line
					(at 0 0 270)
					(length 0)
					(name "GND"
						(effects
							(font
								(size 1.27 1.27)
							)
						)
					)
					(number "1"
						(effects
							(font
								(size 1.27 1.27)
							)
						)
					)
				)
			)
		)
	(symbol "antmicropower:PWR_FLAG"
			(power)
			(pin_numbers
				(hide yes)
			)
			(pin_names
				(offset 0)
				(hide yes)
			)
			(exclude_from_sim no)
			(in_bom yes)
			(on_board yes)
			(property "Reference" "#FLG"
				(at 0 1.905 0)
				(effects
					(font
						(size 1.27 1.27)
					)
					(hide yes)
				)
			)
			(property "Value" "PWR_FLAG"
				(at 0 3.81 0)
				(effects
					(font
						(size 1.27 1.27)
					)
				)
			)
			(property "Footprint" ""
				(at 0 0 0)
				(effects
					(font
						(size 1.27 1.27)
					)
					(hide yes)
				)
			)
			(property "Datasheet" ""
				(at 0 0 0)
				(effects
					(font
						(size 1.27 1.27)
					)
					(hide yes)
				)
			)
			(property "Description" ""
				(at 0 0 0)
				(effects
					(font
						(size 1.27 1.27)
					)
					(hide yes)
				)
			)
			(symbol "PWR_FLAG_0_0"
				(pin power_out line
					(at 0 0 90)
					(length 0)
					(name "pwr"
						(effects
							(font
								(size 1.27 1.27)
							)
						)
					)
					(number "1"
						(effects
							(font
								(size 1.27 1.27)
							)
						)
					)
				)
			)
			(symbol "PWR_FLAG_0_1"
				(polyline
					(pts
						(xy 0 0) (xy 0 1.27) (xy -1.016 1.905) (xy 0 2.54) (xy 1.016 1.905) (xy 0 1.27)
					)
					(stroke
						(width 0)
						(type default)
					)
					(fill
						(type none)
					)
				)
			)
		)
	(symbol "antmicropower:VDC"
			(power)
			(pin_names
				(offset 0)
			)
			(exclude_from_sim no)
			(in_bom yes)
			(on_board yes)
			(property "Reference" "#PWR"
				(at 0 -2.54 0)
				(effects
					(font
						(size 1.27 1.27)
					)
					(hide yes)
				)
			)
			(property "Value" "VDC"
				(at 0 6.35 0)
				(effects
					(font
						(size 1.27 1.27)
					)
				)
			)
			(property "Footprint" ""
				(at 0 0 0)
				(effects
					(font
						(size 1.27 1.27)
					)
					(hide yes)
				)
			)
			(property "Datasheet" ""
				(at 0 0 0)
				(effects
					(font
						(size 1.27 1.27)
					)
					(hide yes)
				)
			)
			(property "Description" ""
				(at 0 0 0)
				(effects
					(font
						(size 1.27 1.27)
					)
					(hide yes)
				)
			)
			(symbol "VDC_0_1"
				(polyline
					(pts
						(xy -0.762 1.27) (xy 0 2.54)
					)
					(stroke
						(width 0)
						(type default)
					)
					(fill
						(type none)
					)
				)
				(polyline
					(pts
						(xy 0 2.54) (xy 0.762 1.27)
					)
					(stroke
						(width 0)
						(type default)
					)
					(fill
						(type none)
					)
				)
				(polyline
					(pts
						(xy 0 0) (xy 0 2.54)
					)
					(stroke
						(width 0)
						(type default)
					)
					(fill
						(type none)
					)
				)
			)
			(symbol "VDC_1_1"
				(pin power_in line
					(at 0 0 90)
					(length 0)
					(hide yes)
					(name "VDC"
						(effects
							(font
								(size 1.27 1.27)
							)
						)
					)
					(number "1"
						(effects
							(font
								(size 1.27 1.27)
							)
						)
					)
				)
			)
		)
	(symbol "sodimm-ddr5-tester:GND_10"
			(power)
			(pin_names
				(offset 0)
			)
			(exclude_from_sim no)
			(in_bom yes)
			(on_board yes)
			(property "Reference" "#PWR"
				(at 0 -6.35 0)
				(effects
					(font
						(size 1.27 1.27)
					)
				)
			)
			(property "Value" "GND_10"
				(at 0 -3.81 0)
				(effects
					(font
						(size 1.27 1.27)
					)
				)
			)
			(property "Footprint" ""
				(at 0 0 0)
				(effects
					(font
						(size 1.27 1.27)
					)
					(hide yes)
				)
			)
			(property "Datasheet" ""
				(at 0 0 0)
				(effects
					(font
						(size 1.27 1.27)
					)
					(hide yes)
				)
			)
			(property "Description" ""
				(at 0 0 0)
				(effects
					(font
						(size 1.27 1.27)
					)
					(hide yes)
				)
			)
			(symbol "GND_10_0_1"
				(polyline
					(pts
						(xy 0 0) (xy 0 -1.27) (xy 1.27 -1.27) (xy 0 -2.54) (xy -1.27 -1.27) (xy 0 -1.27)
					)
					(stroke
						(width 0)
						(type default)
					)
					(fill
						(type none)
					)
				)
			)
			(symbol "GND_10_1_1"
				(pin power_in line
					(at 0 0 270)
					(length 0)
					(hide yes)
					(name "GND"
						(effects
							(font
								(size 1.27 1.27)
							)
						)
					)
					(number "1"
						(effects
							(font
								(size 1.27 1.27)
							)
						)
					)
				)
			)
		)
	(symbol "sodimm-ddr5-tester:GND_11"
			(power)
			(pin_names
				(offset 0)
			)
			(exclude_from_sim no)
			(in_bom yes)
			(on_board yes)
			(property "Reference" "#PWR"
				(at 0 -6.35 0)
				(effects
					(font
						(size 1.27 1.27)
					)
					(hide yes)
				)
			)
			(property "Value" "GND_11"
				(at 0 -3.81 0)
				(effects
					(font
						(size 1.27 1.27)
					)
				)
			)
			(property "Footprint" ""
				(at 0 0 0)
				(effects
					(font
						(size 1.27 1.27)
					)
					(hide yes)
				)
			)
			(property "Datasheet" ""
				(at 0 0 0)
				(effects
					(font
						(size 1.27 1.27)
					)
					(hide yes)
				)
			)
			(property "Description" ""
				(at 0 0 0)
				(effects
					(font
						(size 1.27 1.27)
					)
					(hide yes)
				)
			)
			(symbol "GND_11_0_1"
				(polyline
					(pts
						(xy 0 0) (xy 0 -1.27) (xy 1.27 -1.27) (xy 0 -2.54) (xy -1.27 -1.27) (xy 0 -1.27)
					)
					(stroke
						(width 0)
						(type default)
					)
					(fill
						(type none)
					)
				)
			)
			(symbol "GND_11_1_1"
				(pin power_in line
					(at 0 0 270)
					(length 0)
					(hide yes)
					(name "GND"
						(effects
							(font
								(size 1.27 1.27)
							)
						)
					)
					(number "1"
						(effects
							(font
								(size 1.27 1.27)
							)
						)
					)
				)
			)
		)
	(symbol "sodimm-ddr5-tester:GND_12"
			(power)
			(pin_names
				(offset 0)
			)
			(exclude_from_sim no)
			(in_bom yes)
			(on_board yes)
			(property "Reference" "#PWR"
				(at 0 -6.35 0)
				(effects
					(font
						(size 1.27 1.27)
					)
					(hide yes)
				)
			)
			(property "Value" "GND_12"
				(at 0 -3.81 0)
				(effects
					(font
						(size 1.27 1.27)
					)
				)
			)
			(property "Footprint" ""
				(at 0 0 0)
				(effects
					(font
						(size 1.27 1.27)
					)
					(hide yes)
				)
			)
			(property "Datasheet" ""
				(at 0 0 0)
				(effects
					(font
						(size 1.27 1.27)
					)
					(hide yes)
				)
			)
			(property "Description" ""
				(at 0 0 0)
				(effects
					(font
						(size 1.27 1.27)
					)
					(hide yes)
				)
			)
			(symbol "GND_12_0_1"
				(polyline
					(pts
						(xy 0 0) (xy 0 -1.27) (xy 1.27 -1.27) (xy 0 -2.54) (xy -1.27 -1.27) (xy 0 -1.27)
					)
					(stroke
						(width 0)
						(type default)
					)
					(fill
						(type none)
					)
				)
			)
			(symbol "GND_12_1_1"
				(pin power_in line
					(at 0 0 270)
					(length 0)
					(hide yes)
					(name "GND"
						(effects
							(font
								(size 1.27 1.27)
							)
						)
					)
					(number "1"
						(effects
							(font
								(size 1.27 1.27)
							)
						)
					)
				)
			)
		)
	(symbol "sodimm-ddr5-tester:GND_13"
			(power)
			(pin_names
				(offset 0)
			)
			(exclude_from_sim no)
			(in_bom yes)
			(on_board yes)
			(property "Reference" "#PWR"
				(at 0 -6.35 0)
				(effects
					(font
						(size 1.27 1.27)
					)
					(hide yes)
				)
			)
			(property "Value" "GND_13"
				(at 0 -3.81 0)
				(effects
					(font
						(size 1.27 1.27)
					)
				)
			)
			(property "Footprint" ""
				(at 0 0 0)
				(effects
					(font
						(size 1.27 1.27)
					)
					(hide yes)
				)
			)
			(property "Datasheet" ""
				(at 0 0 0)
				(effects
					(font
						(size 1.27 1.27)
					)
					(hide yes)
				)
			)
			(property "Description" ""
				(at 0 0 0)
				(effects
					(font
						(size 1.27 1.27)
					)
					(hide yes)
				)
			)
			(symbol "GND_13_0_1"
				(polyline
					(pts
						(xy 0 0) (xy 0 -1.27) (xy 1.27 -1.27) (xy 0 -2.54) (xy -1.27 -1.27) (xy 0 -1.27)
					)
					(stroke
						(width 0)
						(type default)
					)
					(fill
						(type none)
					)
				)
			)
			(symbol "GND_13_1_1"
				(pin power_in line
					(at 0 0 270)
					(length 0)
					(hide yes)
					(name "GND"
						(effects
							(font
								(size 1.27 1.27)
							)
						)
					)
					(number "1"
						(effects
							(font
								(size 1.27 1.27)
							)
						)
					)
				)
			)
		)
	(symbol "sodimm-ddr5-tester:GND_14"
			(power)
			(pin_names
				(offset 0)
			)
			(exclude_from_sim no)
			(in_bom yes)
			(on_board yes)
			(property "Reference" "#PWR"
				(at 0 -6.35 0)
				(effects
					(font
						(size 1.27 1.27)
					)
					(hide yes)
				)
			)
			(property "Value" "GND_14"
				(at 0 -3.81 0)
				(effects
					(font
						(size 1.27 1.27)
					)
				)
			)
			(property "Footprint" ""
				(at 0 0 0)
				(effects
					(font
						(size 1.27 1.27)
					)
					(hide yes)
				)
			)
			(property "Datasheet" ""
				(at 0 0 0)
				(effects
					(font
						(size 1.27 1.27)
					)
					(hide yes)
				)
			)
			(property "Description" ""
				(at 0 0 0)
				(effects
					(font
						(size 1.27 1.27)
					)
					(hide yes)
				)
			)
			(symbol "GND_14_0_1"
				(polyline
					(pts
						(xy 0 0) (xy 0 -1.27) (xy 1.27 -1.27) (xy 0 -2.54) (xy -1.27 -1.27) (xy 0 -1.27)
					)
					(stroke
						(width 0)
						(type default)
					)
					(fill
						(type none)
					)
				)
			)
			(symbol "GND_14_1_1"
				(pin power_in line
					(at 0 0 270)
					(length 0)
					(hide yes)
					(name "GND"
						(effects
							(font
								(size 1.27 1.27)
							)
						)
					)
					(number "1"
						(effects
							(font
								(size 1.27 1.27)
							)
						)
					)
				)
			)
		)
	(symbol "sodimm-ddr5-tester:GND_15"
			(power)
			(pin_names
				(offset 0)
			)
			(exclude_from_sim no)
			(in_bom yes)
			(on_board yes)
			(property "Reference" "#PWR"
				(at 0 -6.35 0)
				(effects
					(font
						(size 1.27 1.27)
					)
					(hide yes)
				)
			)
			(property "Value" "GND_15"
				(at 0 -3.81 0)
				(effects
					(font
						(size 1.27 1.27)
					)
				)
			)
			(property "Footprint" ""
				(at 0 0 0)
				(effects
					(font
						(size 1.27 1.27)
					)
					(hide yes)
				)
			)
			(property "Datasheet" ""
				(at 0 0 0)
				(effects
					(font
						(size 1.27 1.27)
					)
					(hide yes)
				)
			)
			(property "Description" ""
				(at 0 0 0)
				(effects
					(font
						(size 1.27 1.27)
					)
					(hide yes)
				)
			)
			(symbol "GND_15_0_1"
				(polyline
					(pts
						(xy 0 0) (xy 0 -1.27) (xy 1.27 -1.27) (xy 0 -2.54) (xy -1.27 -1.27) (xy 0 -1.27)
					)
					(stroke
						(width 0)
						(type default)
					)
					(fill
						(type none)
					)
				)
			)
			(symbol "GND_15_1_1"
				(pin power_in line
					(at 0 0 270)
					(length 0)
					(hide yes)
					(name "GND"
						(effects
							(font
								(size 1.27 1.27)
							)
						)
					)
					(number "1"
						(effects
							(font
								(size 1.27 1.27)
							)
						)
					)
				)
			)
		)
	(symbol "sodimm-ddr5-tester:GND_16"
			(power)
			(pin_names
				(offset 0)
			)
			(exclude_from_sim no)
			(in_bom yes)
			(on_board yes)
			(property "Reference" "#PWR"
				(at 0 -6.35 0)
				(effects
					(font
						(size 1.27 1.27)
					)
					(hide yes)
				)
			)
			(property "Value" "GND_16"
				(at 0 -3.81 0)
				(effects
					(font
						(size 1.27 1.27)
					)
				)
			)
			(property "Footprint" ""
				(at 0 0 0)
				(effects
					(font
						(size 1.27 1.27)
					)
					(hide yes)
				)
			)
			(property "Datasheet" ""
				(at 0 0 0)
				(effects
					(font
						(size 1.27 1.27)
					)
					(hide yes)
				)
			)
			(property "Description" ""
				(at 0 0 0)
				(effects
					(font
						(size 1.27 1.27)
					)
					(hide yes)
				)
			)
			(symbol "GND_16_0_1"
				(polyline
					(pts
						(xy 0 0) (xy 0 -1.27) (xy 1.27 -1.27) (xy 0 -2.54) (xy -1.27 -1.27) (xy 0 -1.27)
					)
					(stroke
						(width 0)
						(type default)
					)
					(fill
						(type none)
					)
				)
			)
			(symbol "GND_16_1_1"
				(pin power_in line
					(at 0 0 270)
					(length 0)
					(hide yes)
					(name "GND"
						(effects
							(font
								(size 1.27 1.27)
							)
						)
					)
					(number "1"
						(effects
							(font
								(size 1.27 1.27)
							)
						)
					)
				)
			)
		)
	(symbol "sodimm-ddr5-tester:GND_17"
			(power)
			(pin_names
				(offset 0)
			)
			(exclude_from_sim no)
			(in_bom yes)
			(on_board yes)
			(property "Reference" "#PWR"
				(at 0 -6.35 0)
				(effects
					(font
						(size 1.27 1.27)
					)
					(hide yes)
				)
			)
			(property "Value" "GND_17"
				(at 0 -3.81 0)
				(effects
					(font
						(size 1.27 1.27)
					)
				)
			)
			(property "Footprint" ""
				(at 0 0 0)
				(effects
					(font
						(size 1.27 1.27)
					)
					(hide yes)
				)
			)
			(property "Datasheet" ""
				(at 0 0 0)
				(effects
					(font
						(size 1.27 1.27)
					)
					(hide yes)
				)
			)
			(property "Description" ""
				(at 0 0 0)
				(effects
					(font
						(size 1.27 1.27)
					)
					(hide yes)
				)
			)
			(symbol "GND_17_0_1"
				(polyline
					(pts
						(xy 0 0) (xy 0 -1.27) (xy 1.27 -1.27) (xy 0 -2.54) (xy -1.27 -1.27) (xy 0 -1.27)
					)
					(stroke
						(width 0)
						(type default)
					)
					(fill
						(type none)
					)
				)
			)
			(symbol "GND_17_1_1"
				(pin power_in line
					(at 0 0 270)
					(length 0)
					(hide yes)
					(name "GND"
						(effects
							(font
								(size 1.27 1.27)
							)
						)
					)
					(number "1"
						(effects
							(font
								(size 1.27 1.27)
							)
						)
					)
				)
			)
		)
	(symbol "sodimm-ddr5-tester:GND_18"
			(power)
			(pin_names
				(offset 0)
			)
			(exclude_from_sim no)
			(in_bom yes)
			(on_board yes)
			(property "Reference" "#PWR"
				(at 0 -6.35 0)
				(effects
					(font
						(size 1.27 1.27)
					)
					(hide yes)
				)
			)
			(property "Value" "GND_18"
				(at 0 -3.81 0)
				(effects
					(font
						(size 1.27 1.27)
					)
				)
			)
			(property "Footprint" ""
				(at 0 0 0)
				(effects
					(font
						(size 1.27 1.27)
					)
					(hide yes)
				)
			)
			(property "Datasheet" ""
				(at 0 0 0)
				(effects
					(font
						(size 1.27 1.27)
					)
					(hide yes)
				)
			)
			(property "Description" ""
				(at 0 0 0)
				(effects
					(font
						(size 1.27 1.27)
					)
					(hide yes)
				)
			)
			(symbol "GND_18_0_1"
				(polyline
					(pts
						(xy 0 0) (xy 0 -1.27) (xy 1.27 -1.27) (xy 0 -2.54) (xy -1.27 -1.27) (xy 0 -1.27)
					)
					(stroke
						(width 0)
						(type default)
					)
					(fill
						(type none)
					)
				)
			)
			(symbol "GND_18_1_1"
				(pin power_in line
					(at 0 0 270)
					(length 0)
					(hide yes)
					(name "GND"
						(effects
							(font
								(size 1.27 1.27)
							)
						)
					)
					(number "1"
						(effects
							(font
								(size 1.27 1.27)
							)
						)
					)
				)
			)
		)
	(symbol "sodimm-ddr5-tester:GND_19"
			(power)
			(pin_names
				(offset 0)
			)
			(exclude_from_sim no)
			(in_bom yes)
			(on_board yes)
			(property "Reference" "#PWR"
				(at 0 -6.35 0)
				(effects
					(font
						(size 1.27 1.27)
					)
					(hide yes)
				)
			)
			(property "Value" "GND_19"
				(at 0 -3.81 0)
				(effects
					(font
						(size 1.27 1.27)
					)
				)
			)
			(property "Footprint" ""
				(at 0 0 0)
				(effects
					(font
						(size 1.27 1.27)
					)
					(hide yes)
				)
			)
			(property "Datasheet" ""
				(at 0 0 0)
				(effects
					(font
						(size 1.27 1.27)
					)
					(hide yes)
				)
			)
			(property "Description" ""
				(at 0 0 0)
				(effects
					(font
						(size 1.27 1.27)
					)
					(hide yes)
				)
			)
			(symbol "GND_19_0_1"
				(polyline
					(pts
						(xy 0 0) (xy 0 -1.27) (xy 1.27 -1.27) (xy 0 -2.54) (xy -1.27 -1.27) (xy 0 -1.27)
					)
					(stroke
						(width 0)
						(type default)
					)
					(fill
						(type none)
					)
				)
			)
			(symbol "GND_19_1_1"
				(pin power_in line
					(at 0 0 270)
					(length 0)
					(hide yes)
					(name "GND"
						(effects
							(font
								(size 1.27 1.27)
							)
						)
					)
					(number "1"
						(effects
							(font
								(size 1.27 1.27)
							)
						)
					)
				)
			)
		)
	(symbol "sodimm-ddr5-tester:GND_20"
			(power)
			(pin_names
				(offset 0)
			)
			(exclude_from_sim no)
			(in_bom yes)
			(on_board yes)
			(property "Reference" "#PWR"
				(at 0 -6.35 0)
				(effects
					(font
						(size 1.27 1.27)
					)
					(hide yes)
				)
			)
			(property "Value" "GND_20"
				(at 0 -3.81 0)
				(effects
					(font
						(size 1.27 1.27)
					)
				)
			)
			(property "Footprint" ""
				(at 0 0 0)
				(effects
					(font
						(size 1.27 1.27)
					)
					(hide yes)
				)
			)
			(property "Datasheet" ""
				(at 0 0 0)
				(effects
					(font
						(size 1.27 1.27)
					)
					(hide yes)
				)
			)
			(property "Description" ""
				(at 0 0 0)
				(effects
					(font
						(size 1.27 1.27)
					)
					(hide yes)
				)
			)
			(symbol "GND_20_0_1"
				(polyline
					(pts
						(xy 0 0) (xy 0 -1.27) (xy 1.27 -1.27) (xy 0 -2.54) (xy -1.27 -1.27) (xy 0 -1.27)
					)
					(stroke
						(width 0)
						(type default)
					)
					(fill
						(type none)
					)
				)
			)
			(symbol "GND_20_1_1"
				(pin power_in line
					(at 0 0 270)
					(length 0)
					(hide yes)
					(name "GND"
						(effects
							(font
								(size 1.27 1.27)
							)
						)
					)
					(number "1"
						(effects
							(font
								(size 1.27 1.27)
							)
						)
					)
				)
			)
		)
	(symbol "sodimm-ddr5-tester:GND_21"
			(power)
			(pin_names
				(offset 0)
			)
			(exclude_from_sim no)
			(in_bom yes)
			(on_board yes)
			(property "Reference" "#PWR"
				(at 0 -6.35 0)
				(effects
					(font
						(size 1.27 1.27)
					)
					(hide yes)
				)
			)
			(property "Value" "GND_21"
				(at 0 -3.81 0)
				(effects
					(font
						(size 1.27 1.27)
					)
				)
			)
			(property "Footprint" ""
				(at 0 0 0)
				(effects
					(font
						(size 1.27 1.27)
					)
					(hide yes)
				)
			)
			(property "Datasheet" ""
				(at 0 0 0)
				(effects
					(font
						(size 1.27 1.27)
					)
					(hide yes)
				)
			)
			(property "Description" ""
				(at 0 0 0)
				(effects
					(font
						(size 1.27 1.27)
					)
					(hide yes)
				)
			)
			(symbol "GND_21_0_1"
				(polyline
					(pts
						(xy 0 0) (xy 0 -1.27) (xy 1.27 -1.27) (xy 0 -2.54) (xy -1.27 -1.27) (xy 0 -1.27)
					)
					(stroke
						(width 0)
						(type default)
					)
					(fill
						(type none)
					)
				)
			)
			(symbol "GND_21_1_1"
				(pin power_in line
					(at 0 0 270)
					(length 0)
					(hide yes)
					(name "GND"
						(effects
							(font
								(size 1.27 1.27)
							)
						)
					)
					(number "1"
						(effects
							(font
								(size 1.27 1.27)
							)
						)
					)
				)
			)
		)
	(symbol "sodimm-ddr5-tester:GND_22"
			(power)
			(pin_names
				(offset 0)
			)
			(exclude_from_sim no)
			(in_bom yes)
			(on_board yes)
			(property "Reference" "#PWR"
				(at 0 -6.35 0)
				(effects
					(font
						(size 1.27 1.27)
					)
					(hide yes)
				)
			)
			(property "Value" "GND_22"
				(at 0 -3.81 0)
				(effects
					(font
						(size 1.27 1.27)
					)
				)
			)
			(property "Footprint" ""
				(at 0 0 0)
				(effects
					(font
						(size 1.27 1.27)
					)
					(hide yes)
				)
			)
			(property "Datasheet" ""
				(at 0 0 0)
				(effects
					(font
						(size 1.27 1.27)
					)
					(hide yes)
				)
			)
			(property "Description" ""
				(at 0 0 0)
				(effects
					(font
						(size 1.27 1.27)
					)
					(hide yes)
				)
			)
			(symbol "GND_22_0_1"
				(polyline
					(pts
						(xy 0 0) (xy 0 -1.27) (xy 1.27 -1.27) (xy 0 -2.54) (xy -1.27 -1.27) (xy 0 -1.27)
					)
					(stroke
						(width 0)
						(type default)
					)
					(fill
						(type none)
					)
				)
			)
			(symbol "GND_22_1_1"
				(pin power_in line
					(at 0 0 270)
					(length 0)
					(hide yes)
					(name "GND"
						(effects
							(font
								(size 1.27 1.27)
							)
						)
					)
					(number "1"
						(effects
							(font
								(size 1.27 1.27)
							)
						)
					)
				)
			)
		)
	(symbol "sodimm-ddr5-tester:GND_23"
			(power)
			(pin_names
				(offset 0)
			)
			(exclude_from_sim no)
			(in_bom yes)
			(on_board yes)
			(property "Reference" "#PWR"
				(at 0 -6.35 0)
				(effects
					(font
						(size 1.27 1.27)
					)
					(hide yes)
				)
			)
			(property "Value" "GND_23"
				(at 0 -3.81 0)
				(effects
					(font
						(size 1.27 1.27)
					)
				)
			)
			(property "Footprint" ""
				(at 0 0 0)
				(effects
					(font
						(size 1.27 1.27)
					)
					(hide yes)
				)
			)
			(property "Datasheet" ""
				(at 0 0 0)
				(effects
					(font
						(size 1.27 1.27)
					)
					(hide yes)
				)
			)
			(property "Description" ""
				(at 0 0 0)
				(effects
					(font
						(size 1.27 1.27)
					)
					(hide yes)
				)
			)
			(symbol "GND_23_0_1"
				(polyline
					(pts
						(xy 0 0) (xy 0 -1.27) (xy 1.27 -1.27) (xy 0 -2.54) (xy -1.27 -1.27) (xy 0 -1.27)
					)
					(stroke
						(width 0)
						(type default)
					)
					(fill
						(type none)
					)
				)
			)
			(symbol "GND_23_1_1"
				(pin power_in line
					(at 0 0 270)
					(length 0)
					(hide yes)
					(name "GND"
						(effects
							(font
								(size 1.27 1.27)
							)
						)
					)
					(number "1"
						(effects
							(font
								(size 1.27 1.27)
							)
						)
					)
				)
			)
		)
	(symbol "sodimm-ddr5-tester:GND_24"
			(power)
			(pin_names
				(offset 0)
			)
			(exclude_from_sim no)
			(in_bom yes)
			(on_board yes)
			(property "Reference" "#PWR"
				(at 0 -6.35 0)
				(effects
					(font
						(size 1.27 1.27)
					)
					(hide yes)
				)
			)
			(property "Value" "GND_24"
				(at 0 -3.81 0)
				(effects
					(font
						(size 1.27 1.27)
					)
				)
			)
			(property "Footprint" ""
				(at 0 0 0)
				(effects
					(font
						(size 1.27 1.27)
					)
					(hide yes)
				)
			)
			(property "Datasheet" ""
				(at 0 0 0)
				(effects
					(font
						(size 1.27 1.27)
					)
					(hide yes)
				)
			)
			(property "Description" ""
				(at 0 0 0)
				(effects
					(font
						(size 1.27 1.27)
					)
					(hide yes)
				)
			)
			(symbol "GND_24_0_1"
				(polyline
					(pts
						(xy 0 0) (xy 0 -1.27) (xy 1.27 -1.27) (xy 0 -2.54) (xy -1.27 -1.27) (xy 0 -1.27)
					)
					(stroke
						(width 0)
						(type default)
					)
					(fill
						(type none)
					)
				)
			)
			(symbol "GND_24_1_1"
				(pin power_in line
					(at 0 0 270)
					(length 0)
					(hide yes)
					(name "GND"
						(effects
							(font
								(size 1.27 1.27)
							)
						)
					)
					(number "1"
						(effects
							(font
								(size 1.27 1.27)
							)
						)
					)
				)
			)
		)
	(symbol "sodimm-ddr5-tester:GND_25"
			(power)
			(pin_names
				(offset 0)
			)
			(exclude_from_sim no)
			(in_bom yes)
			(on_board yes)
			(property "Reference" "#PWR"
				(at 0 -6.35 0)
				(effects
					(font
						(size 1.27 1.27)
					)
					(hide yes)
				)
			)
			(property "Value" "GND_25"
				(at 0 -3.81 0)
				(effects
					(font
						(size 1.27 1.27)
					)
				)
			)
			(property "Footprint" ""
				(at 0 0 0)
				(effects
					(font
						(size 1.27 1.27)
					)
					(hide yes)
				)
			)
			(property "Datasheet" ""
				(at 0 0 0)
				(effects
					(font
						(size 1.27 1.27)
					)
					(hide yes)
				)
			)
			(property "Description" ""
				(at 0 0 0)
				(effects
					(font
						(size 1.27 1.27)
					)
					(hide yes)
				)
			)
			(symbol "GND_25_0_1"
				(polyline
					(pts
						(xy 0 0) (xy 0 -1.27) (xy 1.27 -1.27) (xy 0 -2.54) (xy -1.27 -1.27) (xy 0 -1.27)
					)
					(stroke
						(width 0)
						(type default)
					)
					(fill
						(type none)
					)
				)
			)
			(symbol "GND_25_1_1"
				(pin power_in line
					(at 0 0 270)
					(length 0)
					(hide yes)
					(name "GND"
						(effects
							(font
								(size 1.27 1.27)
							)
						)
					)
					(number "1"
						(effects
							(font
								(size 1.27 1.27)
							)
						)
					)
				)
			)
		)
	(symbol "sodimm-ddr5-tester:GND_26"
			(power)
			(pin_names
				(offset 0)
			)
			(exclude_from_sim no)
			(in_bom yes)
			(on_board yes)
			(property "Reference" "#PWR"
				(at 0 -6.35 0)
				(effects
					(font
						(size 1.27 1.27)
					)
					(hide yes)
				)
			)
			(property "Value" "GND_26"
				(at 0 -3.81 0)
				(effects
					(font
						(size 1.27 1.27)
					)
				)
			)
			(property "Footprint" ""
				(at 0 0 0)
				(effects
					(font
						(size 1.27 1.27)
					)
					(hide yes)
				)
			)
			(property "Datasheet" ""
				(at 0 0 0)
				(effects
					(font
						(size 1.27 1.27)
					)
					(hide yes)
				)
			)
			(property "Description" ""
				(at 0 0 0)
				(effects
					(font
						(size 1.27 1.27)
					)
					(hide yes)
				)
			)
			(symbol "GND_26_0_1"
				(polyline
					(pts
						(xy 0 0) (xy 0 -1.27) (xy 1.27 -1.27) (xy 0 -2.54) (xy -1.27 -1.27) (xy 0 -1.27)
					)
					(stroke
						(width 0)
						(type default)
					)
					(fill
						(type none)
					)
				)
			)
			(symbol "GND_26_1_1"
				(pin power_in line
					(at 0 0 270)
					(length 0)
					(hide yes)
					(name "GND"
						(effects
							(font
								(size 1.27 1.27)
							)
						)
					)
					(number "1"
						(effects
							(font
								(size 1.27 1.27)
							)
						)
					)
				)
			)
		)
	(symbol "sodimm-ddr5-tester:GND_27"
			(power)
			(pin_names
				(offset 0)
			)
			(exclude_from_sim no)
			(in_bom yes)
			(on_board yes)
			(property "Reference" "#PWR"
				(at 0 -6.35 0)
				(effects
					(font
						(size 1.27 1.27)
					)
					(hide yes)
				)
			)
			(property "Value" "GND_27"
				(at 0 -3.81 0)
				(effects
					(font
						(size 1.27 1.27)
					)
				)
			)
			(property "Footprint" ""
				(at 0 0 0)
				(effects
					(font
						(size 1.27 1.27)
					)
					(hide yes)
				)
			)
			(property "Datasheet" ""
				(at 0 0 0)
				(effects
					(font
						(size 1.27 1.27)
					)
					(hide yes)
				)
			)
			(property "Description" ""
				(at 0 0 0)
				(effects
					(font
						(size 1.27 1.27)
					)
					(hide yes)
				)
			)
			(symbol "GND_27_0_1"
				(polyline
					(pts
						(xy 0 0) (xy 0 -1.27) (xy 1.27 -1.27) (xy 0 -2.54) (xy -1.27 -1.27) (xy 0 -1.27)
					)
					(stroke
						(width 0)
						(type default)
					)
					(fill
						(type none)
					)
				)
			)
			(symbol "GND_27_1_1"
				(pin power_in line
					(at 0 0 270)
					(length 0)
					(hide yes)
					(name "GND"
						(effects
							(font
								(size 1.27 1.27)
							)
						)
					)
					(number "1"
						(effects
							(font
								(size 1.27 1.27)
							)
						)
					)
				)
			)
		)
	(symbol "sodimm-ddr5-tester:GND_28"
			(power)
			(pin_names
				(offset 0)
			)
			(exclude_from_sim no)
			(in_bom yes)
			(on_board yes)
			(property "Reference" "#PWR"
				(at 0 -6.35 0)
				(effects
					(font
						(size 1.27 1.27)
					)
					(hide yes)
				)
			)
			(property "Value" "GND_28"
				(at 0 -3.81 0)
				(effects
					(font
						(size 1.27 1.27)
					)
				)
			)
			(property "Footprint" ""
				(at 0 0 0)
				(effects
					(font
						(size 1.27 1.27)
					)
					(hide yes)
				)
			)
			(property "Datasheet" ""
				(at 0 0 0)
				(effects
					(font
						(size 1.27 1.27)
					)
					(hide yes)
				)
			)
			(property "Description" ""
				(at 0 0 0)
				(effects
					(font
						(size 1.27 1.27)
					)
					(hide yes)
				)
			)
			(symbol "GND_28_0_1"
				(polyline
					(pts
						(xy 0 0) (xy 0 -1.27) (xy 1.27 -1.27) (xy 0 -2.54) (xy -1.27 -1.27) (xy 0 -1.27)
					)
					(stroke
						(width 0)
						(type default)
					)
					(fill
						(type none)
					)
				)
			)
			(symbol "GND_28_1_1"
				(pin power_in line
					(at 0 0 270)
					(length 0)
					(hide yes)
					(name "GND"
						(effects
							(font
								(size 1.27 1.27)
							)
						)
					)
					(number "1"
						(effects
							(font
								(size 1.27 1.27)
							)
						)
					)
				)
			)
		)
	(symbol "sodimm-ddr5-tester:GND_29"
			(power)
			(pin_names
				(offset 0)
			)
			(exclude_from_sim no)
			(in_bom yes)
			(on_board yes)
			(property "Reference" "#PWR"
				(at 0 -6.35 0)
				(effects
					(font
						(size 1.27 1.27)
					)
					(hide yes)
				)
			)
			(property "Value" "GND_29"
				(at 0 -3.81 0)
				(effects
					(font
						(size 1.27 1.27)
					)
				)
			)
			(property "Footprint" ""
				(at 0 0 0)
				(effects
					(font
						(size 1.27 1.27)
					)
					(hide yes)
				)
			)
			(property "Datasheet" ""
				(at 0 0 0)
				(effects
					(font
						(size 1.27 1.27)
					)
					(hide yes)
				)
			)
			(property "Description" ""
				(at 0 0 0)
				(effects
					(font
						(size 1.27 1.27)
					)
					(hide yes)
				)
			)
			(symbol "GND_29_0_1"
				(polyline
					(pts
						(xy 0 0) (xy 0 -1.27) (xy 1.27 -1.27) (xy 0 -2.54) (xy -1.27 -1.27) (xy 0 -1.27)
					)
					(stroke
						(width 0)
						(type default)
					)
					(fill
						(type none)
					)
				)
			)
			(symbol "GND_29_1_1"
				(pin power_in line
					(at 0 0 270)
					(length 0)
					(hide yes)
					(name "GND"
						(effects
							(font
								(size 1.27 1.27)
							)
						)
					)
					(number "1"
						(effects
							(font
								(size 1.27 1.27)
							)
						)
					)
				)
			)
		)
	(symbol "sodimm-ddr5-tester:GND_30"
			(power)
			(pin_names
				(offset 0)
			)
			(exclude_from_sim no)
			(in_bom yes)
			(on_board yes)
			(property "Reference" "#PWR"
				(at 0 -6.35 0)
				(effects
					(font
						(size 1.27 1.27)
					)
					(hide yes)
				)
			)
			(property "Value" "GND_30"
				(at 0 -3.81 0)
				(effects
					(font
						(size 1.27 1.27)
					)
				)
			)
			(property "Footprint" ""
				(at 0 0 0)
				(effects
					(font
						(size 1.27 1.27)
					)
					(hide yes)
				)
			)
			(property "Datasheet" ""
				(at 0 0 0)
				(effects
					(font
						(size 1.27 1.27)
					)
					(hide yes)
				)
			)
			(property "Description" ""
				(at 0 0 0)
				(effects
					(font
						(size 1.27 1.27)
					)
					(hide yes)
				)
			)
			(symbol "GND_30_0_1"
				(polyline
					(pts
						(xy 0 0) (xy 0 -1.27) (xy 1.27 -1.27) (xy 0 -2.54) (xy -1.27 -1.27) (xy 0 -1.27)
					)
					(stroke
						(width 0)
						(type default)
					)
					(fill
						(type none)
					)
				)
			)
			(symbol "GND_30_1_1"
				(pin power_in line
					(at 0 0 270)
					(length 0)
					(hide yes)
					(name "GND"
						(effects
							(font
								(size 1.27 1.27)
							)
						)
					)
					(number "1"
						(effects
							(font
								(size 1.27 1.27)
							)
						)
					)
				)
			)
		)
	(symbol "sodimm-ddr5-tester:GND_31"
			(power)
			(pin_names
				(offset 0)
			)
			(exclude_from_sim no)
			(in_bom yes)
			(on_board yes)
			(property "Reference" "#PWR"
				(at 0 -6.35 0)
				(effects
					(font
						(size 1.27 1.27)
					)
					(hide yes)
				)
			)
			(property "Value" "GND_31"
				(at 0 -3.81 0)
				(effects
					(font
						(size 1.27 1.27)
					)
				)
			)
			(property "Footprint" ""
				(at 0 0 0)
				(effects
					(font
						(size 1.27 1.27)
					)
					(hide yes)
				)
			)
			(property "Datasheet" ""
				(at 0 0 0)
				(effects
					(font
						(size 1.27 1.27)
					)
					(hide yes)
				)
			)
			(property "Description" ""
				(at 0 0 0)
				(effects
					(font
						(size 1.27 1.27)
					)
					(hide yes)
				)
			)
			(symbol "GND_31_0_1"
				(polyline
					(pts
						(xy 0 0) (xy 0 -1.27) (xy 1.27 -1.27) (xy 0 -2.54) (xy -1.27 -1.27) (xy 0 -1.27)
					)
					(stroke
						(width 0)
						(type default)
					)
					(fill
						(type none)
					)
				)
			)
			(symbol "GND_31_1_1"
				(pin power_in line
					(at 0 0 270)
					(length 0)
					(hide yes)
					(name "GND"
						(effects
							(font
								(size 1.27 1.27)
							)
						)
					)
					(number "1"
						(effects
							(font
								(size 1.27 1.27)
							)
						)
					)
				)
			)
		)
	(symbol "sodimm-ddr5-tester:GND_32"
			(power)
			(pin_names
				(offset 0)
			)
			(exclude_from_sim no)
			(in_bom yes)
			(on_board yes)
			(property "Reference" "#PWR"
				(at 0 -6.35 0)
				(effects
					(font
						(size 1.27 1.27)
					)
					(hide yes)
				)
			)
			(property "Value" "GND_32"
				(at 0 -3.81 0)
				(effects
					(font
						(size 1.27 1.27)
					)
				)
			)
			(property "Footprint" ""
				(at 0 0 0)
				(effects
					(font
						(size 1.27 1.27)
					)
					(hide yes)
				)
			)
			(property "Datasheet" ""
				(at 0 0 0)
				(effects
					(font
						(size 1.27 1.27)
					)
					(hide yes)
				)
			)
			(property "Description" ""
				(at 0 0 0)
				(effects
					(font
						(size 1.27 1.27)
					)
					(hide yes)
				)
			)
			(symbol "GND_32_0_1"
				(polyline
					(pts
						(xy 0 0) (xy 0 -1.27) (xy 1.27 -1.27) (xy 0 -2.54) (xy -1.27 -1.27) (xy 0 -1.27)
					)
					(stroke
						(width 0)
						(type default)
					)
					(fill
						(type none)
					)
				)
			)
			(symbol "GND_32_1_1"
				(pin power_in line
					(at 0 0 270)
					(length 0)
					(hide yes)
					(name "GND"
						(effects
							(font
								(size 1.27 1.27)
							)
						)
					)
					(number "1"
						(effects
							(font
								(size 1.27 1.27)
							)
						)
					)
				)
			)
		)
	(symbol "sodimm-ddr5-tester:GND_33"
			(power)
			(pin_names
				(offset 0)
			)
			(exclude_from_sim no)
			(in_bom yes)
			(on_board yes)
			(property "Reference" "#PWR"
				(at 0 -6.35 0)
				(effects
					(font
						(size 1.27 1.27)
					)
					(hide yes)
				)
			)
			(property "Value" "GND_33"
				(at 0 -3.81 0)
				(effects
					(font
						(size 1.27 1.27)
					)
				)
			)
			(property "Footprint" ""
				(at 0 0 0)
				(effects
					(font
						(size 1.27 1.27)
					)
					(hide yes)
				)
			)
			(property "Datasheet" ""
				(at 0 0 0)
				(effects
					(font
						(size 1.27 1.27)
					)
					(hide yes)
				)
			)
			(property "Description" ""
				(at 0 0 0)
				(effects
					(font
						(size 1.27 1.27)
					)
					(hide yes)
				)
			)
			(symbol "GND_33_0_1"
				(polyline
					(pts
						(xy 0 0) (xy 0 -1.27) (xy 1.27 -1.27) (xy 0 -2.54) (xy -1.27 -1.27) (xy 0 -1.27)
					)
					(stroke
						(width 0)
						(type default)
					)
					(fill
						(type none)
					)
				)
			)
			(symbol "GND_33_1_1"
				(pin power_in line
					(at 0 0 270)
					(length 0)
					(hide yes)
					(name "GND"
						(effects
							(font
								(size 1.27 1.27)
							)
						)
					)
					(number "1"
						(effects
							(font
								(size 1.27 1.27)
							)
						)
					)
				)
			)
		)
	(symbol "sodimm-ddr5-tester:GND_34"
			(power)
			(pin_names
				(offset 0)
			)
			(exclude_from_sim no)
			(in_bom yes)
			(on_board yes)
			(property "Reference" "#PWR"
				(at 0 -6.35 0)
				(effects
					(font
						(size 1.27 1.27)
					)
					(hide yes)
				)
			)
			(property "Value" "GND_34"
				(at 0 -3.81 0)
				(effects
					(font
						(size 1.27 1.27)
					)
				)
			)
			(property "Footprint" ""
				(at 0 0 0)
				(effects
					(font
						(size 1.27 1.27)
					)
					(hide yes)
				)
			)
			(property "Datasheet" ""
				(at 0 0 0)
				(effects
					(font
						(size 1.27 1.27)
					)
					(hide yes)
				)
			)
			(property "Description" ""
				(at 0 0 0)
				(effects
					(font
						(size 1.27 1.27)
					)
					(hide yes)
				)
			)
			(symbol "GND_34_0_1"
				(polyline
					(pts
						(xy 0 0) (xy 0 -1.27) (xy 1.27 -1.27) (xy 0 -2.54) (xy -1.27 -1.27) (xy 0 -1.27)
					)
					(stroke
						(width 0)
						(type default)
					)
					(fill
						(type none)
					)
				)
			)
			(symbol "GND_34_1_1"
				(pin power_in line
					(at 0 0 270)
					(length 0)
					(hide yes)
					(name "GND"
						(effects
							(font
								(size 1.27 1.27)
							)
						)
					)
					(number "1"
						(effects
							(font
								(size 1.27 1.27)
							)
						)
					)
				)
			)
		)
	(symbol "sodimm-ddr5-tester:GND_36"
			(power)
			(pin_names
				(offset 0)
			)
			(exclude_from_sim no)
			(in_bom yes)
			(on_board yes)
			(property "Reference" "#PWR"
				(at 0 -6.35 0)
				(effects
					(font
						(size 1.27 1.27)
					)
					(hide yes)
				)
			)
			(property "Value" "GND_36"
				(at 0 -3.81 0)
				(effects
					(font
						(size 1.27 1.27)
					)
				)
			)
			(property "Footprint" ""
				(at 0 0 0)
				(effects
					(font
						(size 1.27 1.27)
					)
					(hide yes)
				)
			)
			(property "Datasheet" ""
				(at 0 0 0)
				(effects
					(font
						(size 1.27 1.27)
					)
					(hide yes)
				)
			)
			(property "Description" ""
				(at 0 0 0)
				(effects
					(font
						(size 1.27 1.27)
					)
					(hide yes)
				)
			)
			(symbol "GND_36_0_1"
				(polyline
					(pts
						(xy 0 0) (xy 0 -1.27) (xy 1.27 -1.27) (xy 0 -2.54) (xy -1.27 -1.27) (xy 0 -1.27)
					)
					(stroke
						(width 0)
						(type default)
					)
					(fill
						(type none)
					)
				)
			)
			(symbol "GND_36_1_1"
				(pin power_in line
					(at 0 0 270)
					(length 0)
					(hide yes)
					(name "GND"
						(effects
							(font
								(size 1.27 1.27)
							)
						)
					)
					(number "1"
						(effects
							(font
								(size 1.27 1.27)
							)
						)
					)
				)
			)
		)
	(symbol "sodimm-ddr5-tester:GND_37"
			(power)
			(pin_names
				(offset 0)
			)
			(exclude_from_sim no)
			(in_bom yes)
			(on_board yes)
			(property "Reference" "#PWR"
				(at 0 -6.35 0)
				(effects
					(font
						(size 1.27 1.27)
					)
					(hide yes)
				)
			)
			(property "Value" "GND_37"
				(at 0 -3.81 0)
				(effects
					(font
						(size 1.27 1.27)
					)
				)
			)
			(property "Footprint" ""
				(at 0 0 0)
				(effects
					(font
						(size 1.27 1.27)
					)
					(hide yes)
				)
			)
			(property "Datasheet" ""
				(at 0 0 0)
				(effects
					(font
						(size 1.27 1.27)
					)
					(hide yes)
				)
			)
			(property "Description" ""
				(at 0 0 0)
				(effects
					(font
						(size 1.27 1.27)
					)
					(hide yes)
				)
			)
			(symbol "GND_37_0_1"
				(polyline
					(pts
						(xy 0 0) (xy 0 -1.27) (xy 1.27 -1.27) (xy 0 -2.54) (xy -1.27 -1.27) (xy 0 -1.27)
					)
					(stroke
						(width 0)
						(type default)
					)
					(fill
						(type none)
					)
				)
			)
			(symbol "GND_37_1_1"
				(pin power_in line
					(at 0 0 270)
					(length 0)
					(hide yes)
					(name "GND"
						(effects
							(font
								(size 1.27 1.27)
							)
						)
					)
					(number "1"
						(effects
							(font
								(size 1.27 1.27)
							)
						)
					)
				)
			)
		)
	(symbol "sodimm-ddr5-tester:GND_38"
			(power)
			(pin_names
				(offset 0)
			)
			(exclude_from_sim no)
			(in_bom yes)
			(on_board yes)
			(property "Reference" "#PWR"
				(at 0 -6.35 0)
				(effects
					(font
						(size 1.27 1.27)
					)
					(hide yes)
				)
			)
			(property "Value" "GND_38"
				(at 0 -3.81 0)
				(effects
					(font
						(size 1.27 1.27)
					)
				)
			)
			(property "Footprint" ""
				(at 0 0 0)
				(effects
					(font
						(size 1.27 1.27)
					)
					(hide yes)
				)
			)
			(property "Datasheet" ""
				(at 0 0 0)
				(effects
					(font
						(size 1.27 1.27)
					)
					(hide yes)
				)
			)
			(property "Description" ""
				(at 0 0 0)
				(effects
					(font
						(size 1.27 1.27)
					)
					(hide yes)
				)
			)
			(symbol "GND_38_0_1"
				(polyline
					(pts
						(xy 0 0) (xy 0 -1.27) (xy 1.27 -1.27) (xy 0 -2.54) (xy -1.27 -1.27) (xy 0 -1.27)
					)
					(stroke
						(width 0)
						(type default)
					)
					(fill
						(type none)
					)
				)
			)
			(symbol "GND_38_1_1"
				(pin power_in line
					(at 0 0 270)
					(length 0)
					(hide yes)
					(name "GND"
						(effects
							(font
								(size 1.27 1.27)
							)
						)
					)
					(number "1"
						(effects
							(font
								(size 1.27 1.27)
							)
						)
					)
				)
			)
		)
	(symbol "sodimm-ddr5-tester:GND_39"
			(power)
			(pin_names
				(offset 0)
			)
			(exclude_from_sim no)
			(in_bom yes)
			(on_board yes)
			(property "Reference" "#PWR"
				(at 0 -6.35 0)
				(effects
					(font
						(size 1.27 1.27)
					)
					(hide yes)
				)
			)
			(property "Value" "GND_39"
				(at 0 -3.81 0)
				(effects
					(font
						(size 1.27 1.27)
					)
				)
			)
			(property "Footprint" ""
				(at 0 0 0)
				(effects
					(font
						(size 1.27 1.27)
					)
					(hide yes)
				)
			)
			(property "Datasheet" ""
				(at 0 0 0)
				(effects
					(font
						(size 1.27 1.27)
					)
					(hide yes)
				)
			)
			(property "Description" ""
				(at 0 0 0)
				(effects
					(font
						(size 1.27 1.27)
					)
					(hide yes)
				)
			)
			(symbol "GND_39_0_1"
				(polyline
					(pts
						(xy 0 0) (xy 0 -1.27) (xy 1.27 -1.27) (xy 0 -2.54) (xy -1.27 -1.27) (xy 0 -1.27)
					)
					(stroke
						(width 0)
						(type default)
					)
					(fill
						(type none)
					)
				)
			)
			(symbol "GND_39_1_1"
				(pin power_in line
					(at 0 0 270)
					(length 0)
					(hide yes)
					(name "GND"
						(effects
							(font
								(size 1.27 1.27)
							)
						)
					)
					(number "1"
						(effects
							(font
								(size 1.27 1.27)
							)
						)
					)
				)
			)
		)
	(symbol "sodimm-ddr5-tester:GND_40"
			(power)
			(pin_names
				(offset 0)
			)
			(exclude_from_sim no)
			(in_bom yes)
			(on_board yes)
			(property "Reference" "#PWR"
				(at 0 -6.35 0)
				(effects
					(font
						(size 1.27 1.27)
					)
					(hide yes)
				)
			)
			(property "Value" "GND_40"
				(at 0 -3.81 0)
				(effects
					(font
						(size 1.27 1.27)
					)
				)
			)
			(property "Footprint" ""
				(at 0 0 0)
				(effects
					(font
						(size 1.27 1.27)
					)
					(hide yes)
				)
			)
			(property "Datasheet" ""
				(at 0 0 0)
				(effects
					(font
						(size 1.27 1.27)
					)
					(hide yes)
				)
			)
			(property "Description" ""
				(at 0 0 0)
				(effects
					(font
						(size 1.27 1.27)
					)
					(hide yes)
				)
			)
			(symbol "GND_40_0_1"
				(polyline
					(pts
						(xy 0 0) (xy 0 -1.27) (xy 1.27 -1.27) (xy 0 -2.54) (xy -1.27 -1.27) (xy 0 -1.27)
					)
					(stroke
						(width 0)
						(type default)
					)
					(fill
						(type none)
					)
				)
			)
			(symbol "GND_40_1_1"
				(pin power_in line
					(at 0 0 270)
					(length 0)
					(hide yes)
					(name "GND"
						(effects
							(font
								(size 1.27 1.27)
							)
						)
					)
					(number "1"
						(effects
							(font
								(size 1.27 1.27)
							)
						)
					)
				)
			)
		)
	(symbol "sodimm-ddr5-tester:GND_41"
			(power)
			(pin_names
				(offset 0)
			)
			(exclude_from_sim no)
			(in_bom yes)
			(on_board yes)
			(property "Reference" "#PWR"
				(at 0 -6.35 0)
				(effects
					(font
						(size 1.27 1.27)
					)
					(hide yes)
				)
			)
			(property "Value" "GND_41"
				(at 0 -3.81 0)
				(effects
					(font
						(size 1.27 1.27)
					)
				)
			)
			(property "Footprint" ""
				(at 0 0 0)
				(effects
					(font
						(size 1.27 1.27)
					)
					(hide yes)
				)
			)
			(property "Datasheet" ""
				(at 0 0 0)
				(effects
					(font
						(size 1.27 1.27)
					)
					(hide yes)
				)
			)
			(property "Description" ""
				(at 0 0 0)
				(effects
					(font
						(size 1.27 1.27)
					)
					(hide yes)
				)
			)
			(symbol "GND_41_0_1"
				(polyline
					(pts
						(xy 0 0) (xy 0 -1.27) (xy 1.27 -1.27) (xy 0 -2.54) (xy -1.27 -1.27) (xy 0 -1.27)
					)
					(stroke
						(width 0)
						(type default)
					)
					(fill
						(type none)
					)
				)
			)
			(symbol "GND_41_1_1"
				(pin power_in line
					(at 0 0 270)
					(length 0)
					(hide yes)
					(name "GND"
						(effects
							(font
								(size 1.27 1.27)
							)
						)
					)
					(number "1"
						(effects
							(font
								(size 1.27 1.27)
							)
						)
					)
				)
			)
		)
	(symbol "sodimm-ddr5-tester:GND_42"
			(power)
			(pin_names
				(offset 0)
			)
			(exclude_from_sim no)
			(in_bom yes)
			(on_board yes)
			(property "Reference" "#PWR"
				(at 0 -6.35 0)
				(effects
					(font
						(size 1.27 1.27)
					)
					(hide yes)
				)
			)
			(property "Value" "GND_42"
				(at 0 -3.81 0)
				(effects
					(font
						(size 1.27 1.27)
					)
				)
			)
			(property "Footprint" ""
				(at 0 0 0)
				(effects
					(font
						(size 1.27 1.27)
					)
					(hide yes)
				)
			)
			(property "Datasheet" ""
				(at 0 0 0)
				(effects
					(font
						(size 1.27 1.27)
					)
					(hide yes)
				)
			)
			(property "Description" ""
				(at 0 0 0)
				(effects
					(font
						(size 1.27 1.27)
					)
					(hide yes)
				)
			)
			(symbol "GND_42_0_1"
				(polyline
					(pts
						(xy 0 0) (xy 0 -1.27) (xy 1.27 -1.27) (xy 0 -2.54) (xy -1.27 -1.27) (xy 0 -1.27)
					)
					(stroke
						(width 0)
						(type default)
					)
					(fill
						(type none)
					)
				)
			)
			(symbol "GND_42_1_1"
				(pin power_in line
					(at 0 0 270)
					(length 0)
					(hide yes)
					(name "GND"
						(effects
							(font
								(size 1.27 1.27)
							)
						)
					)
					(number "1"
						(effects
							(font
								(size 1.27 1.27)
							)
						)
					)
				)
			)
		)
	(symbol "sodimm-ddr5-tester:GND_43"
			(power)
			(pin_names
				(offset 0)
			)
			(exclude_from_sim no)
			(in_bom yes)
			(on_board yes)
			(property "Reference" "#PWR"
				(at 0 -6.35 0)
				(effects
					(font
						(size 1.27 1.27)
					)
					(hide yes)
				)
			)
			(property "Value" "GND_43"
				(at 0 -3.81 0)
				(effects
					(font
						(size 1.27 1.27)
					)
				)
			)
			(property "Footprint" ""
				(at 0 0 0)
				(effects
					(font
						(size 1.27 1.27)
					)
					(hide yes)
				)
			)
			(property "Datasheet" ""
				(at 0 0 0)
				(effects
					(font
						(size 1.27 1.27)
					)
					(hide yes)
				)
			)
			(property "Description" ""
				(at 0 0 0)
				(effects
					(font
						(size 1.27 1.27)
					)
					(hide yes)
				)
			)
			(symbol "GND_43_0_1"
				(polyline
					(pts
						(xy 0 0) (xy 0 -1.27) (xy 1.27 -1.27) (xy 0 -2.54) (xy -1.27 -1.27) (xy 0 -1.27)
					)
					(stroke
						(width 0)
						(type default)
					)
					(fill
						(type none)
					)
				)
			)
			(symbol "GND_43_1_1"
				(pin power_in line
					(at 0 0 270)
					(length 0)
					(hide yes)
					(name "GND"
						(effects
							(font
								(size 1.27 1.27)
							)
						)
					)
					(number "1"
						(effects
							(font
								(size 1.27 1.27)
							)
						)
					)
				)
			)
		)
	(symbol "sodimm-ddr5-tester:GND_44"
			(power)
			(pin_names
				(offset 0)
			)
			(exclude_from_sim no)
			(in_bom yes)
			(on_board yes)
			(property "Reference" "#PWR"
				(at 0 -6.35 0)
				(effects
					(font
						(size 1.27 1.27)
					)
					(hide yes)
				)
			)
			(property "Value" "GND_44"
				(at 0 -3.81 0)
				(effects
					(font
						(size 1.27 1.27)
					)
				)
			)
			(property "Footprint" ""
				(at 0 0 0)
				(effects
					(font
						(size 1.27 1.27)
					)
					(hide yes)
				)
			)
			(property "Datasheet" ""
				(at 0 0 0)
				(effects
					(font
						(size 1.27 1.27)
					)
					(hide yes)
				)
			)
			(property "Description" ""
				(at 0 0 0)
				(effects
					(font
						(size 1.27 1.27)
					)
					(hide yes)
				)
			)
			(symbol "GND_44_0_1"
				(polyline
					(pts
						(xy 0 0) (xy 0 -1.27) (xy 1.27 -1.27) (xy 0 -2.54) (xy -1.27 -1.27) (xy 0 -1.27)
					)
					(stroke
						(width 0)
						(type default)
					)
					(fill
						(type none)
					)
				)
			)
			(symbol "GND_44_1_1"
				(pin power_in line
					(at 0 0 270)
					(length 0)
					(hide yes)
					(name "GND"
						(effects
							(font
								(size 1.27 1.27)
							)
						)
					)
					(number "1"
						(effects
							(font
								(size 1.27 1.27)
							)
						)
					)
				)
			)
		)
	(symbol "sodimm-ddr5-tester:GND_46"
			(power)
			(pin_names
				(offset 0)
			)
			(exclude_from_sim no)
			(in_bom yes)
			(on_board yes)
			(property "Reference" "#PWR"
				(at 0 -6.35 0)
				(effects
					(font
						(size 1.27 1.27)
					)
					(hide yes)
				)
			)
			(property "Value" "GND_46"
				(at 0 -3.81 0)
				(effects
					(font
						(size 1.27 1.27)
					)
				)
			)
			(property "Footprint" ""
				(at 0 0 0)
				(effects
					(font
						(size 1.27 1.27)
					)
					(hide yes)
				)
			)
			(property "Datasheet" ""
				(at 0 0 0)
				(effects
					(font
						(size 1.27 1.27)
					)
					(hide yes)
				)
			)
			(property "Description" ""
				(at 0 0 0)
				(effects
					(font
						(size 1.27 1.27)
					)
					(hide yes)
				)
			)
			(symbol "GND_46_0_1"
				(polyline
					(pts
						(xy 0 0) (xy 0 -1.27) (xy 1.27 -1.27) (xy 0 -2.54) (xy -1.27 -1.27) (xy 0 -1.27)
					)
					(stroke
						(width 0)
						(type default)
					)
					(fill
						(type none)
					)
				)
			)
			(symbol "GND_46_1_1"
				(pin power_in line
					(at 0 0 270)
					(length 0)
					(hide yes)
					(name "GND"
						(effects
							(font
								(size 1.27 1.27)
							)
						)
					)
					(number "1"
						(effects
							(font
								(size 1.27 1.27)
							)
						)
					)
				)
			)
		)
	(symbol "sodimm-ddr5-tester:GND_47"
			(power)
			(pin_names
				(offset 0)
			)
			(exclude_from_sim no)
			(in_bom yes)
			(on_board yes)
			(property "Reference" "#PWR"
				(at 0 -6.35 0)
				(effects
					(font
						(size 1.27 1.27)
					)
					(hide yes)
				)
			)
			(property "Value" "GND_47"
				(at 0 -3.81 0)
				(effects
					(font
						(size 1.27 1.27)
					)
				)
			)
			(property "Footprint" ""
				(at 0 0 0)
				(effects
					(font
						(size 1.27 1.27)
					)
					(hide yes)
				)
			)
			(property "Datasheet" ""
				(at 0 0 0)
				(effects
					(font
						(size 1.27 1.27)
					)
					(hide yes)
				)
			)
			(property "Description" ""
				(at 0 0 0)
				(effects
					(font
						(size 1.27 1.27)
					)
					(hide yes)
				)
			)
			(symbol "GND_47_0_1"
				(polyline
					(pts
						(xy 0 0) (xy 0 -1.27) (xy 1.27 -1.27) (xy 0 -2.54) (xy -1.27 -1.27) (xy 0 -1.27)
					)
					(stroke
						(width 0)
						(type default)
					)
					(fill
						(type none)
					)
				)
			)
			(symbol "GND_47_1_1"
				(pin power_in line
					(at 0 0 270)
					(length 0)
					(hide yes)
					(name "GND"
						(effects
							(font
								(size 1.27 1.27)
							)
						)
					)
					(number "1"
						(effects
							(font
								(size 1.27 1.27)
							)
						)
					)
				)
			)
		)
	(symbol "sodimm-ddr5-tester:GND_48"
			(power)
			(pin_names
				(offset 0)
			)
			(exclude_from_sim no)
			(in_bom yes)
			(on_board yes)
			(property "Reference" "#PWR"
				(at 0 -6.35 0)
				(effects
					(font
						(size 1.27 1.27)
					)
					(hide yes)
				)
			)
			(property "Value" "GND_48"
				(at 0 -3.81 0)
				(effects
					(font
						(size 1.27 1.27)
					)
				)
			)
			(property "Footprint" ""
				(at 0 0 0)
				(effects
					(font
						(size 1.27 1.27)
					)
					(hide yes)
				)
			)
			(property "Datasheet" ""
				(at 0 0 0)
				(effects
					(font
						(size 1.27 1.27)
					)
					(hide yes)
				)
			)
			(property "Description" ""
				(at 0 0 0)
				(effects
					(font
						(size 1.27 1.27)
					)
					(hide yes)
				)
			)
			(symbol "GND_48_0_1"
				(polyline
					(pts
						(xy 0 0) (xy 0 -1.27) (xy 1.27 -1.27) (xy 0 -2.54) (xy -1.27 -1.27) (xy 0 -1.27)
					)
					(stroke
						(width 0)
						(type default)
					)
					(fill
						(type none)
					)
				)
			)
			(symbol "GND_48_1_1"
				(pin power_in line
					(at 0 0 270)
					(length 0)
					(hide yes)
					(name "GND"
						(effects
							(font
								(size 1.27 1.27)
							)
						)
					)
					(number "1"
						(effects
							(font
								(size 1.27 1.27)
							)
						)
					)
				)
			)
		)
	(symbol "sodimm-ddr5-tester:GND_49"
			(power)
			(pin_names
				(offset 0)
			)
			(exclude_from_sim no)
			(in_bom yes)
			(on_board yes)
			(property "Reference" "#PWR"
				(at 0 -6.35 0)
				(effects
					(font
						(size 1.27 1.27)
					)
					(hide yes)
				)
			)
			(property "Value" "GND_49"
				(at 0 -3.81 0)
				(effects
					(font
						(size 1.27 1.27)
					)
				)
			)
			(property "Footprint" ""
				(at 0 0 0)
				(effects
					(font
						(size 1.27 1.27)
					)
					(hide yes)
				)
			)
			(property "Datasheet" ""
				(at 0 0 0)
				(effects
					(font
						(size 1.27 1.27)
					)
					(hide yes)
				)
			)
			(property "Description" ""
				(at 0 0 0)
				(effects
					(font
						(size 1.27 1.27)
					)
					(hide yes)
				)
			)
			(symbol "GND_49_0_1"
				(polyline
					(pts
						(xy 0 0) (xy 0 -1.27) (xy 1.27 -1.27) (xy 0 -2.54) (xy -1.27 -1.27) (xy 0 -1.27)
					)
					(stroke
						(width 0)
						(type default)
					)
					(fill
						(type none)
					)
				)
			)
			(symbol "GND_49_1_1"
				(pin power_in line
					(at 0 0 270)
					(length 0)
					(hide yes)
					(name "GND"
						(effects
							(font
								(size 1.27 1.27)
							)
						)
					)
					(number "1"
						(effects
							(font
								(size 1.27 1.27)
							)
						)
					)
				)
			)
		)
	(symbol "sodimm-ddr5-tester:GND_50"
			(power)
			(pin_names
				(offset 0)
			)
			(exclude_from_sim no)
			(in_bom yes)
			(on_board yes)
			(property "Reference" "#PWR"
				(at 0 -6.35 0)
				(effects
					(font
						(size 1.27 1.27)
					)
					(hide yes)
				)
			)
			(property "Value" "GND_50"
				(at 0 -3.81 0)
				(effects
					(font
						(size 1.27 1.27)
					)
				)
			)
			(property "Footprint" ""
				(at 0 0 0)
				(effects
					(font
						(size 1.27 1.27)
					)
					(hide yes)
				)
			)
			(property "Datasheet" ""
				(at 0 0 0)
				(effects
					(font
						(size 1.27 1.27)
					)
					(hide yes)
				)
			)
			(property "Description" ""
				(at 0 0 0)
				(effects
					(font
						(size 1.27 1.27)
					)
					(hide yes)
				)
			)
			(symbol "GND_50_0_1"
				(polyline
					(pts
						(xy 0 0) (xy 0 -1.27) (xy 1.27 -1.27) (xy 0 -2.54) (xy -1.27 -1.27) (xy 0 -1.27)
					)
					(stroke
						(width 0)
						(type default)
					)
					(fill
						(type none)
					)
				)
			)
			(symbol "GND_50_1_1"
				(pin power_in line
					(at 0 0 270)
					(length 0)
					(hide yes)
					(name "GND"
						(effects
							(font
								(size 1.27 1.27)
							)
						)
					)
					(number "1"
						(effects
							(font
								(size 1.27 1.27)
							)
						)
					)
				)
			)
		)
	(symbol "sodimm-ddr5-tester:GND_51"
			(power)
			(pin_names
				(offset 0)
			)
			(exclude_from_sim no)
			(in_bom yes)
			(on_board yes)
			(property "Reference" "#PWR"
				(at 0 -6.35 0)
				(effects
					(font
						(size 1.27 1.27)
					)
					(hide yes)
				)
			)
			(property "Value" "GND_51"
				(at 0 -3.81 0)
				(effects
					(font
						(size 1.27 1.27)
					)
				)
			)
			(property "Footprint" ""
				(at 0 0 0)
				(effects
					(font
						(size 1.27 1.27)
					)
					(hide yes)
				)
			)
			(property "Datasheet" ""
				(at 0 0 0)
				(effects
					(font
						(size 1.27 1.27)
					)
					(hide yes)
				)
			)
			(property "Description" ""
				(at 0 0 0)
				(effects
					(font
						(size 1.27 1.27)
					)
					(hide yes)
				)
			)
			(symbol "GND_51_0_1"
				(polyline
					(pts
						(xy 0 0) (xy 0 -1.27) (xy 1.27 -1.27) (xy 0 -2.54) (xy -1.27 -1.27) (xy 0 -1.27)
					)
					(stroke
						(width 0)
						(type default)
					)
					(fill
						(type none)
					)
				)
			)
			(symbol "GND_51_1_1"
				(pin power_in line
					(at 0 0 270)
					(length 0)
					(hide yes)
					(name "GND"
						(effects
							(font
								(size 1.27 1.27)
							)
						)
					)
					(number "1"
						(effects
							(font
								(size 1.27 1.27)
							)
						)
					)
				)
			)
		)
	(symbol "sodimm-ddr5-tester:GND_52"
			(power)
			(pin_names
				(offset 0)
			)
			(exclude_from_sim no)
			(in_bom yes)
			(on_board yes)
			(property "Reference" "#PWR"
				(at 0 -6.35 0)
				(effects
					(font
						(size 1.27 1.27)
					)
					(hide yes)
				)
			)
			(property "Value" "GND_52"
				(at 0 -3.81 0)
				(effects
					(font
						(size 1.27 1.27)
					)
				)
			)
			(property "Footprint" ""
				(at 0 0 0)
				(effects
					(font
						(size 1.27 1.27)
					)
					(hide yes)
				)
			)
			(property "Datasheet" ""
				(at 0 0 0)
				(effects
					(font
						(size 1.27 1.27)
					)
					(hide yes)
				)
			)
			(property "Description" ""
				(at 0 0 0)
				(effects
					(font
						(size 1.27 1.27)
					)
					(hide yes)
				)
			)
			(symbol "GND_52_0_1"
				(polyline
					(pts
						(xy 0 0) (xy 0 -1.27) (xy 1.27 -1.27) (xy 0 -2.54) (xy -1.27 -1.27) (xy 0 -1.27)
					)
					(stroke
						(width 0)
						(type default)
					)
					(fill
						(type none)
					)
				)
			)
			(symbol "GND_52_1_1"
				(pin power_in line
					(at 0 0 270)
					(length 0)
					(hide yes)
					(name "GND"
						(effects
							(font
								(size 1.27 1.27)
							)
						)
					)
					(number "1"
						(effects
							(font
								(size 1.27 1.27)
							)
						)
					)
				)
			)
		)
	(symbol "sodimm-ddr5-tester:GND_53"
			(power)
			(pin_names
				(offset 0)
			)
			(exclude_from_sim no)
			(in_bom yes)
			(on_board yes)
			(property "Reference" "#PWR"
				(at 0 -6.35 0)
				(effects
					(font
						(size 1.27 1.27)
					)
					(hide yes)
				)
			)
			(property "Value" "GND_53"
				(at 0 -3.81 0)
				(effects
					(font
						(size 1.27 1.27)
					)
				)
			)
			(property "Footprint" ""
				(at 0 0 0)
				(effects
					(font
						(size 1.27 1.27)
					)
					(hide yes)
				)
			)
			(property "Datasheet" ""
				(at 0 0 0)
				(effects
					(font
						(size 1.27 1.27)
					)
					(hide yes)
				)
			)
			(property "Description" ""
				(at 0 0 0)
				(effects
					(font
						(size 1.27 1.27)
					)
					(hide yes)
				)
			)
			(symbol "GND_53_0_1"
				(polyline
					(pts
						(xy 0 0) (xy 0 -1.27) (xy 1.27 -1.27) (xy 0 -2.54) (xy -1.27 -1.27) (xy 0 -1.27)
					)
					(stroke
						(width 0)
						(type default)
					)
					(fill
						(type none)
					)
				)
			)
			(symbol "GND_53_1_1"
				(pin power_in line
					(at 0 0 270)
					(length 0)
					(hide yes)
					(name "GND"
						(effects
							(font
								(size 1.27 1.27)
							)
						)
					)
					(number "1"
						(effects
							(font
								(size 1.27 1.27)
							)
						)
					)
				)
			)
		)
	(symbol "sodimm-ddr5-tester:GND_54"
			(power)
			(pin_names
				(offset 0)
			)
			(exclude_from_sim no)
			(in_bom yes)
			(on_board yes)
			(property "Reference" "#PWR"
				(at 0 -6.35 0)
				(effects
					(font
						(size 1.27 1.27)
					)
					(hide yes)
				)
			)
			(property "Value" "GND_54"
				(at 0 -3.81 0)
				(effects
					(font
						(size 1.27 1.27)
					)
				)
			)
			(property "Footprint" ""
				(at 0 0 0)
				(effects
					(font
						(size 1.27 1.27)
					)
					(hide yes)
				)
			)
			(property "Datasheet" ""
				(at 0 0 0)
				(effects
					(font
						(size 1.27 1.27)
					)
					(hide yes)
				)
			)
			(property "Description" ""
				(at 0 0 0)
				(effects
					(font
						(size 1.27 1.27)
					)
					(hide yes)
				)
			)
			(symbol "GND_54_0_1"
				(polyline
					(pts
						(xy 0 0) (xy 0 -1.27) (xy 1.27 -1.27) (xy 0 -2.54) (xy -1.27 -1.27) (xy 0 -1.27)
					)
					(stroke
						(width 0)
						(type default)
					)
					(fill
						(type none)
					)
				)
			)
			(symbol "GND_54_1_1"
				(pin power_in line
					(at 0 0 270)
					(length 0)
					(hide yes)
					(name "GND"
						(effects
							(font
								(size 1.27 1.27)
							)
						)
					)
					(number "1"
						(effects
							(font
								(size 1.27 1.27)
							)
						)
					)
				)
			)
		)
	(symbol "sodimm-ddr5-tester:GND_55"
			(power)
			(pin_names
				(offset 0)
			)
			(exclude_from_sim no)
			(in_bom yes)
			(on_board yes)
			(property "Reference" "#PWR"
				(at 0 -6.35 0)
				(effects
					(font
						(size 1.27 1.27)
					)
					(hide yes)
				)
			)
			(property "Value" "GND_55"
				(at 0 -3.81 0)
				(effects
					(font
						(size 1.27 1.27)
					)
				)
			)
			(property "Footprint" ""
				(at 0 0 0)
				(effects
					(font
						(size 1.27 1.27)
					)
					(hide yes)
				)
			)
			(property "Datasheet" ""
				(at 0 0 0)
				(effects
					(font
						(size 1.27 1.27)
					)
					(hide yes)
				)
			)
			(property "Description" ""
				(at 0 0 0)
				(effects
					(font
						(size 1.27 1.27)
					)
					(hide yes)
				)
			)
			(symbol "GND_55_0_1"
				(polyline
					(pts
						(xy 0 0) (xy 0 -1.27) (xy 1.27 -1.27) (xy 0 -2.54) (xy -1.27 -1.27) (xy 0 -1.27)
					)
					(stroke
						(width 0)
						(type default)
					)
					(fill
						(type none)
					)
				)
			)
			(symbol "GND_55_1_1"
				(pin power_in line
					(at 0 0 270)
					(length 0)
					(hide yes)
					(name "GND"
						(effects
							(font
								(size 1.27 1.27)
							)
						)
					)
					(number "1"
						(effects
							(font
								(size 1.27 1.27)
							)
						)
					)
				)
			)
		)
	(symbol "sodimm-ddr5-tester:GND_56"
			(power)
			(pin_names
				(offset 0)
			)
			(exclude_from_sim no)
			(in_bom yes)
			(on_board yes)
			(property "Reference" "#PWR"
				(at 0 -6.35 0)
				(effects
					(font
						(size 1.27 1.27)
					)
					(hide yes)
				)
			)
			(property "Value" "GND_56"
				(at 0 -3.81 0)
				(effects
					(font
						(size 1.27 1.27)
					)
				)
			)
			(property "Footprint" ""
				(at 0 0 0)
				(effects
					(font
						(size 1.27 1.27)
					)
					(hide yes)
				)
			)
			(property "Datasheet" ""
				(at 0 0 0)
				(effects
					(font
						(size 1.27 1.27)
					)
					(hide yes)
				)
			)
			(property "Description" ""
				(at 0 0 0)
				(effects
					(font
						(size 1.27 1.27)
					)
					(hide yes)
				)
			)
			(symbol "GND_56_0_1"
				(polyline
					(pts
						(xy 0 0) (xy 0 -1.27) (xy 1.27 -1.27) (xy 0 -2.54) (xy -1.27 -1.27) (xy 0 -1.27)
					)
					(stroke
						(width 0)
						(type default)
					)
					(fill
						(type none)
					)
				)
			)
			(symbol "GND_56_1_1"
				(pin power_in line
					(at 0 0 270)
					(length 0)
					(hide yes)
					(name "GND"
						(effects
							(font
								(size 1.27 1.27)
							)
						)
					)
					(number "1"
						(effects
							(font
								(size 1.27 1.27)
							)
						)
					)
				)
			)
		)
	(symbol "sodimm-ddr5-tester:GND_57"
			(power)
			(pin_names
				(offset 0)
			)
			(exclude_from_sim no)
			(in_bom yes)
			(on_board yes)
			(property "Reference" "#PWR"
				(at 0 -6.35 0)
				(effects
					(font
						(size 1.27 1.27)
					)
					(hide yes)
				)
			)
			(property "Value" "GND_57"
				(at 0 -3.81 0)
				(effects
					(font
						(size 1.27 1.27)
					)
				)
			)
			(property "Footprint" ""
				(at 0 0 0)
				(effects
					(font
						(size 1.27 1.27)
					)
					(hide yes)
				)
			)
			(property "Datasheet" ""
				(at 0 0 0)
				(effects
					(font
						(size 1.27 1.27)
					)
					(hide yes)
				)
			)
			(property "Description" ""
				(at 0 0 0)
				(effects
					(font
						(size 1.27 1.27)
					)
					(hide yes)
				)
			)
			(symbol "GND_57_0_1"
				(polyline
					(pts
						(xy 0 0) (xy 0 -1.27) (xy 1.27 -1.27) (xy 0 -2.54) (xy -1.27 -1.27) (xy 0 -1.27)
					)
					(stroke
						(width 0)
						(type default)
					)
					(fill
						(type none)
					)
				)
			)
			(symbol "GND_57_1_1"
				(pin power_in line
					(at 0 0 270)
					(length 0)
					(hide yes)
					(name "GND"
						(effects
							(font
								(size 1.27 1.27)
							)
						)
					)
					(number "1"
						(effects
							(font
								(size 1.27 1.27)
							)
						)
					)
				)
			)
		)
	(symbol "sodimm-ddr5-tester:GND_58"
			(power)
			(pin_names
				(offset 0)
			)
			(exclude_from_sim no)
			(in_bom yes)
			(on_board yes)
			(property "Reference" "#PWR"
				(at 0 -6.35 0)
				(effects
					(font
						(size 1.27 1.27)
					)
					(hide yes)
				)
			)
			(property "Value" "GND_58"
				(at 0 -3.81 0)
				(effects
					(font
						(size 1.27 1.27)
					)
				)
			)
			(property "Footprint" ""
				(at 0 0 0)
				(effects
					(font
						(size 1.27 1.27)
					)
					(hide yes)
				)
			)
			(property "Datasheet" ""
				(at 0 0 0)
				(effects
					(font
						(size 1.27 1.27)
					)
					(hide yes)
				)
			)
			(property "Description" ""
				(at 0 0 0)
				(effects
					(font
						(size 1.27 1.27)
					)
					(hide yes)
				)
			)
			(symbol "GND_58_0_1"
				(polyline
					(pts
						(xy 0 0) (xy 0 -1.27) (xy 1.27 -1.27) (xy 0 -2.54) (xy -1.27 -1.27) (xy 0 -1.27)
					)
					(stroke
						(width 0)
						(type default)
					)
					(fill
						(type none)
					)
				)
			)
			(symbol "GND_58_1_1"
				(pin power_in line
					(at 0 0 270)
					(length 0)
					(hide yes)
					(name "GND"
						(effects
							(font
								(size 1.27 1.27)
							)
						)
					)
					(number "1"
						(effects
							(font
								(size 1.27 1.27)
							)
						)
					)
				)
			)
		)
	(symbol "sodimm-ddr5-tester:GND_59"
			(power)
			(pin_names
				(offset 0)
			)
			(exclude_from_sim no)
			(in_bom yes)
			(on_board yes)
			(property "Reference" "#PWR"
				(at 0 -6.35 0)
				(effects
					(font
						(size 1.27 1.27)
					)
					(hide yes)
				)
			)
			(property "Value" "GND_59"
				(at 0 -3.81 0)
				(effects
					(font
						(size 1.27 1.27)
					)
				)
			)
			(property "Footprint" ""
				(at 0 0 0)
				(effects
					(font
						(size 1.27 1.27)
					)
					(hide yes)
				)
			)
			(property "Datasheet" ""
				(at 0 0 0)
				(effects
					(font
						(size 1.27 1.27)
					)
					(hide yes)
				)
			)
			(property "Description" ""
				(at 0 0 0)
				(effects
					(font
						(size 1.27 1.27)
					)
					(hide yes)
				)
			)
			(symbol "GND_59_0_1"
				(polyline
					(pts
						(xy 0 0) (xy 0 -1.27) (xy 1.27 -1.27) (xy 0 -2.54) (xy -1.27 -1.27) (xy 0 -1.27)
					)
					(stroke
						(width 0)
						(type default)
					)
					(fill
						(type none)
					)
				)
			)
			(symbol "GND_59_1_1"
				(pin power_in line
					(at 0 0 270)
					(length 0)
					(hide yes)
					(name "GND"
						(effects
							(font
								(size 1.27 1.27)
							)
						)
					)
					(number "1"
						(effects
							(font
								(size 1.27 1.27)
							)
						)
					)
				)
			)
		)
	(symbol "sodimm-ddr5-tester:GND_60"
			(power)
			(pin_names
				(offset 0)
			)
			(exclude_from_sim no)
			(in_bom yes)
			(on_board yes)
			(property "Reference" "#PWR"
				(at 0 -6.35 0)
				(effects
					(font
						(size 1.27 1.27)
					)
					(hide yes)
				)
			)
			(property "Value" "GND_60"
				(at 0 -3.81 0)
				(effects
					(font
						(size 1.27 1.27)
					)
				)
			)
			(property "Footprint" ""
				(at 0 0 0)
				(effects
					(font
						(size 1.27 1.27)
					)
					(hide yes)
				)
			)
			(property "Datasheet" ""
				(at 0 0 0)
				(effects
					(font
						(size 1.27 1.27)
					)
					(hide yes)
				)
			)
			(property "Description" ""
				(at 0 0 0)
				(effects
					(font
						(size 1.27 1.27)
					)
					(hide yes)
				)
			)
			(symbol "GND_60_0_1"
				(polyline
					(pts
						(xy 0 0) (xy 0 -1.27) (xy 1.27 -1.27) (xy 0 -2.54) (xy -1.27 -1.27) (xy 0 -1.27)
					)
					(stroke
						(width 0)
						(type default)
					)
					(fill
						(type none)
					)
				)
			)
			(symbol "GND_60_1_1"
				(pin power_in line
					(at 0 0 270)
					(length 0)
					(hide yes)
					(name "GND"
						(effects
							(font
								(size 1.27 1.27)
							)
						)
					)
					(number "1"
						(effects
							(font
								(size 1.27 1.27)
							)
						)
					)
				)
			)
		)
	(symbol "sodimm-ddr5-tester:GND_61"
			(power)
			(pin_names
				(offset 0)
			)
			(exclude_from_sim no)
			(in_bom yes)
			(on_board yes)
			(property "Reference" "#PWR"
				(at 0 -6.35 0)
				(effects
					(font
						(size 1.27 1.27)
					)
					(hide yes)
				)
			)
			(property "Value" "GND_61"
				(at 0 -3.81 0)
				(effects
					(font
						(size 1.27 1.27)
					)
				)
			)
			(property "Footprint" ""
				(at 0 0 0)
				(effects
					(font
						(size 1.27 1.27)
					)
					(hide yes)
				)
			)
			(property "Datasheet" ""
				(at 0 0 0)
				(effects
					(font
						(size 1.27 1.27)
					)
					(hide yes)
				)
			)
			(property "Description" ""
				(at 0 0 0)
				(effects
					(font
						(size 1.27 1.27)
					)
					(hide yes)
				)
			)
			(symbol "GND_61_0_1"
				(polyline
					(pts
						(xy 0 0) (xy 0 -1.27) (xy 1.27 -1.27) (xy 0 -2.54) (xy -1.27 -1.27) (xy 0 -1.27)
					)
					(stroke
						(width 0)
						(type default)
					)
					(fill
						(type none)
					)
				)
			)
			(symbol "GND_61_1_1"
				(pin power_in line
					(at 0 0 270)
					(length 0)
					(hide yes)
					(name "GND"
						(effects
							(font
								(size 1.27 1.27)
							)
						)
					)
					(number "1"
						(effects
							(font
								(size 1.27 1.27)
							)
						)
					)
				)
			)
		)
	(symbol "sodimm-ddr5-tester:GND_62"
			(power)
			(pin_names
				(offset 0)
			)
			(exclude_from_sim no)
			(in_bom yes)
			(on_board yes)
			(property "Reference" "#PWR"
				(at 0 -6.35 0)
				(effects
					(font
						(size 1.27 1.27)
					)
					(hide yes)
				)
			)
			(property "Value" "GND_62"
				(at 0 -3.81 0)
				(effects
					(font
						(size 1.27 1.27)
					)
				)
			)
			(property "Footprint" ""
				(at 0 0 0)
				(effects
					(font
						(size 1.27 1.27)
					)
					(hide yes)
				)
			)
			(property "Datasheet" ""
				(at 0 0 0)
				(effects
					(font
						(size 1.27 1.27)
					)
					(hide yes)
				)
			)
			(property "Description" ""
				(at 0 0 0)
				(effects
					(font
						(size 1.27 1.27)
					)
					(hide yes)
				)
			)
			(symbol "GND_62_0_1"
				(polyline
					(pts
						(xy 0 0) (xy 0 -1.27) (xy 1.27 -1.27) (xy 0 -2.54) (xy -1.27 -1.27) (xy 0 -1.27)
					)
					(stroke
						(width 0)
						(type default)
					)
					(fill
						(type none)
					)
				)
			)
			(symbol "GND_62_1_1"
				(pin power_in line
					(at 0 0 270)
					(length 0)
					(hide yes)
					(name "GND"
						(effects
							(font
								(size 1.27 1.27)
							)
						)
					)
					(number "1"
						(effects
							(font
								(size 1.27 1.27)
							)
						)
					)
				)
			)
		)
	(symbol "sodimm-ddr5-tester:GND_63"
			(power)
			(pin_names
				(offset 0)
			)
			(exclude_from_sim no)
			(in_bom yes)
			(on_board yes)
			(property "Reference" "#PWR"
				(at 0 -6.35 0)
				(effects
					(font
						(size 1.27 1.27)
					)
					(hide yes)
				)
			)
			(property "Value" "GND_63"
				(at 0 -3.81 0)
				(effects
					(font
						(size 1.27 1.27)
					)
				)
			)
			(property "Footprint" ""
				(at 0 0 0)
				(effects
					(font
						(size 1.27 1.27)
					)
					(hide yes)
				)
			)
			(property "Datasheet" ""
				(at 0 0 0)
				(effects
					(font
						(size 1.27 1.27)
					)
					(hide yes)
				)
			)
			(property "Description" ""
				(at 0 0 0)
				(effects
					(font
						(size 1.27 1.27)
					)
					(hide yes)
				)
			)
			(symbol "GND_63_0_1"
				(polyline
					(pts
						(xy 0 0) (xy 0 -1.27) (xy 1.27 -1.27) (xy 0 -2.54) (xy -1.27 -1.27) (xy 0 -1.27)
					)
					(stroke
						(width 0)
						(type default)
					)
					(fill
						(type none)
					)
				)
			)
			(symbol "GND_63_1_1"
				(pin power_in line
					(at 0 0 270)
					(length 0)
					(hide yes)
					(name "GND"
						(effects
							(font
								(size 1.27 1.27)
							)
						)
					)
					(number "1"
						(effects
							(font
								(size 1.27 1.27)
							)
						)
					)
				)
			)
		)
	(symbol "sodimm-ddr5-tester:GND_64"
			(power)
			(pin_names
				(offset 0)
			)
			(exclude_from_sim no)
			(in_bom yes)
			(on_board yes)
			(property "Reference" "#PWR"
				(at 0 -6.35 0)
				(effects
					(font
						(size 1.27 1.27)
					)
					(hide yes)
				)
			)
			(property "Value" "GND_64"
				(at 0 -3.81 0)
				(effects
					(font
						(size 1.27 1.27)
					)
				)
			)
			(property "Footprint" ""
				(at 0 0 0)
				(effects
					(font
						(size 1.27 1.27)
					)
					(hide yes)
				)
			)
			(property "Datasheet" ""
				(at 0 0 0)
				(effects
					(font
						(size 1.27 1.27)
					)
					(hide yes)
				)
			)
			(property "Description" ""
				(at 0 0 0)
				(effects
					(font
						(size 1.27 1.27)
					)
					(hide yes)
				)
			)
			(symbol "GND_64_0_1"
				(polyline
					(pts
						(xy 0 0) (xy 0 -1.27) (xy 1.27 -1.27) (xy 0 -2.54) (xy -1.27 -1.27) (xy 0 -1.27)
					)
					(stroke
						(width 0)
						(type default)
					)
					(fill
						(type none)
					)
				)
			)
			(symbol "GND_64_1_1"
				(pin power_in line
					(at 0 0 270)
					(length 0)
					(hide yes)
					(name "GND"
						(effects
							(font
								(size 1.27 1.27)
							)
						)
					)
					(number "1"
						(effects
							(font
								(size 1.27 1.27)
							)
						)
					)
				)
			)
		)
	(symbol "sodimm-ddr5-tester:GND_65"
			(power)
			(pin_names
				(offset 0)
			)
			(exclude_from_sim no)
			(in_bom yes)
			(on_board yes)
			(property "Reference" "#PWR"
				(at 0 -6.35 0)
				(effects
					(font
						(size 1.27 1.27)
					)
					(hide yes)
				)
			)
			(property "Value" "GND_65"
				(at 0 -3.81 0)
				(effects
					(font
						(size 1.27 1.27)
					)
				)
			)
			(property "Footprint" ""
				(at 0 0 0)
				(effects
					(font
						(size 1.27 1.27)
					)
					(hide yes)
				)
			)
			(property "Datasheet" ""
				(at 0 0 0)
				(effects
					(font
						(size 1.27 1.27)
					)
					(hide yes)
				)
			)
			(property "Description" ""
				(at 0 0 0)
				(effects
					(font
						(size 1.27 1.27)
					)
					(hide yes)
				)
			)
			(symbol "GND_65_0_1"
				(polyline
					(pts
						(xy 0 0) (xy 0 -1.27) (xy 1.27 -1.27) (xy 0 -2.54) (xy -1.27 -1.27) (xy 0 -1.27)
					)
					(stroke
						(width 0)
						(type default)
					)
					(fill
						(type none)
					)
				)
			)
			(symbol "GND_65_1_1"
				(pin power_in line
					(at 0 0 270)
					(length 0)
					(hide yes)
					(name "GND"
						(effects
							(font
								(size 1.27 1.27)
							)
						)
					)
					(number "1"
						(effects
							(font
								(size 1.27 1.27)
							)
						)
					)
				)
			)
		)
	(symbol "sodimm-ddr5-tester:GND_66"
			(power)
			(pin_names
				(offset 0)
			)
			(exclude_from_sim no)
			(in_bom yes)
			(on_board yes)
			(property "Reference" "#PWR"
				(at 0 -6.35 0)
				(effects
					(font
						(size 1.27 1.27)
					)
					(hide yes)
				)
			)
			(property "Value" "GND_66"
				(at 0 -3.81 0)
				(effects
					(font
						(size 1.27 1.27)
					)
				)
			)
			(property "Footprint" ""
				(at 0 0 0)
				(effects
					(font
						(size 1.27 1.27)
					)
					(hide yes)
				)
			)
			(property "Datasheet" ""
				(at 0 0 0)
				(effects
					(font
						(size 1.27 1.27)
					)
					(hide yes)
				)
			)
			(property "Description" ""
				(at 0 0 0)
				(effects
					(font
						(size 1.27 1.27)
					)
					(hide yes)
				)
			)
			(symbol "GND_66_0_1"
				(polyline
					(pts
						(xy 0 0) (xy 0 -1.27) (xy 1.27 -1.27) (xy 0 -2.54) (xy -1.27 -1.27) (xy 0 -1.27)
					)
					(stroke
						(width 0)
						(type default)
					)
					(fill
						(type none)
					)
				)
			)
			(symbol "GND_66_1_1"
				(pin power_in line
					(at 0 0 270)
					(length 0)
					(hide yes)
					(name "GND"
						(effects
							(font
								(size 1.27 1.27)
							)
						)
					)
					(number "1"
						(effects
							(font
								(size 1.27 1.27)
							)
						)
					)
				)
			)
		)
	(symbol "sodimm-ddr5-tester:GND_67"
			(power)
			(pin_names
				(offset 0)
			)
			(exclude_from_sim no)
			(in_bom yes)
			(on_board yes)
			(property "Reference" "#PWR"
				(at 0 -6.35 0)
				(effects
					(font
						(size 1.27 1.27)
					)
					(hide yes)
				)
			)
			(property "Value" "GND_67"
				(at 0 -3.81 0)
				(effects
					(font
						(size 1.27 1.27)
					)
				)
			)
			(property "Footprint" ""
				(at 0 0 0)
				(effects
					(font
						(size 1.27 1.27)
					)
					(hide yes)
				)
			)
			(property "Datasheet" ""
				(at 0 0 0)
				(effects
					(font
						(size 1.27 1.27)
					)
					(hide yes)
				)
			)
			(property "Description" ""
				(at 0 0 0)
				(effects
					(font
						(size 1.27 1.27)
					)
					(hide yes)
				)
			)
			(symbol "GND_67_0_1"
				(polyline
					(pts
						(xy 0 0) (xy 0 -1.27) (xy 1.27 -1.27) (xy 0 -2.54) (xy -1.27 -1.27) (xy 0 -1.27)
					)
					(stroke
						(width 0)
						(type default)
					)
					(fill
						(type none)
					)
				)
			)
			(symbol "GND_67_1_1"
				(pin power_in line
					(at 0 0 270)
					(length 0)
					(hide yes)
					(name "GND"
						(effects
							(font
								(size 1.27 1.27)
							)
						)
					)
					(number "1"
						(effects
							(font
								(size 1.27 1.27)
							)
						)
					)
				)
			)
		)
	(symbol "sodimm-ddr5-tester:GND_68"
			(power)
			(pin_names
				(offset 0)
			)
			(exclude_from_sim no)
			(in_bom yes)
			(on_board yes)
			(property "Reference" "#PWR"
				(at 0 -6.35 0)
				(effects
					(font
						(size 1.27 1.27)
					)
					(hide yes)
				)
			)
			(property "Value" "GND_68"
				(at 0 -3.81 0)
				(effects
					(font
						(size 1.27 1.27)
					)
				)
			)
			(property "Footprint" ""
				(at 0 0 0)
				(effects
					(font
						(size 1.27 1.27)
					)
					(hide yes)
				)
			)
			(property "Datasheet" ""
				(at 0 0 0)
				(effects
					(font
						(size 1.27 1.27)
					)
					(hide yes)
				)
			)
			(property "Description" ""
				(at 0 0 0)
				(effects
					(font
						(size 1.27 1.27)
					)
					(hide yes)
				)
			)
			(symbol "GND_68_0_1"
				(polyline
					(pts
						(xy 0 0) (xy 0 -1.27) (xy 1.27 -1.27) (xy 0 -2.54) (xy -1.27 -1.27) (xy 0 -1.27)
					)
					(stroke
						(width 0)
						(type default)
					)
					(fill
						(type none)
					)
				)
			)
			(symbol "GND_68_1_1"
				(pin power_in line
					(at 0 0 270)
					(length 0)
					(hide yes)
					(name "GND"
						(effects
							(font
								(size 1.27 1.27)
							)
						)
					)
					(number "1"
						(effects
							(font
								(size 1.27 1.27)
							)
						)
					)
				)
			)
		)
	(symbol "sodimm-ddr5-tester:GND_69"
			(power)
			(pin_names
				(offset 0)
			)
			(exclude_from_sim no)
			(in_bom yes)
			(on_board yes)
			(property "Reference" "#PWR"
				(at 0 -6.35 0)
				(effects
					(font
						(size 1.27 1.27)
					)
					(hide yes)
				)
			)
			(property "Value" "GND_69"
				(at 0 -3.81 0)
				(effects
					(font
						(size 1.27 1.27)
					)
				)
			)
			(property "Footprint" ""
				(at 0 0 0)
				(effects
					(font
						(size 1.27 1.27)
					)
					(hide yes)
				)
			)
			(property "Datasheet" ""
				(at 0 0 0)
				(effects
					(font
						(size 1.27 1.27)
					)
					(hide yes)
				)
			)
			(property "Description" ""
				(at 0 0 0)
				(effects
					(font
						(size 1.27 1.27)
					)
					(hide yes)
				)
			)
			(symbol "GND_69_0_1"
				(polyline
					(pts
						(xy 0 0) (xy 0 -1.27) (xy 1.27 -1.27) (xy 0 -2.54) (xy -1.27 -1.27) (xy 0 -1.27)
					)
					(stroke
						(width 0)
						(type default)
					)
					(fill
						(type none)
					)
				)
			)
			(symbol "GND_69_1_1"
				(pin power_in line
					(at 0 0 270)
					(length 0)
					(hide yes)
					(name "GND"
						(effects
							(font
								(size 1.27 1.27)
							)
						)
					)
					(number "1"
						(effects
							(font
								(size 1.27 1.27)
							)
						)
					)
				)
			)
		)
	(symbol "sodimm-ddr5-tester:GND_70"
			(power)
			(pin_names
				(offset 0)
			)
			(exclude_from_sim no)
			(in_bom yes)
			(on_board yes)
			(property "Reference" "#PWR"
				(at 0 -6.35 0)
				(effects
					(font
						(size 1.27 1.27)
					)
					(hide yes)
				)
			)
			(property "Value" "GND_70"
				(at 0 -3.81 0)
				(effects
					(font
						(size 1.27 1.27)
					)
				)
			)
			(property "Footprint" ""
				(at 0 0 0)
				(effects
					(font
						(size 1.27 1.27)
					)
					(hide yes)
				)
			)
			(property "Datasheet" ""
				(at 0 0 0)
				(effects
					(font
						(size 1.27 1.27)
					)
					(hide yes)
				)
			)
			(property "Description" ""
				(at 0 0 0)
				(effects
					(font
						(size 1.27 1.27)
					)
					(hide yes)
				)
			)
			(symbol "GND_70_0_1"
				(polyline
					(pts
						(xy 0 0) (xy 0 -1.27) (xy 1.27 -1.27) (xy 0 -2.54) (xy -1.27 -1.27) (xy 0 -1.27)
					)
					(stroke
						(width 0)
						(type default)
					)
					(fill
						(type none)
					)
				)
			)
			(symbol "GND_70_1_1"
				(pin power_in line
					(at 0 0 270)
					(length 0)
					(hide yes)
					(name "GND"
						(effects
							(font
								(size 1.27 1.27)
							)
						)
					)
					(number "1"
						(effects
							(font
								(size 1.27 1.27)
							)
						)
					)
				)
			)
		)
	(symbol "sodimm-ddr5-tester:GND_71"
			(power)
			(pin_names
				(offset 0)
			)
			(exclude_from_sim no)
			(in_bom yes)
			(on_board yes)
			(property "Reference" "#PWR"
				(at 0 -6.35 0)
				(effects
					(font
						(size 1.27 1.27)
					)
					(hide yes)
				)
			)
			(property "Value" "GND_71"
				(at 0 -3.81 0)
				(effects
					(font
						(size 1.27 1.27)
					)
				)
			)
			(property "Footprint" ""
				(at 0 0 0)
				(effects
					(font
						(size 1.27 1.27)
					)
					(hide yes)
				)
			)
			(property "Datasheet" ""
				(at 0 0 0)
				(effects
					(font
						(size 1.27 1.27)
					)
					(hide yes)
				)
			)
			(property "Description" ""
				(at 0 0 0)
				(effects
					(font
						(size 1.27 1.27)
					)
					(hide yes)
				)
			)
			(symbol "GND_71_0_1"
				(polyline
					(pts
						(xy 0 0) (xy 0 -1.27) (xy 1.27 -1.27) (xy 0 -2.54) (xy -1.27 -1.27) (xy 0 -1.27)
					)
					(stroke
						(width 0)
						(type default)
					)
					(fill
						(type none)
					)
				)
			)
			(symbol "GND_71_1_1"
				(pin power_in line
					(at 0 0 270)
					(length 0)
					(hide yes)
					(name "GND"
						(effects
							(font
								(size 1.27 1.27)
							)
						)
					)
					(number "1"
						(effects
							(font
								(size 1.27 1.27)
							)
						)
					)
				)
			)
		)
	(symbol "sodimm-ddr5-tester:GND_72"
			(power)
			(pin_names
				(offset 0)
			)
			(exclude_from_sim no)
			(in_bom yes)
			(on_board yes)
			(property "Reference" "#PWR"
				(at 0 -6.35 0)
				(effects
					(font
						(size 1.27 1.27)
					)
					(hide yes)
				)
			)
			(property "Value" "GND_72"
				(at 0 -3.81 0)
				(effects
					(font
						(size 1.27 1.27)
					)
				)
			)
			(property "Footprint" ""
				(at 0 0 0)
				(effects
					(font
						(size 1.27 1.27)
					)
					(hide yes)
				)
			)
			(property "Datasheet" ""
				(at 0 0 0)
				(effects
					(font
						(size 1.27 1.27)
					)
					(hide yes)
				)
			)
			(property "Description" ""
				(at 0 0 0)
				(effects
					(font
						(size 1.27 1.27)
					)
					(hide yes)
				)
			)
			(symbol "GND_72_0_1"
				(polyline
					(pts
						(xy 0 0) (xy 0 -1.27) (xy 1.27 -1.27) (xy 0 -2.54) (xy -1.27 -1.27) (xy 0 -1.27)
					)
					(stroke
						(width 0)
						(type default)
					)
					(fill
						(type none)
					)
				)
			)
			(symbol "GND_72_1_1"
				(pin power_in line
					(at 0 0 270)
					(length 0)
					(hide yes)
					(name "GND"
						(effects
							(font
								(size 1.27 1.27)
							)
						)
					)
					(number "1"
						(effects
							(font
								(size 1.27 1.27)
							)
						)
					)
				)
			)
		)
	(symbol "sodimm-ddr5-tester:GND_73"
			(power)
			(pin_names
				(offset 0)
			)
			(exclude_from_sim no)
			(in_bom yes)
			(on_board yes)
			(property "Reference" "#PWR"
				(at 0 -6.35 0)
				(effects
					(font
						(size 1.27 1.27)
					)
					(hide yes)
				)
			)
			(property "Value" "GND_73"
				(at 0 -3.81 0)
				(effects
					(font
						(size 1.27 1.27)
					)
				)
			)
			(property "Footprint" ""
				(at 0 0 0)
				(effects
					(font
						(size 1.27 1.27)
					)
					(hide yes)
				)
			)
			(property "Datasheet" ""
				(at 0 0 0)
				(effects
					(font
						(size 1.27 1.27)
					)
					(hide yes)
				)
			)
			(property "Description" ""
				(at 0 0 0)
				(effects
					(font
						(size 1.27 1.27)
					)
					(hide yes)
				)
			)
			(symbol "GND_73_0_1"
				(polyline
					(pts
						(xy 0 0) (xy 0 -1.27) (xy 1.27 -1.27) (xy 0 -2.54) (xy -1.27 -1.27) (xy 0 -1.27)
					)
					(stroke
						(width 0)
						(type default)
					)
					(fill
						(type none)
					)
				)
			)
			(symbol "GND_73_1_1"
				(pin power_in line
					(at 0 0 270)
					(length 0)
					(hide yes)
					(name "GND"
						(effects
							(font
								(size 1.27 1.27)
							)
						)
					)
					(number "1"
						(effects
							(font
								(size 1.27 1.27)
							)
						)
					)
				)
			)
		)
	(symbol "sodimm-ddr5-tester:GND_74"
			(power)
			(pin_names
				(offset 0)
			)
			(exclude_from_sim no)
			(in_bom yes)
			(on_board yes)
			(property "Reference" "#PWR"
				(at 0 -6.35 0)
				(effects
					(font
						(size 1.27 1.27)
					)
					(hide yes)
				)
			)
			(property "Value" "GND_74"
				(at 0 -3.81 0)
				(effects
					(font
						(size 1.27 1.27)
					)
				)
			)
			(property "Footprint" ""
				(at 0 0 0)
				(effects
					(font
						(size 1.27 1.27)
					)
					(hide yes)
				)
			)
			(property "Datasheet" ""
				(at 0 0 0)
				(effects
					(font
						(size 1.27 1.27)
					)
					(hide yes)
				)
			)
			(property "Description" ""
				(at 0 0 0)
				(effects
					(font
						(size 1.27 1.27)
					)
					(hide yes)
				)
			)
			(symbol "GND_74_0_1"
				(polyline
					(pts
						(xy 0 0) (xy 0 -1.27) (xy 1.27 -1.27) (xy 0 -2.54) (xy -1.27 -1.27) (xy 0 -1.27)
					)
					(stroke
						(width 0)
						(type default)
					)
					(fill
						(type none)
					)
				)
			)
			(symbol "GND_74_1_1"
				(pin power_in line
					(at 0 0 270)
					(length 0)
					(hide yes)
					(name "GND"
						(effects
							(font
								(size 1.27 1.27)
							)
						)
					)
					(number "1"
						(effects
							(font
								(size 1.27 1.27)
							)
						)
					)
				)
			)
		)
	(symbol "sodimm-ddr5-tester:GND_75"
			(power)
			(pin_names
				(offset 0)
			)
			(exclude_from_sim no)
			(in_bom yes)
			(on_board yes)
			(property "Reference" "#PWR"
				(at 0 -6.35 0)
				(effects
					(font
						(size 1.27 1.27)
					)
					(hide yes)
				)
			)
			(property "Value" "GND_75"
				(at 0 -3.81 0)
				(effects
					(font
						(size 1.27 1.27)
					)
				)
			)
			(property "Footprint" ""
				(at 0 0 0)
				(effects
					(font
						(size 1.27 1.27)
					)
					(hide yes)
				)
			)
			(property "Datasheet" ""
				(at 0 0 0)
				(effects
					(font
						(size 1.27 1.27)
					)
					(hide yes)
				)
			)
			(property "Description" ""
				(at 0 0 0)
				(effects
					(font
						(size 1.27 1.27)
					)
					(hide yes)
				)
			)
			(symbol "GND_75_0_1"
				(polyline
					(pts
						(xy 0 0) (xy 0 -1.27) (xy 1.27 -1.27) (xy 0 -2.54) (xy -1.27 -1.27) (xy 0 -1.27)
					)
					(stroke
						(width 0)
						(type default)
					)
					(fill
						(type none)
					)
				)
			)
			(symbol "GND_75_1_1"
				(pin power_in line
					(at 0 0 270)
					(length 0)
					(hide yes)
					(name "GND"
						(effects
							(font
								(size 1.27 1.27)
							)
						)
					)
					(number "1"
						(effects
							(font
								(size 1.27 1.27)
							)
						)
					)
				)
			)
		)
	(symbol "sodimm-ddr5-tester:GND_76"
			(power)
			(pin_names
				(offset 0)
			)
			(exclude_from_sim no)
			(in_bom yes)
			(on_board yes)
			(property "Reference" "#PWR"
				(at 0 -6.35 0)
				(effects
					(font
						(size 1.27 1.27)
					)
					(hide yes)
				)
			)
			(property "Value" "GND_76"
				(at 0 -3.81 0)
				(effects
					(font
						(size 1.27 1.27)
					)
				)
			)
			(property "Footprint" ""
				(at 0 0 0)
				(effects
					(font
						(size 1.27 1.27)
					)
					(hide yes)
				)
			)
			(property "Datasheet" ""
				(at 0 0 0)
				(effects
					(font
						(size 1.27 1.27)
					)
					(hide yes)
				)
			)
			(property "Description" ""
				(at 0 0 0)
				(effects
					(font
						(size 1.27 1.27)
					)
					(hide yes)
				)
			)
			(symbol "GND_76_0_1"
				(polyline
					(pts
						(xy 0 0) (xy 0 -1.27) (xy 1.27 -1.27) (xy 0 -2.54) (xy -1.27 -1.27) (xy 0 -1.27)
					)
					(stroke
						(width 0)
						(type default)
					)
					(fill
						(type none)
					)
				)
			)
			(symbol "GND_76_1_1"
				(pin power_in line
					(at 0 0 270)
					(length 0)
					(hide yes)
					(name "GND"
						(effects
							(font
								(size 1.27 1.27)
							)
						)
					)
					(number "1"
						(effects
							(font
								(size 1.27 1.27)
							)
						)
					)
				)
			)
		)
	(symbol "sodimm-ddr5-tester:GND_77"
			(power)
			(pin_names
				(offset 0)
			)
			(exclude_from_sim no)
			(in_bom yes)
			(on_board yes)
			(property "Reference" "#PWR"
				(at 0 -6.35 0)
				(effects
					(font
						(size 1.27 1.27)
					)
					(hide yes)
				)
			)
			(property "Value" "GND_77"
				(at 0 -3.81 0)
				(effects
					(font
						(size 1.27 1.27)
					)
				)
			)
			(property "Footprint" ""
				(at 0 0 0)
				(effects
					(font
						(size 1.27 1.27)
					)
					(hide yes)
				)
			)
			(property "Datasheet" ""
				(at 0 0 0)
				(effects
					(font
						(size 1.27 1.27)
					)
					(hide yes)
				)
			)
			(property "Description" ""
				(at 0 0 0)
				(effects
					(font
						(size 1.27 1.27)
					)
					(hide yes)
				)
			)
			(symbol "GND_77_0_1"
				(polyline
					(pts
						(xy 0 0) (xy 0 -1.27) (xy 1.27 -1.27) (xy 0 -2.54) (xy -1.27 -1.27) (xy 0 -1.27)
					)
					(stroke
						(width 0)
						(type default)
					)
					(fill
						(type none)
					)
				)
			)
			(symbol "GND_77_1_1"
				(pin power_in line
					(at 0 0 270)
					(length 0)
					(hide yes)
					(name "GND"
						(effects
							(font
								(size 1.27 1.27)
							)
						)
					)
					(number "1"
						(effects
							(font
								(size 1.27 1.27)
							)
						)
					)
				)
			)
		)
	(symbol "sodimm-ddr5-tester:GND_78"
			(power)
			(pin_names
				(offset 0)
			)
			(exclude_from_sim no)
			(in_bom yes)
			(on_board yes)
			(property "Reference" "#PWR"
				(at 0 -6.35 0)
				(effects
					(font
						(size 1.27 1.27)
					)
					(hide yes)
				)
			)
			(property "Value" "GND_78"
				(at 0 -3.81 0)
				(effects
					(font
						(size 1.27 1.27)
					)
				)
			)
			(property "Footprint" ""
				(at 0 0 0)
				(effects
					(font
						(size 1.27 1.27)
					)
					(hide yes)
				)
			)
			(property "Datasheet" ""
				(at 0 0 0)
				(effects
					(font
						(size 1.27 1.27)
					)
					(hide yes)
				)
			)
			(property "Description" ""
				(at 0 0 0)
				(effects
					(font
						(size 1.27 1.27)
					)
					(hide yes)
				)
			)
			(symbol "GND_78_0_1"
				(polyline
					(pts
						(xy 0 0) (xy 0 -1.27) (xy 1.27 -1.27) (xy 0 -2.54) (xy -1.27 -1.27) (xy 0 -1.27)
					)
					(stroke
						(width 0)
						(type default)
					)
					(fill
						(type none)
					)
				)
			)
			(symbol "GND_78_1_1"
				(pin power_in line
					(at 0 0 270)
					(length 0)
					(hide yes)
					(name "GND"
						(effects
							(font
								(size 1.27 1.27)
							)
						)
					)
					(number "1"
						(effects
							(font
								(size 1.27 1.27)
							)
						)
					)
				)
			)
		)
	(symbol "sodimm-ddr5-tester:GND_79"
			(power)
			(pin_names
				(offset 0)
			)
			(exclude_from_sim no)
			(in_bom yes)
			(on_board yes)
			(property "Reference" "#PWR"
				(at 0 -6.35 0)
				(effects
					(font
						(size 1.27 1.27)
					)
					(hide yes)
				)
			)
			(property "Value" "GND_79"
				(at 0 -3.81 0)
				(effects
					(font
						(size 1.27 1.27)
					)
				)
			)
			(property "Footprint" ""
				(at 0 0 0)
				(effects
					(font
						(size 1.27 1.27)
					)
					(hide yes)
				)
			)
			(property "Datasheet" ""
				(at 0 0 0)
				(effects
					(font
						(size 1.27 1.27)
					)
					(hide yes)
				)
			)
			(property "Description" ""
				(at 0 0 0)
				(effects
					(font
						(size 1.27 1.27)
					)
					(hide yes)
				)
			)
			(symbol "GND_79_0_1"
				(polyline
					(pts
						(xy 0 0) (xy 0 -1.27) (xy 1.27 -1.27) (xy 0 -2.54) (xy -1.27 -1.27) (xy 0 -1.27)
					)
					(stroke
						(width 0)
						(type default)
					)
					(fill
						(type none)
					)
				)
			)
			(symbol "GND_79_1_1"
				(pin power_in line
					(at 0 0 270)
					(length 0)
					(hide yes)
					(name "GND"
						(effects
							(font
								(size 1.27 1.27)
							)
						)
					)
					(number "1"
						(effects
							(font
								(size 1.27 1.27)
							)
						)
					)
				)
			)
		)
	(symbol "sodimm-ddr5-tester:GND_81"
			(power)
			(pin_names
				(offset 0)
			)
			(exclude_from_sim no)
			(in_bom yes)
			(on_board yes)
			(property "Reference" "#PWR"
				(at 0 -6.35 0)
				(effects
					(font
						(size 1.27 1.27)
					)
					(hide yes)
				)
			)
			(property "Value" "GND_81"
				(at 0 -3.81 0)
				(effects
					(font
						(size 1.27 1.27)
					)
				)
			)
			(property "Footprint" ""
				(at 0 0 0)
				(effects
					(font
						(size 1.27 1.27)
					)
					(hide yes)
				)
			)
			(property "Datasheet" ""
				(at 0 0 0)
				(effects
					(font
						(size 1.27 1.27)
					)
					(hide yes)
				)
			)
			(property "Description" ""
				(at 0 0 0)
				(effects
					(font
						(size 1.27 1.27)
					)
					(hide yes)
				)
			)
			(symbol "GND_81_0_1"
				(polyline
					(pts
						(xy 0 0) (xy 0 -1.27) (xy 1.27 -1.27) (xy 0 -2.54) (xy -1.27 -1.27) (xy 0 -1.27)
					)
					(stroke
						(width 0)
						(type default)
					)
					(fill
						(type none)
					)
				)
			)
			(symbol "GND_81_1_1"
				(pin power_in line
					(at 0 0 270)
					(length 0)
					(hide yes)
					(name "GND"
						(effects
							(font
								(size 1.27 1.27)
							)
						)
					)
					(number "1"
						(effects
							(font
								(size 1.27 1.27)
							)
						)
					)
				)
			)
		)
	(symbol "sodimm-ddr5-tester:GND_82"
			(power)
			(pin_names
				(offset 0)
			)
			(exclude_from_sim no)
			(in_bom yes)
			(on_board yes)
			(property "Reference" "#PWR"
				(at 0 -6.35 0)
				(effects
					(font
						(size 1.27 1.27)
					)
					(hide yes)
				)
			)
			(property "Value" "GND_82"
				(at 0 -3.81 0)
				(effects
					(font
						(size 1.27 1.27)
					)
				)
			)
			(property "Footprint" ""
				(at 0 0 0)
				(effects
					(font
						(size 1.27 1.27)
					)
					(hide yes)
				)
			)
			(property "Datasheet" ""
				(at 0 0 0)
				(effects
					(font
						(size 1.27 1.27)
					)
					(hide yes)
				)
			)
			(property "Description" ""
				(at 0 0 0)
				(effects
					(font
						(size 1.27 1.27)
					)
					(hide yes)
				)
			)
			(symbol "GND_82_0_1"
				(polyline
					(pts
						(xy 0 0) (xy 0 -1.27) (xy 1.27 -1.27) (xy 0 -2.54) (xy -1.27 -1.27) (xy 0 -1.27)
					)
					(stroke
						(width 0)
						(type default)
					)
					(fill
						(type none)
					)
				)
			)
			(symbol "GND_82_1_1"
				(pin power_in line
					(at 0 0 270)
					(length 0)
					(hide yes)
					(name "GND"
						(effects
							(font
								(size 1.27 1.27)
							)
						)
					)
					(number "1"
						(effects
							(font
								(size 1.27 1.27)
							)
						)
					)
				)
			)
		)
	(symbol "sodimm-ddr5-tester:GND_83"
			(power)
			(pin_names
				(offset 0)
			)
			(exclude_from_sim no)
			(in_bom yes)
			(on_board yes)
			(property "Reference" "#PWR"
				(at 0 -6.35 0)
				(effects
					(font
						(size 1.27 1.27)
					)
					(hide yes)
				)
			)
			(property "Value" "GND_83"
				(at 0 -3.81 0)
				(effects
					(font
						(size 1.27 1.27)
					)
				)
			)
			(property "Footprint" ""
				(at 0 0 0)
				(effects
					(font
						(size 1.27 1.27)
					)
					(hide yes)
				)
			)
			(property "Datasheet" ""
				(at 0 0 0)
				(effects
					(font
						(size 1.27 1.27)
					)
					(hide yes)
				)
			)
			(property "Description" ""
				(at 0 0 0)
				(effects
					(font
						(size 1.27 1.27)
					)
					(hide yes)
				)
			)
			(symbol "GND_83_0_1"
				(polyline
					(pts
						(xy 0 0) (xy 0 -1.27) (xy 1.27 -1.27) (xy 0 -2.54) (xy -1.27 -1.27) (xy 0 -1.27)
					)
					(stroke
						(width 0)
						(type default)
					)
					(fill
						(type none)
					)
				)
			)
			(symbol "GND_83_1_1"
				(pin power_in line
					(at 0 0 270)
					(length 0)
					(hide yes)
					(name "GND"
						(effects
							(font
								(size 1.27 1.27)
							)
						)
					)
					(number "1"
						(effects
							(font
								(size 1.27 1.27)
							)
						)
					)
				)
			)
		)
	(symbol "sodimm-ddr5-tester:GND_85"
			(power)
			(pin_names
				(offset 0)
			)
			(exclude_from_sim no)
			(in_bom yes)
			(on_board yes)
			(property "Reference" "#PWR"
				(at 0 -6.35 0)
				(effects
					(font
						(size 1.27 1.27)
					)
					(hide yes)
				)
			)
			(property "Value" "GND_85"
				(at 0 -3.81 0)
				(effects
					(font
						(size 1.27 1.27)
					)
				)
			)
			(property "Footprint" ""
				(at 0 0 0)
				(effects
					(font
						(size 1.27 1.27)
					)
					(hide yes)
				)
			)
			(property "Datasheet" ""
				(at 0 0 0)
				(effects
					(font
						(size 1.27 1.27)
					)
					(hide yes)
				)
			)
			(property "Description" ""
				(at 0 0 0)
				(effects
					(font
						(size 1.27 1.27)
					)
					(hide yes)
				)
			)
			(symbol "GND_85_0_1"
				(polyline
					(pts
						(xy 0 0) (xy 0 -1.27) (xy 1.27 -1.27) (xy 0 -2.54) (xy -1.27 -1.27) (xy 0 -1.27)
					)
					(stroke
						(width 0)
						(type default)
					)
					(fill
						(type none)
					)
				)
			)
			(symbol "GND_85_1_1"
				(pin power_in line
					(at 0 0 270)
					(length 0)
					(hide yes)
					(name "GND"
						(effects
							(font
								(size 1.27 1.27)
							)
						)
					)
					(number "1"
						(effects
							(font
								(size 1.27 1.27)
							)
						)
					)
				)
			)
		)
	(symbol "sodimm-ddr5-tester:GND_86"
			(power)
			(pin_names
				(offset 0)
			)
			(exclude_from_sim no)
			(in_bom yes)
			(on_board yes)
			(property "Reference" "#PWR"
				(at 0 -6.35 0)
				(effects
					(font
						(size 1.27 1.27)
					)
					(hide yes)
				)
			)
			(property "Value" "GND_86"
				(at 0 -3.81 0)
				(effects
					(font
						(size 1.27 1.27)
					)
				)
			)
			(property "Footprint" ""
				(at 0 0 0)
				(effects
					(font
						(size 1.27 1.27)
					)
					(hide yes)
				)
			)
			(property "Datasheet" ""
				(at 0 0 0)
				(effects
					(font
						(size 1.27 1.27)
					)
					(hide yes)
				)
			)
			(property "Description" ""
				(at 0 0 0)
				(effects
					(font
						(size 1.27 1.27)
					)
					(hide yes)
				)
			)
			(symbol "GND_86_0_1"
				(polyline
					(pts
						(xy 0 0) (xy 0 -1.27) (xy 1.27 -1.27) (xy 0 -2.54) (xy -1.27 -1.27) (xy 0 -1.27)
					)
					(stroke
						(width 0)
						(type default)
					)
					(fill
						(type none)
					)
				)
			)
			(symbol "GND_86_1_1"
				(pin power_in line
					(at 0 0 270)
					(length 0)
					(hide yes)
					(name "GND"
						(effects
							(font
								(size 1.27 1.27)
							)
						)
					)
					(number "1"
						(effects
							(font
								(size 1.27 1.27)
							)
						)
					)
				)
			)
		)
	(symbol "sodimm-ddr5-tester:GND_87"
			(power)
			(pin_names
				(offset 0)
			)
			(exclude_from_sim no)
			(in_bom yes)
			(on_board yes)
			(property "Reference" "#PWR"
				(at 0 -6.35 0)
				(effects
					(font
						(size 1.27 1.27)
					)
					(hide yes)
				)
			)
			(property "Value" "GND_87"
				(at 0 -3.81 0)
				(effects
					(font
						(size 1.27 1.27)
					)
				)
			)
			(property "Footprint" ""
				(at 0 0 0)
				(effects
					(font
						(size 1.27 1.27)
					)
					(hide yes)
				)
			)
			(property "Datasheet" ""
				(at 0 0 0)
				(effects
					(font
						(size 1.27 1.27)
					)
					(hide yes)
				)
			)
			(property "Description" ""
				(at 0 0 0)
				(effects
					(font
						(size 1.27 1.27)
					)
					(hide yes)
				)
			)
			(symbol "GND_87_0_1"
				(polyline
					(pts
						(xy 0 0) (xy 0 -1.27) (xy 1.27 -1.27) (xy 0 -2.54) (xy -1.27 -1.27) (xy 0 -1.27)
					)
					(stroke
						(width 0)
						(type default)
					)
					(fill
						(type none)
					)
				)
			)
			(symbol "GND_87_1_1"
				(pin power_in line
					(at 0 0 270)
					(length 0)
					(hide yes)
					(name "GND"
						(effects
							(font
								(size 1.27 1.27)
							)
						)
					)
					(number "1"
						(effects
							(font
								(size 1.27 1.27)
							)
						)
					)
				)
			)
		)
	(symbol "sodimm-ddr5-tester:GND_88"
			(power)
			(pin_names
				(offset 0)
			)
			(exclude_from_sim no)
			(in_bom yes)
			(on_board yes)
			(property "Reference" "#PWR"
				(at 0 -6.35 0)
				(effects
					(font
						(size 1.27 1.27)
					)
					(hide yes)
				)
			)
			(property "Value" "GND_88"
				(at 0 -3.81 0)
				(effects
					(font
						(size 1.27 1.27)
					)
				)
			)
			(property "Footprint" ""
				(at 0 0 0)
				(effects
					(font
						(size 1.27 1.27)
					)
					(hide yes)
				)
			)
			(property "Datasheet" ""
				(at 0 0 0)
				(effects
					(font
						(size 1.27 1.27)
					)
					(hide yes)
				)
			)
			(property "Description" ""
				(at 0 0 0)
				(effects
					(font
						(size 1.27 1.27)
					)
					(hide yes)
				)
			)
			(symbol "GND_88_0_1"
				(polyline
					(pts
						(xy 0 0) (xy 0 -1.27) (xy 1.27 -1.27) (xy 0 -2.54) (xy -1.27 -1.27) (xy 0 -1.27)
					)
					(stroke
						(width 0)
						(type default)
					)
					(fill
						(type none)
					)
				)
			)
			(symbol "GND_88_1_1"
				(pin power_in line
					(at 0 0 270)
					(length 0)
					(hide yes)
					(name "GND"
						(effects
							(font
								(size 1.27 1.27)
							)
						)
					)
					(number "1"
						(effects
							(font
								(size 1.27 1.27)
							)
						)
					)
				)
			)
		)
	(symbol "sodimm-ddr5-tester:GND_89"
			(power)
			(pin_names
				(offset 0)
			)
			(exclude_from_sim no)
			(in_bom yes)
			(on_board yes)
			(property "Reference" "#PWR"
				(at 0 -6.35 0)
				(effects
					(font
						(size 1.27 1.27)
					)
					(hide yes)
				)
			)
			(property "Value" "GND_89"
				(at 0 -3.81 0)
				(effects
					(font
						(size 1.27 1.27)
					)
				)
			)
			(property "Footprint" ""
				(at 0 0 0)
				(effects
					(font
						(size 1.27 1.27)
					)
					(hide yes)
				)
			)
			(property "Datasheet" ""
				(at 0 0 0)
				(effects
					(font
						(size 1.27 1.27)
					)
					(hide yes)
				)
			)
			(property "Description" ""
				(at 0 0 0)
				(effects
					(font
						(size 1.27 1.27)
					)
					(hide yes)
				)
			)
			(symbol "GND_89_0_1"
				(polyline
					(pts
						(xy 0 0) (xy 0 -1.27) (xy 1.27 -1.27) (xy 0 -2.54) (xy -1.27 -1.27) (xy 0 -1.27)
					)
					(stroke
						(width 0)
						(type default)
					)
					(fill
						(type none)
					)
				)
			)
			(symbol "GND_89_1_1"
				(pin power_in line
					(at 0 0 270)
					(length 0)
					(hide yes)
					(name "GND"
						(effects
							(font
								(size 1.27 1.27)
							)
						)
					)
					(number "1"
						(effects
							(font
								(size 1.27 1.27)
							)
						)
					)
				)
			)
		)
	(symbol "sodimm-ddr5-tester:GND_90"
			(power)
			(pin_names
				(offset 0)
			)
			(exclude_from_sim no)
			(in_bom yes)
			(on_board yes)
			(property "Reference" "#PWR"
				(at 0 -6.35 0)
				(effects
					(font
						(size 1.27 1.27)
					)
					(hide yes)
				)
			)
			(property "Value" "GND_90"
				(at 0 -3.81 0)
				(effects
					(font
						(size 1.27 1.27)
					)
				)
			)
			(property "Footprint" ""
				(at 0 0 0)
				(effects
					(font
						(size 1.27 1.27)
					)
					(hide yes)
				)
			)
			(property "Datasheet" ""
				(at 0 0 0)
				(effects
					(font
						(size 1.27 1.27)
					)
					(hide yes)
				)
			)
			(property "Description" ""
				(at 0 0 0)
				(effects
					(font
						(size 1.27 1.27)
					)
					(hide yes)
				)
			)
			(symbol "GND_90_0_1"
				(polyline
					(pts
						(xy 0 0) (xy 0 -1.27) (xy 1.27 -1.27) (xy 0 -2.54) (xy -1.27 -1.27) (xy 0 -1.27)
					)
					(stroke
						(width 0)
						(type default)
					)
					(fill
						(type none)
					)
				)
			)
			(symbol "GND_90_1_1"
				(pin power_in line
					(at 0 0 270)
					(length 0)
					(hide yes)
					(name "GND"
						(effects
							(font
								(size 1.27 1.27)
							)
						)
					)
					(number "1"
						(effects
							(font
								(size 1.27 1.27)
							)
						)
					)
				)
			)
		)
	(symbol "sodimm-ddr5-tester:GND_91"
			(power)
			(pin_names
				(offset 0)
			)
			(exclude_from_sim no)
			(in_bom yes)
			(on_board yes)
			(property "Reference" "#PWR"
				(at 0 -6.35 0)
				(effects
					(font
						(size 1.27 1.27)
					)
					(hide yes)
				)
			)
			(property "Value" "GND_91"
				(at 0 -3.81 0)
				(effects
					(font
						(size 1.27 1.27)
					)
				)
			)
			(property "Footprint" ""
				(at 0 0 0)
				(effects
					(font
						(size 1.27 1.27)
					)
					(hide yes)
				)
			)
			(property "Datasheet" ""
				(at 0 0 0)
				(effects
					(font
						(size 1.27 1.27)
					)
					(hide yes)
				)
			)
			(property "Description" ""
				(at 0 0 0)
				(effects
					(font
						(size 1.27 1.27)
					)
					(hide yes)
				)
			)
			(symbol "GND_91_0_1"
				(polyline
					(pts
						(xy 0 0) (xy 0 -1.27) (xy 1.27 -1.27) (xy 0 -2.54) (xy -1.27 -1.27) (xy 0 -1.27)
					)
					(stroke
						(width 0)
						(type default)
					)
					(fill
						(type none)
					)
				)
			)
			(symbol "GND_91_1_1"
				(pin power_in line
					(at 0 0 270)
					(length 0)
					(hide yes)
					(name "GND"
						(effects
							(font
								(size 1.27 1.27)
							)
						)
					)
					(number "1"
						(effects
							(font
								(size 1.27 1.27)
							)
						)
					)
				)
			)
		)
	(symbol "sodimm-ddr5-tester:GND_92"
			(power)
			(pin_names
				(offset 0)
			)
			(exclude_from_sim no)
			(in_bom yes)
			(on_board yes)
			(property "Reference" "#PWR"
				(at 0 -6.35 0)
				(effects
					(font
						(size 1.27 1.27)
					)
					(hide yes)
				)
			)
			(property "Value" "GND_92"
				(at 0 -3.81 0)
				(effects
					(font
						(size 1.27 1.27)
					)
				)
			)
			(property "Footprint" ""
				(at 0 0 0)
				(effects
					(font
						(size 1.27 1.27)
					)
					(hide yes)
				)
			)
			(property "Datasheet" ""
				(at 0 0 0)
				(effects
					(font
						(size 1.27 1.27)
					)
					(hide yes)
				)
			)
			(property "Description" ""
				(at 0 0 0)
				(effects
					(font
						(size 1.27 1.27)
					)
					(hide yes)
				)
			)
			(symbol "GND_92_0_1"
				(polyline
					(pts
						(xy 0 0) (xy 0 -1.27) (xy 1.27 -1.27) (xy 0 -2.54) (xy -1.27 -1.27) (xy 0 -1.27)
					)
					(stroke
						(width 0)
						(type default)
					)
					(fill
						(type none)
					)
				)
			)
			(symbol "GND_92_1_1"
				(pin power_in line
					(at 0 0 270)
					(length 0)
					(hide yes)
					(name "GND"
						(effects
							(font
								(size 1.27 1.27)
							)
						)
					)
					(number "1"
						(effects
							(font
								(size 1.27 1.27)
							)
						)
					)
				)
			)
		)
	(symbol "sodimm-ddr5-tester:GND_93"
			(power)
			(pin_names
				(offset 0)
			)
			(exclude_from_sim no)
			(in_bom yes)
			(on_board yes)
			(property "Reference" "#PWR"
				(at 0 -6.35 0)
				(effects
					(font
						(size 1.27 1.27)
					)
					(hide yes)
				)
			)
			(property "Value" "GND_93"
				(at 0 -3.81 0)
				(effects
					(font
						(size 1.27 1.27)
					)
				)
			)
			(property "Footprint" ""
				(at 0 0 0)
				(effects
					(font
						(size 1.27 1.27)
					)
					(hide yes)
				)
			)
			(property "Datasheet" ""
				(at 0 0 0)
				(effects
					(font
						(size 1.27 1.27)
					)
					(hide yes)
				)
			)
			(property "Description" ""
				(at 0 0 0)
				(effects
					(font
						(size 1.27 1.27)
					)
					(hide yes)
				)
			)
			(symbol "GND_93_0_1"
				(polyline
					(pts
						(xy 0 0) (xy 0 -1.27) (xy 1.27 -1.27) (xy 0 -2.54) (xy -1.27 -1.27) (xy 0 -1.27)
					)
					(stroke
						(width 0)
						(type default)
					)
					(fill
						(type none)
					)
				)
			)
			(symbol "GND_93_1_1"
				(pin power_in line
					(at 0 0 270)
					(length 0)
					(hide yes)
					(name "GND"
						(effects
							(font
								(size 1.27 1.27)
							)
						)
					)
					(number "1"
						(effects
							(font
								(size 1.27 1.27)
							)
						)
					)
				)
			)
		)
	(symbol "sodimm-ddr5-tester:GND_94"
			(power)
			(pin_names
				(offset 0)
			)
			(exclude_from_sim no)
			(in_bom yes)
			(on_board yes)
			(property "Reference" "#PWR"
				(at 0 -6.35 0)
				(effects
					(font
						(size 1.27 1.27)
					)
					(hide yes)
				)
			)
			(property "Value" "GND_94"
				(at 0 -3.81 0)
				(effects
					(font
						(size 1.27 1.27)
					)
				)
			)
			(property "Footprint" ""
				(at 0 0 0)
				(effects
					(font
						(size 1.27 1.27)
					)
					(hide yes)
				)
			)
			(property "Datasheet" ""
				(at 0 0 0)
				(effects
					(font
						(size 1.27 1.27)
					)
					(hide yes)
				)
			)
			(property "Description" ""
				(at 0 0 0)
				(effects
					(font
						(size 1.27 1.27)
					)
					(hide yes)
				)
			)
			(symbol "GND_94_0_1"
				(polyline
					(pts
						(xy 0 0) (xy 0 -1.27) (xy 1.27 -1.27) (xy 0 -2.54) (xy -1.27 -1.27) (xy 0 -1.27)
					)
					(stroke
						(width 0)
						(type default)
					)
					(fill
						(type none)
					)
				)
			)
			(symbol "GND_94_1_1"
				(pin power_in line
					(at 0 0 270)
					(length 0)
					(hide yes)
					(name "GND"
						(effects
							(font
								(size 1.27 1.27)
							)
						)
					)
					(number "1"
						(effects
							(font
								(size 1.27 1.27)
							)
						)
					)
				)
			)
		)
	(symbol "sodimm-ddr5-tester:GND_95"
			(power)
			(pin_names
				(offset 0)
			)
			(exclude_from_sim no)
			(in_bom yes)
			(on_board yes)
			(property "Reference" "#PWR"
				(at 0 -6.35 0)
				(effects
					(font
						(size 1.27 1.27)
					)
					(hide yes)
				)
			)
			(property "Value" "GND_95"
				(at 0 -3.81 0)
				(effects
					(font
						(size 1.27 1.27)
					)
				)
			)
			(property "Footprint" ""
				(at 0 0 0)
				(effects
					(font
						(size 1.27 1.27)
					)
					(hide yes)
				)
			)
			(property "Datasheet" ""
				(at 0 0 0)
				(effects
					(font
						(size 1.27 1.27)
					)
					(hide yes)
				)
			)
			(property "Description" ""
				(at 0 0 0)
				(effects
					(font
						(size 1.27 1.27)
					)
					(hide yes)
				)
			)
			(symbol "GND_95_0_1"
				(polyline
					(pts
						(xy 0 0) (xy 0 -1.27) (xy 1.27 -1.27) (xy 0 -2.54) (xy -1.27 -1.27) (xy 0 -1.27)
					)
					(stroke
						(width 0)
						(type default)
					)
					(fill
						(type none)
					)
				)
			)
			(symbol "GND_95_1_1"
				(pin power_in line
					(at 0 0 270)
					(length 0)
					(hide yes)
					(name "GND"
						(effects
							(font
								(size 1.27 1.27)
							)
						)
					)
					(number "1"
						(effects
							(font
								(size 1.27 1.27)
							)
						)
					)
				)
			)
		)
	(symbol "sodimm-ddr5-tester:GND_96"
			(power)
			(pin_names
				(offset 0)
			)
			(exclude_from_sim no)
			(in_bom yes)
			(on_board yes)
			(property "Reference" "#PWR"
				(at 0 -6.35 0)
				(effects
					(font
						(size 1.27 1.27)
					)
					(hide yes)
				)
			)
			(property "Value" "GND_96"
				(at 0 -3.81 0)
				(effects
					(font
						(size 1.27 1.27)
					)
				)
			)
			(property "Footprint" ""
				(at 0 0 0)
				(effects
					(font
						(size 1.27 1.27)
					)
					(hide yes)
				)
			)
			(property "Datasheet" ""
				(at 0 0 0)
				(effects
					(font
						(size 1.27 1.27)
					)
					(hide yes)
				)
			)
			(property "Description" ""
				(at 0 0 0)
				(effects
					(font
						(size 1.27 1.27)
					)
					(hide yes)
				)
			)
			(symbol "GND_96_0_1"
				(polyline
					(pts
						(xy 0 0) (xy 0 -1.27) (xy 1.27 -1.27) (xy 0 -2.54) (xy -1.27 -1.27) (xy 0 -1.27)
					)
					(stroke
						(width 0)
						(type default)
					)
					(fill
						(type none)
					)
				)
			)
			(symbol "GND_96_1_1"
				(pin power_in line
					(at 0 0 270)
					(length 0)
					(hide yes)
					(name "GND"
						(effects
							(font
								(size 1.27 1.27)
							)
						)
					)
					(number "1"
						(effects
							(font
								(size 1.27 1.27)
							)
						)
					)
				)
			)
		)
	(symbol "sodimm-ddr5-tester:GND_97"
			(power)
			(pin_names
				(offset 0)
			)
			(exclude_from_sim no)
			(in_bom yes)
			(on_board yes)
			(property "Reference" "#PWR"
				(at 0 -6.35 0)
				(effects
					(font
						(size 1.27 1.27)
					)
					(hide yes)
				)
			)
			(property "Value" "GND_97"
				(at 0 -3.81 0)
				(effects
					(font
						(size 1.27 1.27)
					)
				)
			)
			(property "Footprint" ""
				(at 0 0 0)
				(effects
					(font
						(size 1.27 1.27)
					)
					(hide yes)
				)
			)
			(property "Datasheet" ""
				(at 0 0 0)
				(effects
					(font
						(size 1.27 1.27)
					)
					(hide yes)
				)
			)
			(property "Description" ""
				(at 0 0 0)
				(effects
					(font
						(size 1.27 1.27)
					)
					(hide yes)
				)
			)
			(symbol "GND_97_0_1"
				(polyline
					(pts
						(xy 0 0) (xy 0 -1.27) (xy 1.27 -1.27) (xy 0 -2.54) (xy -1.27 -1.27) (xy 0 -1.27)
					)
					(stroke
						(width 0)
						(type default)
					)
					(fill
						(type none)
					)
				)
			)
			(symbol "GND_97_1_1"
				(pin power_in line
					(at 0 0 270)
					(length 0)
					(hide yes)
					(name "GND"
						(effects
							(font
								(size 1.27 1.27)
							)
						)
					)
					(number "1"
						(effects
							(font
								(size 1.27 1.27)
							)
						)
					)
				)
			)
		)
	(symbol "sodimm-ddr5-tester:GND_98"
			(power)
			(pin_names
				(offset 0)
			)
			(exclude_from_sim no)
			(in_bom yes)
			(on_board yes)
			(property "Reference" "#PWR"
				(at 0 -6.35 0)
				(effects
					(font
						(size 1.27 1.27)
					)
					(hide yes)
				)
			)
			(property "Value" "GND_98"
				(at 0 -3.81 0)
				(effects
					(font
						(size 1.27 1.27)
					)
				)
			)
			(property "Footprint" ""
				(at 0 0 0)
				(effects
					(font
						(size 1.27 1.27)
					)
					(hide yes)
				)
			)
			(property "Datasheet" ""
				(at 0 0 0)
				(effects
					(font
						(size 1.27 1.27)
					)
					(hide yes)
				)
			)
			(property "Description" ""
				(at 0 0 0)
				(effects
					(font
						(size 1.27 1.27)
					)
					(hide yes)
				)
			)
			(symbol "GND_98_0_1"
				(polyline
					(pts
						(xy 0 0) (xy 0 -1.27) (xy 1.27 -1.27) (xy 0 -2.54) (xy -1.27 -1.27) (xy 0 -1.27)
					)
					(stroke
						(width 0)
						(type default)
					)
					(fill
						(type none)
					)
				)
			)
			(symbol "GND_98_1_1"
				(pin power_in line
					(at 0 0 270)
					(length 0)
					(hide yes)
					(name "GND"
						(effects
							(font
								(size 1.27 1.27)
							)
						)
					)
					(number "1"
						(effects
							(font
								(size 1.27 1.27)
							)
						)
					)
				)
			)
		)
	(symbol "sodimm-ddr5-tester:Net-Tie_2_10"
			(pin_numbers
				(hide yes)
			)
			(pin_names
				(hide yes)
			)
			(exclude_from_sim no)
			(in_bom yes)
			(on_board yes)
			(property "Reference" "TP"
				(at 21.59 0 0)
				(effects
					(font
						(size 1.27 1.27)
						(thickness 0.15)
					)
					(justify left bottom)
				)
			)
			(property "Value" "Net-Tie_2_10"
				(at 21.59 -2.54 0)
				(effects
					(font
						(size 1.27 1.27)
						(thickness 0.15)
					)
					(justify left bottom)
				)
			)
			(property "Footprint" "sodimm-ddr5-tester-footprints:NetTie-2_SMD_Pad0.127mm"
				(at 21.59 -5.08 0)
				(effects
					(font
						(size 1.27 1.27)
						(thickness 0.15)
					)
					(justify left bottom)
					(hide yes)
				)
			)
			(property "Datasheet" ""
				(at 21.59 -7.62 0)
				(effects
					(font
						(size 1.27 1.27)
						(thickness 0.15)
					)
					(justify left bottom)
					(hide yes)
				)
			)
			(property "Description" "Net tie, 2 pins"
				(at 0 0 0)
				(effects
					(font
						(size 1.27 1.27)
					)
					(hide yes)
				)
			)
			(property "MPN" ""
				(at 21.59 -8.89 0)
				(effects
					(font
						(size 1.27 1.27)
					)
					(justify left)
					(hide yes)
				)
			)
			(property "Manufacturer" ""
				(at 21.59 -11.43 0)
				(effects
					(font
						(size 1.27 1.27)
					)
					(justify left)
					(hide yes)
				)
			)
			(property "Author" "Antmicro"
				(at 21.59 -15.24 0)
				(effects
					(font
						(size 1.27 1.27)
						(thickness 0.15)
					)
					(justify left bottom)
					(hide yes)
				)
			)
			(property "License" "Apache-2.0"
				(at 21.59 -17.78 0)
				(effects
					(font
						(size 1.27 1.27)
						(thickness 0.15)
					)
					(justify left bottom)
					(hide yes)
				)
			)
			(property "ki_keywords" "net tie short"
				(at 0 0 0)
				(effects
					(font
						(size 1.27 1.27)
					)
					(hide yes)
				)
			)
			(property "ki_fp_filters" "Net*Tie*"
				(at 0 0 0)
				(effects
					(font
						(size 1.27 1.27)
					)
					(hide yes)
				)
			)
			(symbol "Net-Tie_2_10_1_1"
				(polyline
					(pts
						(xy 1.27 0) (xy 2.54 0)
					)
					(stroke
						(width 0.254)
						(type default)
					)
					(fill
						(type background)
					)
				)
				(pin passive line
					(at 0 0 0)
					(length 1.27)
					(name "1"
						(effects
							(font
								(size 1.27 1.27)
							)
						)
					)
					(number "1"
						(effects
							(font
								(size 1.27 1.27)
							)
						)
					)
				)
				(pin passive line
					(at 3.81 0 180)
					(length 1.27)
					(name "2"
						(effects
							(font
								(size 1.27 1.27)
							)
						)
					)
					(number "2"
						(effects
							(font
								(size 1.27 1.27)
							)
						)
					)
				)
			)
		)
	(symbol "sodimm-ddr5-tester:Net-Tie_2_11"
			(pin_numbers
				(hide yes)
			)
			(pin_names
				(hide yes)
			)
			(exclude_from_sim no)
			(in_bom yes)
			(on_board yes)
			(property "Reference" "TP"
				(at 21.59 0 0)
				(effects
					(font
						(size 1.27 1.27)
						(thickness 0.15)
					)
					(justify left bottom)
				)
			)
			(property "Value" "Net-Tie_2_11"
				(at 21.59 -2.54 0)
				(effects
					(font
						(size 1.27 1.27)
						(thickness 0.15)
					)
					(justify left bottom)
				)
			)
			(property "Footprint" "sodimm-ddr5-tester-footprints:NetTie-2_SMD_Pad0.127mm"
				(at 21.59 -5.08 0)
				(effects
					(font
						(size 1.27 1.27)
						(thickness 0.15)
					)
					(justify left bottom)
					(hide yes)
				)
			)
			(property "Datasheet" ""
				(at 21.59 -7.62 0)
				(effects
					(font
						(size 1.27 1.27)
						(thickness 0.15)
					)
					(justify left bottom)
					(hide yes)
				)
			)
			(property "Description" "Net tie, 2 pins"
				(at 0 0 0)
				(effects
					(font
						(size 1.27 1.27)
					)
					(hide yes)
				)
			)
			(property "MPN" ""
				(at 21.59 -8.89 0)
				(effects
					(font
						(size 1.27 1.27)
					)
					(justify left)
					(hide yes)
				)
			)
			(property "Manufacturer" ""
				(at 21.59 -11.43 0)
				(effects
					(font
						(size 1.27 1.27)
					)
					(justify left)
					(hide yes)
				)
			)
			(property "Author" "Antmicro"
				(at 21.59 -15.24 0)
				(effects
					(font
						(size 1.27 1.27)
						(thickness 0.15)
					)
					(justify left bottom)
					(hide yes)
				)
			)
			(property "License" "Apache-2.0"
				(at 21.59 -17.78 0)
				(effects
					(font
						(size 1.27 1.27)
						(thickness 0.15)
					)
					(justify left bottom)
					(hide yes)
				)
			)
			(property "ki_keywords" "net tie short"
				(at 0 0 0)
				(effects
					(font
						(size 1.27 1.27)
					)
					(hide yes)
				)
			)
			(property "ki_fp_filters" "Net*Tie*"
				(at 0 0 0)
				(effects
					(font
						(size 1.27 1.27)
					)
					(hide yes)
				)
			)
			(symbol "Net-Tie_2_11_1_1"
				(polyline
					(pts
						(xy 1.27 0) (xy 2.54 0)
					)
					(stroke
						(width 0.254)
						(type default)
					)
					(fill
						(type background)
					)
				)
				(pin passive line
					(at 0 0 0)
					(length 1.27)
					(name "1"
						(effects
							(font
								(size 1.27 1.27)
							)
						)
					)
					(number "1"
						(effects
							(font
								(size 1.27 1.27)
							)
						)
					)
				)
				(pin passive line
					(at 3.81 0 180)
					(length 1.27)
					(name "2"
						(effects
							(font
								(size 1.27 1.27)
							)
						)
					)
					(number "2"
						(effects
							(font
								(size 1.27 1.27)
							)
						)
					)
				)
			)
		)
	(symbol "sodimm-ddr5-tester:Net-Tie_2_12"
			(pin_numbers
				(hide yes)
			)
			(pin_names
				(hide yes)
			)
			(exclude_from_sim no)
			(in_bom yes)
			(on_board yes)
			(property "Reference" "TP"
				(at 21.59 0 0)
				(effects
					(font
						(size 1.27 1.27)
						(thickness 0.15)
					)
					(justify left bottom)
				)
			)
			(property "Value" "Net-Tie_2_12"
				(at 21.59 -2.54 0)
				(effects
					(font
						(size 1.27 1.27)
						(thickness 0.15)
					)
					(justify left bottom)
				)
			)
			(property "Footprint" "sodimm-ddr5-tester-footprints:NetTie-2_SMD_Pad0.127mm"
				(at 21.59 -5.08 0)
				(effects
					(font
						(size 1.27 1.27)
						(thickness 0.15)
					)
					(justify left bottom)
					(hide yes)
				)
			)
			(property "Datasheet" ""
				(at 21.59 -7.62 0)
				(effects
					(font
						(size 1.27 1.27)
						(thickness 0.15)
					)
					(justify left bottom)
					(hide yes)
				)
			)
			(property "Description" "Net tie, 2 pins"
				(at 0 0 0)
				(effects
					(font
						(size 1.27 1.27)
					)
					(hide yes)
				)
			)
			(property "MPN" ""
				(at 21.59 -8.89 0)
				(effects
					(font
						(size 1.27 1.27)
					)
					(justify left)
					(hide yes)
				)
			)
			(property "Manufacturer" ""
				(at 21.59 -11.43 0)
				(effects
					(font
						(size 1.27 1.27)
					)
					(justify left)
					(hide yes)
				)
			)
			(property "Author" "Antmicro"
				(at 21.59 -15.24 0)
				(effects
					(font
						(size 1.27 1.27)
						(thickness 0.15)
					)
					(justify left bottom)
					(hide yes)
				)
			)
			(property "License" "Apache-2.0"
				(at 21.59 -17.78 0)
				(effects
					(font
						(size 1.27 1.27)
						(thickness 0.15)
					)
					(justify left bottom)
					(hide yes)
				)
			)
			(property "ki_keywords" "net tie short"
				(at 0 0 0)
				(effects
					(font
						(size 1.27 1.27)
					)
					(hide yes)
				)
			)
			(property "ki_fp_filters" "Net*Tie*"
				(at 0 0 0)
				(effects
					(font
						(size 1.27 1.27)
					)
					(hide yes)
				)
			)
			(symbol "Net-Tie_2_12_1_1"
				(polyline
					(pts
						(xy 1.27 0) (xy 2.54 0)
					)
					(stroke
						(width 0.254)
						(type default)
					)
					(fill
						(type background)
					)
				)
				(pin passive line
					(at 0 0 0)
					(length 1.27)
					(name "1"
						(effects
							(font
								(size 1.27 1.27)
							)
						)
					)
					(number "1"
						(effects
							(font
								(size 1.27 1.27)
							)
						)
					)
				)
				(pin passive line
					(at 3.81 0 180)
					(length 1.27)
					(name "2"
						(effects
							(font
								(size 1.27 1.27)
							)
						)
					)
					(number "2"
						(effects
							(font
								(size 1.27 1.27)
							)
						)
					)
				)
			)
		)
	(symbol "sodimm-ddr5-tester:Net-Tie_2_13"
			(pin_numbers
				(hide yes)
			)
			(pin_names
				(hide yes)
			)
			(exclude_from_sim no)
			(in_bom yes)
			(on_board yes)
			(property "Reference" "TP"
				(at 21.59 0 0)
				(effects
					(font
						(size 1.27 1.27)
						(thickness 0.15)
					)
					(justify left bottom)
				)
			)
			(property "Value" "Net-Tie_2_13"
				(at 21.59 -2.54 0)
				(effects
					(font
						(size 1.27 1.27)
						(thickness 0.15)
					)
					(justify left bottom)
				)
			)
			(property "Footprint" "sodimm-ddr5-tester-footprints:NetTie-2_SMD_Pad0.127mm"
				(at 21.59 -5.08 0)
				(effects
					(font
						(size 1.27 1.27)
						(thickness 0.15)
					)
					(justify left bottom)
					(hide yes)
				)
			)
			(property "Datasheet" ""
				(at 21.59 -7.62 0)
				(effects
					(font
						(size 1.27 1.27)
						(thickness 0.15)
					)
					(justify left bottom)
					(hide yes)
				)
			)
			(property "Description" "Net tie, 2 pins"
				(at 0 0 0)
				(effects
					(font
						(size 1.27 1.27)
					)
					(hide yes)
				)
			)
			(property "MPN" ""
				(at 21.59 -8.89 0)
				(effects
					(font
						(size 1.27 1.27)
					)
					(justify left)
					(hide yes)
				)
			)
			(property "Manufacturer" ""
				(at 21.59 -11.43 0)
				(effects
					(font
						(size 1.27 1.27)
					)
					(justify left)
					(hide yes)
				)
			)
			(property "Author" "Antmicro"
				(at 21.59 -15.24 0)
				(effects
					(font
						(size 1.27 1.27)
						(thickness 0.15)
					)
					(justify left bottom)
					(hide yes)
				)
			)
			(property "License" "Apache-2.0"
				(at 21.59 -17.78 0)
				(effects
					(font
						(size 1.27 1.27)
						(thickness 0.15)
					)
					(justify left bottom)
					(hide yes)
				)
			)
			(property "ki_keywords" "net tie short"
				(at 0 0 0)
				(effects
					(font
						(size 1.27 1.27)
					)
					(hide yes)
				)
			)
			(property "ki_fp_filters" "Net*Tie*"
				(at 0 0 0)
				(effects
					(font
						(size 1.27 1.27)
					)
					(hide yes)
				)
			)
			(symbol "Net-Tie_2_13_1_1"
				(polyline
					(pts
						(xy 1.27 0) (xy 2.54 0)
					)
					(stroke
						(width 0.254)
						(type default)
					)
					(fill
						(type background)
					)
				)
				(pin passive line
					(at 0 0 0)
					(length 1.27)
					(name "1"
						(effects
							(font
								(size 1.27 1.27)
							)
						)
					)
					(number "1"
						(effects
							(font
								(size 1.27 1.27)
							)
						)
					)
				)
				(pin passive line
					(at 3.81 0 180)
					(length 1.27)
					(name "2"
						(effects
							(font
								(size 1.27 1.27)
							)
						)
					)
					(number "2"
						(effects
							(font
								(size 1.27 1.27)
							)
						)
					)
				)
			)
		)
	(symbol "sodimm-ddr5-tester:Net-Tie_2_14"
			(pin_numbers
				(hide yes)
			)
			(pin_names
				(hide yes)
			)
			(exclude_from_sim no)
			(in_bom yes)
			(on_board yes)
			(property "Reference" "TP"
				(at 21.59 0 0)
				(effects
					(font
						(size 1.27 1.27)
						(thickness 0.15)
					)
					(justify left bottom)
				)
			)
			(property "Value" "Net-Tie_2_14"
				(at 21.59 -2.54 0)
				(effects
					(font
						(size 1.27 1.27)
						(thickness 0.15)
					)
					(justify left bottom)
				)
			)
			(property "Footprint" "sodimm-ddr5-tester-footprints:NetTie-2_SMD_Pad0.127mm"
				(at 21.59 -5.08 0)
				(effects
					(font
						(size 1.27 1.27)
						(thickness 0.15)
					)
					(justify left bottom)
					(hide yes)
				)
			)
			(property "Datasheet" ""
				(at 21.59 -7.62 0)
				(effects
					(font
						(size 1.27 1.27)
						(thickness 0.15)
					)
					(justify left bottom)
					(hide yes)
				)
			)
			(property "Description" "Net tie, 2 pins"
				(at 0 0 0)
				(effects
					(font
						(size 1.27 1.27)
					)
					(hide yes)
				)
			)
			(property "MPN" ""
				(at 21.59 -8.89 0)
				(effects
					(font
						(size 1.27 1.27)
					)
					(justify left)
					(hide yes)
				)
			)
			(property "Manufacturer" ""
				(at 21.59 -11.43 0)
				(effects
					(font
						(size 1.27 1.27)
					)
					(justify left)
					(hide yes)
				)
			)
			(property "Author" "Antmicro"
				(at 21.59 -15.24 0)
				(effects
					(font
						(size 1.27 1.27)
						(thickness 0.15)
					)
					(justify left bottom)
					(hide yes)
				)
			)
			(property "License" "Apache-2.0"
				(at 21.59 -17.78 0)
				(effects
					(font
						(size 1.27 1.27)
						(thickness 0.15)
					)
					(justify left bottom)
					(hide yes)
				)
			)
			(property "ki_keywords" "net tie short"
				(at 0 0 0)
				(effects
					(font
						(size 1.27 1.27)
					)
					(hide yes)
				)
			)
			(property "ki_fp_filters" "Net*Tie*"
				(at 0 0 0)
				(effects
					(font
						(size 1.27 1.27)
					)
					(hide yes)
				)
			)
			(symbol "Net-Tie_2_14_1_1"
				(polyline
					(pts
						(xy 1.27 0) (xy 2.54 0)
					)
					(stroke
						(width 0.254)
						(type default)
					)
					(fill
						(type background)
					)
				)
				(pin passive line
					(at 0 0 0)
					(length 1.27)
					(name "1"
						(effects
							(font
								(size 1.27 1.27)
							)
						)
					)
					(number "1"
						(effects
							(font
								(size 1.27 1.27)
							)
						)
					)
				)
				(pin passive line
					(at 3.81 0 180)
					(length 1.27)
					(name "2"
						(effects
							(font
								(size 1.27 1.27)
							)
						)
					)
					(number "2"
						(effects
							(font
								(size 1.27 1.27)
							)
						)
					)
				)
			)
		)
	(symbol "sodimm-ddr5-tester:Net-Tie_2_15"
			(pin_numbers
				(hide yes)
			)
			(pin_names
				(hide yes)
			)
			(exclude_from_sim no)
			(in_bom yes)
			(on_board yes)
			(property "Reference" "TP"
				(at 21.59 0 0)
				(effects
					(font
						(size 1.27 1.27)
						(thickness 0.15)
					)
					(justify left bottom)
				)
			)
			(property "Value" "Net-Tie_2_15"
				(at 21.59 -2.54 0)
				(effects
					(font
						(size 1.27 1.27)
						(thickness 0.15)
					)
					(justify left bottom)
				)
			)
			(property "Footprint" "sodimm-ddr5-tester-footprints:NetTie-2_SMD_Pad0.127mm"
				(at 21.59 -5.08 0)
				(effects
					(font
						(size 1.27 1.27)
						(thickness 0.15)
					)
					(justify left bottom)
					(hide yes)
				)
			)
			(property "Datasheet" ""
				(at 21.59 -7.62 0)
				(effects
					(font
						(size 1.27 1.27)
						(thickness 0.15)
					)
					(justify left bottom)
					(hide yes)
				)
			)
			(property "Description" "Net tie, 2 pins"
				(at 0 0 0)
				(effects
					(font
						(size 1.27 1.27)
					)
					(hide yes)
				)
			)
			(property "MPN" ""
				(at 21.59 -8.89 0)
				(effects
					(font
						(size 1.27 1.27)
					)
					(justify left)
					(hide yes)
				)
			)
			(property "Manufacturer" ""
				(at 21.59 -11.43 0)
				(effects
					(font
						(size 1.27 1.27)
					)
					(justify left)
					(hide yes)
				)
			)
			(property "Author" "Antmicro"
				(at 21.59 -15.24 0)
				(effects
					(font
						(size 1.27 1.27)
						(thickness 0.15)
					)
					(justify left bottom)
					(hide yes)
				)
			)
			(property "License" "Apache-2.0"
				(at 21.59 -17.78 0)
				(effects
					(font
						(size 1.27 1.27)
						(thickness 0.15)
					)
					(justify left bottom)
					(hide yes)
				)
			)
			(property "ki_keywords" "net tie short"
				(at 0 0 0)
				(effects
					(font
						(size 1.27 1.27)
					)
					(hide yes)
				)
			)
			(property "ki_fp_filters" "Net*Tie*"
				(at 0 0 0)
				(effects
					(font
						(size 1.27 1.27)
					)
					(hide yes)
				)
			)
			(symbol "Net-Tie_2_15_1_1"
				(polyline
					(pts
						(xy 1.27 0) (xy 2.54 0)
					)
					(stroke
						(width 0.254)
						(type default)
					)
					(fill
						(type background)
					)
				)
				(pin passive line
					(at 0 0 0)
					(length 1.27)
					(name "1"
						(effects
							(font
								(size 1.27 1.27)
							)
						)
					)
					(number "1"
						(effects
							(font
								(size 1.27 1.27)
							)
						)
					)
				)
				(pin passive line
					(at 3.81 0 180)
					(length 1.27)
					(name "2"
						(effects
							(font
								(size 1.27 1.27)
							)
						)
					)
					(number "2"
						(effects
							(font
								(size 1.27 1.27)
							)
						)
					)
				)
			)
		)
	(symbol "sodimm-ddr5-tester:TP_1mm_SMD_10"
			(pin_numbers
				(hide yes)
			)
			(pin_names
				(hide yes)
			)
			(exclude_from_sim no)
			(in_bom yes)
			(on_board yes)
			(property "Reference" "TP"
				(at 15.24 -5.08 0)
				(effects
					(font
						(size 1.27 1.27)
						(thickness 0.15)
					)
					(justify left bottom)
				)
			)
			(property "Value" "TP_1mm_SMD_10"
				(at 15.24 -7.62 0)
				(effects
					(font
						(size 1.27 1.27)
						(thickness 0.15)
					)
					(justify left bottom)
					(hide yes)
				)
			)
			(property "Footprint" "sodimm-ddr5-tester-footprints:Testpoint_smd_1mm"
				(at 15.24 -10.16 0)
				(effects
					(font
						(size 1.27 1.27)
						(thickness 0.15)
					)
					(justify left bottom)
					(hide yes)
				)
			)
			(property "Datasheet" ""
				(at 15.24 -12.7 0)
				(effects
					(font
						(size 1.27 1.27)
						(thickness 0.15)
					)
					(justify left bottom)
					(hide yes)
				)
			)
			(property "Description" "Test Point 1mm"
				(at 0 0 0)
				(effects
					(font
						(size 1.27 1.27)
					)
					(hide yes)
				)
			)
			(property "MPN" ""
				(at 0 0 0)
				(effects
					(font
						(size 1.27 1.27)
					)
					(hide yes)
				)
			)
			(property "Manufacturer" ""
				(at 0 0 0)
				(effects
					(font
						(size 1.27 1.27)
					)
					(hide yes)
				)
			)
			(property "Author" "Antmicro"
				(at 15.24 -15.24 0)
				(effects
					(font
						(size 1.27 1.27)
						(thickness 0.15)
					)
					(justify left bottom)
					(hide yes)
				)
			)
			(property "License" "Apache-2.0"
				(at 15.24 -17.78 0)
				(effects
					(font
						(size 1.27 1.27)
						(thickness 0.15)
					)
					(justify left bottom)
					(hide yes)
				)
			)
			(symbol "TP_1mm_SMD_10_1_1"
				(circle
					(center 3.175 0)
					(radius 0.635)
					(stroke
						(width 0.254)
						(type default)
					)
					(fill
						(type none)
					)
				)
				(pin passive line
					(at 0 0 0)
					(length 2.54)
					(name "1"
						(effects
							(font
								(size 1.27 1.27)
							)
						)
					)
					(number "1"
						(effects
							(font
								(size 1.27 1.27)
							)
						)
					)
				)
			)
		)
	(symbol "sodimm-ddr5-tester:TP_1mm_SMD_11"
			(pin_numbers
				(hide yes)
			)
			(pin_names
				(hide yes)
			)
			(exclude_from_sim no)
			(in_bom yes)
			(on_board yes)
			(property "Reference" "TP"
				(at 15.24 -5.08 0)
				(effects
					(font
						(size 1.27 1.27)
						(thickness 0.15)
					)
					(justify left bottom)
				)
			)
			(property "Value" "TP_1mm_SMD_11"
				(at 15.24 -7.62 0)
				(effects
					(font
						(size 1.27 1.27)
						(thickness 0.15)
					)
					(justify left bottom)
					(hide yes)
				)
			)
			(property "Footprint" "sodimm-ddr5-tester-footprints:Testpoint_smd_1mm"
				(at 15.24 -10.16 0)
				(effects
					(font
						(size 1.27 1.27)
						(thickness 0.15)
					)
					(justify left bottom)
					(hide yes)
				)
			)
			(property "Datasheet" ""
				(at 15.24 -12.7 0)
				(effects
					(font
						(size 1.27 1.27)
						(thickness 0.15)
					)
					(justify left bottom)
					(hide yes)
				)
			)
			(property "Description" "Test Point 1mm"
				(at 0 0 0)
				(effects
					(font
						(size 1.27 1.27)
					)
					(hide yes)
				)
			)
			(property "MPN" ""
				(at 0 0 0)
				(effects
					(font
						(size 1.27 1.27)
					)
					(hide yes)
				)
			)
			(property "Manufacturer" ""
				(at 0 0 0)
				(effects
					(font
						(size 1.27 1.27)
					)
					(hide yes)
				)
			)
			(property "Author" "Antmicro"
				(at 15.24 -15.24 0)
				(effects
					(font
						(size 1.27 1.27)
						(thickness 0.15)
					)
					(justify left bottom)
					(hide yes)
				)
			)
			(property "License" "Apache-2.0"
				(at 15.24 -17.78 0)
				(effects
					(font
						(size 1.27 1.27)
						(thickness 0.15)
					)
					(justify left bottom)
					(hide yes)
				)
			)
			(symbol "TP_1mm_SMD_11_1_1"
				(circle
					(center 3.175 0)
					(radius 0.635)
					(stroke
						(width 0.254)
						(type default)
					)
					(fill
						(type none)
					)
				)
				(pin passive line
					(at 0 0 0)
					(length 2.54)
					(name "1"
						(effects
							(font
								(size 1.27 1.27)
							)
						)
					)
					(number "1"
						(effects
							(font
								(size 1.27 1.27)
							)
						)
					)
				)
			)
		)
	(symbol "sodimm-ddr5-tester:TP_1mm_SMD_12"
			(pin_numbers
				(hide yes)
			)
			(pin_names
				(hide yes)
			)
			(exclude_from_sim no)
			(in_bom yes)
			(on_board yes)
			(property "Reference" "TP"
				(at 15.24 -5.08 0)
				(effects
					(font
						(size 1.27 1.27)
						(thickness 0.15)
					)
					(justify left bottom)
				)
			)
			(property "Value" "TP_1mm_SMD_12"
				(at 15.24 -7.62 0)
				(effects
					(font
						(size 1.27 1.27)
						(thickness 0.15)
					)
					(justify left bottom)
					(hide yes)
				)
			)
			(property "Footprint" "sodimm-ddr5-tester-footprints:Testpoint_smd_1mm"
				(at 15.24 -10.16 0)
				(effects
					(font
						(size 1.27 1.27)
						(thickness 0.15)
					)
					(justify left bottom)
					(hide yes)
				)
			)
			(property "Datasheet" ""
				(at 15.24 -12.7 0)
				(effects
					(font
						(size 1.27 1.27)
						(thickness 0.15)
					)
					(justify left bottom)
					(hide yes)
				)
			)
			(property "Description" "Test Point 1mm"
				(at 0 0 0)
				(effects
					(font
						(size 1.27 1.27)
					)
					(hide yes)
				)
			)
			(property "MPN" ""
				(at 0 0 0)
				(effects
					(font
						(size 1.27 1.27)
					)
					(hide yes)
				)
			)
			(property "Manufacturer" ""
				(at 0 0 0)
				(effects
					(font
						(size 1.27 1.27)
					)
					(hide yes)
				)
			)
			(property "Author" "Antmicro"
				(at 15.24 -15.24 0)
				(effects
					(font
						(size 1.27 1.27)
						(thickness 0.15)
					)
					(justify left bottom)
					(hide yes)
				)
			)
			(property "License" "Apache-2.0"
				(at 15.24 -17.78 0)
				(effects
					(font
						(size 1.27 1.27)
						(thickness 0.15)
					)
					(justify left bottom)
					(hide yes)
				)
			)
			(symbol "TP_1mm_SMD_12_1_1"
				(circle
					(center 3.175 0)
					(radius 0.635)
					(stroke
						(width 0.254)
						(type default)
					)
					(fill
						(type none)
					)
				)
				(pin passive line
					(at 0 0 0)
					(length 2.54)
					(name "1"
						(effects
							(font
								(size 1.27 1.27)
							)
						)
					)
					(number "1"
						(effects
							(font
								(size 1.27 1.27)
							)
						)
					)
				)
			)
		)
	(symbol "sodimm-ddr5-tester:TP_1mm_SMD_13"
			(pin_numbers
				(hide yes)
			)
			(pin_names
				(hide yes)
			)
			(exclude_from_sim no)
			(in_bom yes)
			(on_board yes)
			(property "Reference" "TP"
				(at 15.24 -5.08 0)
				(effects
					(font
						(size 1.27 1.27)
						(thickness 0.15)
					)
					(justify left bottom)
				)
			)
			(property "Value" "TP_1mm_SMD_13"
				(at 15.24 -7.62 0)
				(effects
					(font
						(size 1.27 1.27)
						(thickness 0.15)
					)
					(justify left bottom)
					(hide yes)
				)
			)
			(property "Footprint" "sodimm-ddr5-tester-footprints:Testpoint_smd_1mm"
				(at 15.24 -10.16 0)
				(effects
					(font
						(size 1.27 1.27)
						(thickness 0.15)
					)
					(justify left bottom)
					(hide yes)
				)
			)
			(property "Datasheet" ""
				(at 15.24 -12.7 0)
				(effects
					(font
						(size 1.27 1.27)
						(thickness 0.15)
					)
					(justify left bottom)
					(hide yes)
				)
			)
			(property "Description" "Test Point 1mm"
				(at 0 0 0)
				(effects
					(font
						(size 1.27 1.27)
					)
					(hide yes)
				)
			)
			(property "MPN" ""
				(at 0 0 0)
				(effects
					(font
						(size 1.27 1.27)
					)
					(hide yes)
				)
			)
			(property "Manufacturer" ""
				(at 0 0 0)
				(effects
					(font
						(size 1.27 1.27)
					)
					(hide yes)
				)
			)
			(property "Author" "Antmicro"
				(at 15.24 -15.24 0)
				(effects
					(font
						(size 1.27 1.27)
						(thickness 0.15)
					)
					(justify left bottom)
					(hide yes)
				)
			)
			(property "License" "Apache-2.0"
				(at 15.24 -17.78 0)
				(effects
					(font
						(size 1.27 1.27)
						(thickness 0.15)
					)
					(justify left bottom)
					(hide yes)
				)
			)
			(symbol "TP_1mm_SMD_13_1_1"
				(circle
					(center 3.175 0)
					(radius 0.635)
					(stroke
						(width 0.254)
						(type default)
					)
					(fill
						(type none)
					)
				)
				(pin passive line
					(at 0 0 0)
					(length 2.54)
					(name "1"
						(effects
							(font
								(size 1.27 1.27)
							)
						)
					)
					(number "1"
						(effects
							(font
								(size 1.27 1.27)
							)
						)
					)
				)
			)
		)
	(symbol "sodimm-ddr5-tester:TP_1mm_SMD_14"
			(pin_numbers
				(hide yes)
			)
			(pin_names
				(hide yes)
			)
			(exclude_from_sim no)
			(in_bom yes)
			(on_board yes)
			(property "Reference" "TP"
				(at 15.24 -5.08 0)
				(effects
					(font
						(size 1.27 1.27)
						(thickness 0.15)
					)
					(justify left bottom)
				)
			)
			(property "Value" "TP_1mm_SMD_14"
				(at 15.24 -7.62 0)
				(effects
					(font
						(size 1.27 1.27)
						(thickness 0.15)
					)
					(justify left bottom)
					(hide yes)
				)
			)
			(property "Footprint" "sodimm-ddr5-tester-footprints:Testpoint_smd_1mm"
				(at 15.24 -10.16 0)
				(effects
					(font
						(size 1.27 1.27)
						(thickness 0.15)
					)
					(justify left bottom)
					(hide yes)
				)
			)
			(property "Datasheet" ""
				(at 15.24 -12.7 0)
				(effects
					(font
						(size 1.27 1.27)
						(thickness 0.15)
					)
					(justify left bottom)
					(hide yes)
				)
			)
			(property "Description" "Test Point 1mm"
				(at 0 0 0)
				(effects
					(font
						(size 1.27 1.27)
					)
					(hide yes)
				)
			)
			(property "MPN" ""
				(at 0 0 0)
				(effects
					(font
						(size 1.27 1.27)
					)
					(hide yes)
				)
			)
			(property "Manufacturer" ""
				(at 0 0 0)
				(effects
					(font
						(size 1.27 1.27)
					)
					(hide yes)
				)
			)
			(property "Author" "Antmicro"
				(at 15.24 -15.24 0)
				(effects
					(font
						(size 1.27 1.27)
						(thickness 0.15)
					)
					(justify left bottom)
					(hide yes)
				)
			)
			(property "License" "Apache-2.0"
				(at 15.24 -17.78 0)
				(effects
					(font
						(size 1.27 1.27)
						(thickness 0.15)
					)
					(justify left bottom)
					(hide yes)
				)
			)
			(symbol "TP_1mm_SMD_14_1_1"
				(circle
					(center 3.175 0)
					(radius 0.635)
					(stroke
						(width 0.254)
						(type default)
					)
					(fill
						(type none)
					)
				)
				(pin passive line
					(at 0 0 0)
					(length 2.54)
					(name "1"
						(effects
							(font
								(size 1.27 1.27)
							)
						)
					)
					(number "1"
						(effects
							(font
								(size 1.27 1.27)
							)
						)
					)
				)
			)
		)
)
